G04 ================== begin FILE IDENTIFICATION RECORD ==================*
G04 Layout Name:  D:/<user>/Wistron_project/16347-sc/gbr/16347-sc.brd*
G04 Film Name:    NOTICE*
G04 File Format:  Gerber RS274X*
G04 File Origin:  Cadence Allegro 16.5-S056*
G04 Origin Date:  Tue Mar 14 17:08:21 2017*
G04 *
G04 Layer:  MANUFACTURING/THERMAL*
G04 *
G04 Offset:    (0.00 0.00)*
G04 Mirror:    No*
G04 Mode:      Positive*
G04 Rotation:  0*
G04 FullContactRelief:  No*
G04 UndefLineWidth:     6.00*
G04 ================== end FILE IDENTIFICATION RECORD ====================*
%FSLAX35Y35*MOIN*%
%IR0*IPPOS*OFA0.00000B0.00000*MIA0B0*SFA1.00000B1.00000*%
%ADD10C,.004*%
%ADD11C,.006*%
%ADD12C,.0033*%
%ADD13C,.008*%
%ADD14C,.0055*%
G75*
%LPD*%
G75*
G36*
G01X301800Y213890D02*
G02X352500Y214150I25558J-40503D01*
G01X341350Y192820D01*
X312850D01*
X301800Y213890D01*
G37*
G36*
G01X298620Y274980D02*
X307300D01*
G03X341410Y274970I17058J11442D01*
G01X348960D01*
X338090Y253970D01*
X309590D01*
X298620Y274980D01*
G37*
G54D10*
G01X796594Y153868D02*
X820594D01*
G01X790009Y177889D02*
Y207889D01*
G01X770009D02*
Y217889D01*
G01X790009Y207889D02*
X770009D01*
G01Y177889D02*
X790009D01*
G01X820009Y167889D02*
X770009D01*
G01D02*
Y177889D01*
G01X790009Y257889D02*
Y287889D01*
G01Y217889D02*
Y247889D01*
G01X770009Y257889D02*
X790009D01*
G01X770009Y247889D02*
Y257889D01*
G01X790009Y247889D02*
X770009D01*
G01Y217889D02*
X790009D01*
G01X770009Y297889D02*
X810009D01*
G01X770009Y287889D02*
Y297889D01*
G01X790009Y287889D02*
X770009D01*
G01X852594Y151868D02*
Y155868D01*
G01X859454Y153868D02*
X840594D01*
G01X852594Y155868D02*
X840594Y153868D01*
G01Y141868D02*
Y161868D01*
G01Y153868D02*
X852594Y151868D01*
G01X820594Y153868D02*
X808594Y155868D01*
G01X820594Y161868D02*
Y141868D01*
G01X808594Y155868D02*
Y151868D01*
G01D02*
X820594Y153868D01*
G01X840009Y167889D02*
X890009D01*
G01X840009Y225249D02*
Y167889D01*
G01X820009Y224740D02*
Y167889D01*
G01X845009Y225249D02*
X961000D01*
G01X850009Y297889D02*
Y235249D01*
G01D02*
X840009Y225249D01*
G01X810005Y234744D02*
X810009Y234740D01*
G01Y297889D02*
Y234740D01*
G01D02*
X820009Y224740D01*
G01X850514Y319548D02*
Y299548D01*
G01Y307548D02*
X859374D01*
G01X838514Y309548D02*
Y305548D01*
G01X850514Y307548D02*
X838514Y309548D01*
G01Y305548D02*
X850514Y307548D01*
G01X890009Y297889D02*
X850009D01*
G01X810514Y319548D02*
Y299548D01*
G01X822514Y305548D02*
Y309548D01*
G01X810514Y307548D02*
X822514Y305548D01*
G01Y309548D02*
X810514Y307548D01*
G01D02*
X850514D01*
G01X890009Y207889D02*
X890000Y217800D01*
G01X890009Y167889D02*
Y177889D01*
G01X870009Y207889D02*
X890009D01*
G01X870009Y177889D02*
Y207889D01*
G01X890009Y177889D02*
X870009D01*
G01X895009Y217889D02*
X961000D01*
G01X890009Y247889D02*
Y257889D01*
G01X870009D02*
Y287889D01*
G01X890009Y257889D02*
X870009D01*
G01Y247889D02*
X890009D01*
G01X870009Y217889D02*
Y247889D01*
G01X890009Y217889D02*
X870009D01*
G01X890009Y287889D02*
Y297889D01*
G01X870009Y287889D02*
X890009D01*
G01X958000Y205889D02*
X956000Y217889D01*
X954000Y205889D01*
X958000D01*
G01X956000Y193889D02*
Y217889D01*
G01X954000Y237249D02*
X956000Y225249D01*
X958000Y237249D01*
X954000D01*
G01X956000Y249249D02*
Y225249D01*
G01X1081654Y209388D02*
X1101654D01*
G01X1081654Y219388D02*
Y209388D01*
G01X1101654Y179388D02*
X1081654D01*
G01Y169388D02*
X1121654D01*
G01X1081654Y179388D02*
Y169388D01*
G01Y249388D02*
X1101654D01*
G01X1081654Y259388D02*
Y249388D01*
G01X1101654Y259388D02*
X1081654D01*
G01X1101654Y219388D02*
X1081654D01*
G01X1131654Y299388D02*
X1081654D01*
G01Y289388D02*
X1101654D01*
G01X1081654Y299388D02*
Y289388D01*
G01X1133654Y149388D02*
Y153388D01*
G01X1121654Y151388D02*
X1133654Y149388D01*
G01Y153388D02*
X1121654Y151388D01*
G01D02*
X1161654D01*
G01X1121654Y163388D02*
Y143388D01*
G01Y169388D02*
Y232028D01*
G01X1101654Y209388D02*
Y179388D01*
G01X1131654Y242028D02*
Y299388D01*
G01X1121654Y232028D02*
X1131654Y242028D01*
G01X1101654Y289388D02*
Y259388D01*
G01Y249388D02*
Y219388D01*
G01X1131654Y327388D02*
Y307388D01*
G01X1119654Y321388D02*
Y317388D01*
G01X1131654Y319388D02*
X1119654Y321388D01*
G01Y317388D02*
X1131654Y319388D01*
G01X1107654D02*
X1131654D01*
G01X1149654Y153388D02*
Y149388D01*
G01X1161654Y151388D02*
X1149654Y153388D01*
G01Y149388D02*
X1161654Y151388D01*
G01D02*
X1170514D01*
G01X1161654Y163388D02*
Y143388D01*
G01X1201654Y209388D02*
X1181654D01*
G01Y179388D02*
X1201654D01*
G01X1181654Y209388D02*
Y179388D01*
G01X1161654Y169388D02*
Y232537D01*
G01X1201654Y169388D02*
X1161654D01*
G01X1201654Y249388D02*
X1181654D01*
G01Y259388D02*
X1201654D01*
G01X1181654Y289388D02*
Y259388D01*
G01Y219388D02*
X1201654D01*
G01X1181654Y249388D02*
Y219388D01*
G01X1161658Y232533D02*
X1161654Y232537D01*
G01X1151654Y242537D02*
Y299388D01*
G01X1161654Y232537D02*
X1151654Y242537D01*
G01X1201654Y289388D02*
X1181654D01*
G01X1151654Y307388D02*
Y327388D01*
G01Y299388D02*
X1201654D01*
G01X1163654Y317388D02*
Y321388D01*
G01X1170514Y319388D02*
X1151654D01*
G01D02*
X1163654Y317388D01*
G01Y321388D02*
X1151654Y319388D01*
G01X1201654Y219388D02*
Y209388D01*
G01Y179388D02*
Y169388D01*
G01Y259388D02*
Y249388D01*
G01Y299388D02*
Y289388D01*
G54D11*
G01X4300Y524700D02*
X4250D01*
G01X54300Y770700D02*
X54250D01*
G01X285090Y269970D02*
X280090D01*
Y243970D01*
X285090D01*
G01X283590Y340830D02*
X278590D01*
Y314830D01*
X283590D01*
G01X288350Y208820D02*
X283350D01*
Y182820D01*
X288350D01*
G01Y187820D02*
X307850D01*
X296850Y208820D01*
X288350D01*
Y213820D01*
X301850D01*
X312850Y192820D01*
X341350D01*
X352350Y213820D01*
X365850D01*
Y208820D01*
X357350D01*
X346350Y187820D01*
X365850D01*
G01X288350D02*
Y182820D01*
X365850D01*
Y187820D01*
G01X285090Y248970D02*
X304590D01*
X293590Y269970D01*
X285090D01*
Y274970D01*
X298590D01*
X309590Y253970D01*
X338090D01*
X349090Y274970D01*
X362590D01*
Y269970D01*
X354090D01*
X343090Y248970D01*
X362590D01*
G01X285090D02*
Y243970D01*
X362590D01*
Y248970D01*
G01X315090Y310830D02*
X303090Y308830D01*
X315090Y306830D01*
Y310830D01*
G01X306290Y308830D02*
X303090D01*
G01X339590D02*
X304090D01*
G01Y354830D02*
X292090Y352830D01*
X304090Y350830D01*
Y354830D01*
G01X311290Y352830D02*
X292090D01*
G01X283590Y319830D02*
Y314830D01*
X361090D01*
Y319830D01*
G01X283590D02*
X303090D01*
X292090Y340830D01*
X283590D01*
Y345830D01*
X297090D01*
X308090Y324830D01*
X336590D01*
X347590Y345830D01*
X361090D01*
Y340830D01*
X352590D01*
X341590Y319830D01*
X361090D01*
G01X357370Y214130D02*
X388140D01*
G01X365850Y208820D02*
X370850D01*
Y182820D01*
X365850D01*
G01X332370Y221310D02*
X388140D01*
G01X362590Y269970D02*
X367590D01*
Y243970D01*
X362590D01*
G01X329290Y266000D02*
X387990D01*
G01X346210Y275010D02*
X387990D01*
G01X329590Y306830D02*
X341590Y308830D01*
X329590Y310830D01*
Y306830D01*
G01X339890Y308830D02*
X341590D01*
G01X340590Y350830D02*
X352590Y352830D01*
X340590Y354830D01*
Y350830D01*
G01X334890Y352830D02*
X352590D01*
G01X361090Y340830D02*
X366090D01*
Y314830D01*
X361090D01*
G01X385140Y202130D02*
X383140Y214130D01*
X381140Y202130D01*
X385140D01*
G01X383140Y197250D02*
Y214130D01*
G01X385140Y233310D02*
X383140Y221310D01*
X381140Y233310D01*
X385140D01*
G01X383140Y237850D02*
Y221310D01*
G01X384990Y254000D02*
X382990Y266000D01*
X380990Y254000D01*
X384990D01*
G01X382990Y250500D02*
Y266000D01*
G01X384990Y287010D02*
X382990Y275010D01*
X380990Y287010D01*
X384990D01*
G01X382990Y275010D02*
Y290150D01*
G01X849500Y-12500D02*
Y59500D01*
X893500D01*
Y-12500D01*
X849500D01*
G01Y-12451D02*
X821000Y-12500D01*
G01X837503Y-14472D02*
X849500Y-12451D01*
X837497Y-10472D01*
X837503Y-14472D01*
G01X864500Y72000D02*
X849500Y69500D01*
X864500Y67000D01*
Y72000D01*
G01X893500Y69500D02*
X849500D01*
G01Y64500D02*
Y79500D01*
G01X827500Y639629D02*
X830000Y624629D01*
X832500Y639629D01*
X827500D01*
G01X830000Y661875D02*
Y624629D01*
G01X931340D02*
X820000D01*
G01X832500Y710829D02*
X830000Y725829D01*
X827500Y710829D01*
X832500D01*
G01X830000Y693125D02*
Y725829D01*
G01X846340D02*
X820000D01*
G01X878500Y67000D02*
X893500Y69500D01*
X878500Y72000D01*
Y67000D01*
G01X901475Y69500D02*
X893500D01*
G01Y64500D02*
Y79500D01*
G01X932000Y2500D02*
X934500Y-12500D01*
X937000Y2500D01*
X932000D01*
G01X934500Y11875D02*
Y-12500D01*
G01X903500D02*
X944500D01*
G01X937000Y44500D02*
X934500Y59500D01*
X932000Y44500D01*
X937000D01*
G01X934500Y43125D02*
Y59500D01*
G01X903500D02*
X944500D01*
G01X1114953Y628479D02*
X1131500Y617000D01*
X1132500D01*
G01X1119916Y626861D02*
X1114953Y628479D01*
X1118206Y624397D01*
X1119916Y626861D01*
G01X1156654Y242537D02*
X1274500D01*
G01X1206654Y249388D02*
X1274500D01*
G01X1267500Y261388D02*
X1269500Y249388D01*
X1271500Y261388D01*
X1267500D01*
G01X1269500Y277200D02*
Y249388D01*
G01X1271500Y230537D02*
X1269500Y242537D01*
X1267500Y230537D01*
X1271500D01*
G01X1269500Y218537D02*
Y242537D01*
G01X11750Y-48833D02*
X12417Y-49250D01*
X13167Y-49500D01*
X13833D01*
X14500Y-49250D01*
X15000Y-48833D01*
X15250Y-48250D01*
X15083Y-47667D01*
X14667Y-47167D01*
X13917Y-46833D01*
X12917Y-46667D01*
X12333Y-46333D01*
X12083Y-45750D01*
X12250Y-45167D01*
X12667Y-44750D01*
X13250Y-44500D01*
X13833D01*
X14417Y-44667D01*
X14917Y-45083D01*
G01X19100Y-46167D02*
Y-49500D01*
G01Y-44833D02*
X18933Y-44750D01*
Y-44583D01*
X19100Y-44500D01*
X19267Y-44583D01*
Y-44750D01*
X19100Y-44833D01*
G01X24700Y-49500D02*
Y-44500D01*
G01X28883Y-49500D02*
Y-44500D01*
G01X31550Y-46167D02*
X28883Y-48083D01*
G01X29967Y-47333D02*
X31717Y-49500D01*
G01X34650Y-48917D02*
X35067Y-49250D01*
X35650Y-49500D01*
X36150D01*
X36650Y-49333D01*
X36983Y-49083D01*
X37150Y-48750D01*
X37067Y-48250D01*
X36733Y-48000D01*
X35233Y-47500D01*
X34900Y-46917D01*
X35067Y-46500D01*
X35400Y-46250D01*
X35900Y-46167D01*
X36400Y-46250D01*
X36900Y-46500D01*
G01X42833Y-46583D02*
X42250Y-46250D01*
X41750Y-46167D01*
X41083Y-46333D01*
X40583Y-46667D01*
X40250Y-47250D01*
X40167Y-47833D01*
X40250Y-48417D01*
X40583Y-48917D01*
X41083Y-49333D01*
X41750Y-49500D01*
X42333Y-49333D01*
X42833Y-49000D01*
G01X45933Y-49500D02*
Y-46167D01*
G01Y-46833D02*
X46350Y-46500D01*
X46767Y-46250D01*
X47350Y-46167D01*
X47767Y-46250D01*
X48267Y-46500D01*
G01X51450Y-47250D02*
X54117D01*
X53867Y-46667D01*
X53450Y-46333D01*
X52867Y-46167D01*
X52283Y-46250D01*
X51783Y-46500D01*
X51450Y-47083D01*
X51283Y-47583D01*
Y-48083D01*
X51450Y-48583D01*
X51867Y-49083D01*
X52367Y-49417D01*
X52950Y-49500D01*
X53533Y-49333D01*
X54117Y-48833D01*
G01X57050Y-47250D02*
X59717D01*
X59467Y-46667D01*
X59050Y-46333D01*
X58467Y-46167D01*
X57883Y-46250D01*
X57383Y-46500D01*
X57050Y-47083D01*
X56883Y-47583D01*
Y-48083D01*
X57050Y-48583D01*
X57467Y-49083D01*
X57967Y-49417D01*
X58550Y-49500D01*
X59133Y-49333D01*
X59717Y-48833D01*
G01X62483Y-49500D02*
Y-46167D01*
G01Y-47000D02*
X62817Y-46583D01*
X63317Y-46250D01*
X63983Y-46167D01*
X64567Y-46250D01*
X65067Y-46583D01*
X65317Y-47167D01*
Y-49500D01*
G01X0Y-24500D02*
X694500D01*
G01X0Y716000D02*
Y-69500D01*
G01D02*
X694500D01*
G01X11750Y-3833D02*
X12417Y-4250D01*
X13167Y-4500D01*
X13833D01*
X14500Y-4250D01*
X15000Y-3833D01*
X15250Y-3250D01*
X15083Y-2667D01*
X14667Y-2167D01*
X13917Y-1833D01*
X12917Y-1667D01*
X12333Y-1333D01*
X12083Y-750D01*
X12250Y-167D01*
X12667Y250D01*
X13250Y500D01*
X13833D01*
X14417Y333D01*
X14917Y-83D01*
G01X19100Y-4500D02*
X18600Y-4417D01*
X18100Y-4083D01*
X17767Y-3500D01*
X17600Y-2833D01*
X17767Y-2167D01*
X18100Y-1583D01*
X18600Y-1250D01*
X19100Y-1167D01*
X19600Y-1250D01*
X20100Y-1583D01*
X20433Y-2167D01*
X20517Y-2833D01*
X20433Y-3500D01*
X20100Y-4083D01*
X19600Y-4417D01*
X19100Y-4500D01*
G01X24700D02*
Y500D01*
G01X31800D02*
Y-4500D01*
G01Y-3750D02*
X31467Y-4167D01*
X30967Y-4417D01*
X30383Y-4500D01*
X29717Y-4333D01*
X29217Y-3917D01*
X28883Y-3417D01*
X28800Y-2833D01*
X28883Y-2250D01*
X29217Y-1750D01*
X29717Y-1333D01*
X30383Y-1167D01*
X30967Y-1250D01*
X31383Y-1417D01*
X31800Y-1750D01*
G01X34650Y-2250D02*
X37317D01*
X37067Y-1667D01*
X36650Y-1333D01*
X36067Y-1167D01*
X35483Y-1250D01*
X34983Y-1500D01*
X34650Y-2083D01*
X34483Y-2583D01*
Y-3083D01*
X34650Y-3583D01*
X35067Y-4083D01*
X35567Y-4417D01*
X36150Y-4500D01*
X36733Y-4333D01*
X37317Y-3833D01*
G01X40333Y-4500D02*
Y-1167D01*
G01Y-1833D02*
X40750Y-1500D01*
X41167Y-1250D01*
X41750Y-1167D01*
X42167Y-1250D01*
X42667Y-1500D01*
G01X50200Y-4500D02*
Y-1167D01*
G01Y-2083D02*
X50450Y-1667D01*
X50867Y-1333D01*
X51450Y-1167D01*
X52033Y-1333D01*
X52450Y-1667D01*
X52700Y-2083D01*
Y-4500D01*
G01Y-2083D02*
X52950Y-1667D01*
X53367Y-1333D01*
X53950Y-1167D01*
X54533Y-1333D01*
X54950Y-1667D01*
X55200Y-2167D01*
Y-4500D01*
G01X59800D02*
Y-1167D01*
G01Y-1750D02*
X59467Y-1417D01*
X58967Y-1250D01*
X58383Y-1167D01*
X57800Y-1333D01*
X57300Y-1667D01*
X56967Y-2167D01*
X56800Y-2833D01*
X56967Y-3500D01*
X57300Y-4000D01*
X57800Y-4333D01*
X58383Y-4500D01*
X58967Y-4417D01*
X59467Y-4167D01*
X59800Y-3833D01*
G01X62650Y-3917D02*
X63067Y-4250D01*
X63650Y-4500D01*
X64150D01*
X64650Y-4333D01*
X64983Y-4083D01*
X65150Y-3750D01*
X65067Y-3250D01*
X64733Y-3000D01*
X63233Y-2500D01*
X62900Y-1917D01*
X63067Y-1500D01*
X63400Y-1250D01*
X63900Y-1167D01*
X64400Y-1250D01*
X64900Y-1500D01*
G01X68083Y-4500D02*
Y500D01*
G01X70750Y-1167D02*
X68083Y-3083D01*
G01X69167Y-2333D02*
X70917Y-4500D01*
G01X0Y19500D02*
X694500D01*
G01X15167Y64000D02*
X11833D01*
Y69000D01*
X15167D01*
G01X13833Y66583D02*
X11833D01*
G01X19100Y69000D02*
Y64000D01*
G01X17933Y67333D02*
X20267D01*
G01X26033Y66917D02*
X25450Y67250D01*
X24950Y67333D01*
X24283Y67167D01*
X23783Y66833D01*
X23450Y66250D01*
X23367Y65667D01*
X23450Y65083D01*
X23783Y64583D01*
X24283Y64167D01*
X24950Y64000D01*
X25533Y64167D01*
X26033Y64500D01*
G01X28883Y64000D02*
Y69000D01*
G01Y66583D02*
X29300Y67000D01*
X29717Y67250D01*
X30383Y67333D01*
X30883Y67250D01*
X31467Y66917D01*
X31717Y66417D01*
Y64000D01*
G01X15167Y111500D02*
X11833D01*
Y116500D01*
X15167D01*
G01X13833Y114083D02*
X11833D01*
G01X17850Y114833D02*
X20350Y111500D01*
G01Y114833D02*
X17850Y111500D01*
G01X24700Y116500D02*
Y111500D01*
G01X23533Y114833D02*
X25867D01*
G01X29050Y113750D02*
X31717D01*
X31467Y114333D01*
X31050Y114667D01*
X30467Y114833D01*
X29883Y114750D01*
X29383Y114500D01*
X29050Y113917D01*
X28883Y113417D01*
Y112917D01*
X29050Y112417D01*
X29467Y111917D01*
X29967Y111583D01*
X30550Y111500D01*
X31133Y111667D01*
X31717Y112167D01*
G01X34733Y111500D02*
Y114833D01*
G01Y114167D02*
X35150Y114500D01*
X35567Y114750D01*
X36150Y114833D01*
X36567Y114750D01*
X37067Y114500D01*
G01X40083Y111500D02*
Y114833D01*
G01Y114000D02*
X40417Y114417D01*
X40917Y114750D01*
X41583Y114833D01*
X42167Y114750D01*
X42667Y114417D01*
X42917Y113833D01*
Y111500D01*
G01X48600D02*
Y114833D01*
G01Y114250D02*
X48267Y114583D01*
X47767Y114750D01*
X47183Y114833D01*
X46600Y114667D01*
X46100Y114333D01*
X45767Y113833D01*
X45600Y113167D01*
X45767Y112500D01*
X46100Y112000D01*
X46600Y111667D01*
X47183Y111500D01*
X47767Y111583D01*
X48267Y111833D01*
X48600Y112167D01*
G01X52700Y111500D02*
Y116500D01*
G01X63900Y111500D02*
Y116500D01*
G01X71000Y111500D02*
Y114833D01*
G01Y114250D02*
X70667Y114583D01*
X70167Y114750D01*
X69583Y114833D01*
X69000Y114667D01*
X68500Y114333D01*
X68167Y113833D01*
X68000Y113167D01*
X68167Y112500D01*
X68500Y112000D01*
X69000Y111667D01*
X69583Y111500D01*
X70167Y111583D01*
X70667Y111833D01*
X71000Y112167D01*
G01X73350Y110000D02*
X73850Y109833D01*
X74517Y110000D01*
X74933Y110333D01*
X75267Y110750D01*
X75767Y112083D01*
X76850Y114833D01*
G01X74183D02*
X75767Y112083D01*
G01X79450Y113750D02*
X82117D01*
X81867Y114333D01*
X81450Y114667D01*
X80867Y114833D01*
X80283Y114750D01*
X79783Y114500D01*
X79450Y113917D01*
X79283Y113417D01*
Y112917D01*
X79450Y112417D01*
X79867Y111917D01*
X80367Y111583D01*
X80950Y111500D01*
X81533Y111667D01*
X82117Y112167D01*
G01X85133Y111500D02*
Y114833D01*
G01Y114167D02*
X85550Y114500D01*
X85967Y114750D01*
X86550Y114833D01*
X86967Y114750D01*
X87467Y114500D01*
G01X0Y105500D02*
X694500D01*
G01X15333Y146083D02*
X14833Y146333D01*
X14250Y146500D01*
X13583D01*
X12833Y146250D01*
X12250Y145833D01*
X11833Y145333D01*
X11500Y144500D01*
X11417Y143750D01*
X11583Y143000D01*
X11833Y142500D01*
X12333Y142000D01*
X12917Y141667D01*
X13500Y141500D01*
X14083D01*
X14667Y141667D01*
X15167Y141917D01*
X15583Y142250D01*
G01X19100Y141500D02*
X18600Y141583D01*
X18100Y141917D01*
X17767Y142500D01*
X17600Y143167D01*
X17767Y143833D01*
X18100Y144417D01*
X18600Y144750D01*
X19100Y144833D01*
X19600Y144750D01*
X20100Y144417D01*
X20433Y143833D01*
X20517Y143167D01*
X20433Y142500D01*
X20100Y141917D01*
X19600Y141583D01*
X19100Y141500D01*
G01X23200Y139833D02*
Y144833D01*
G01Y144083D02*
X23617Y144500D01*
X24033Y144750D01*
X24700Y144833D01*
X25283Y144750D01*
X25867Y144333D01*
X26117Y143750D01*
X26200Y143167D01*
X26117Y142583D01*
X25867Y142000D01*
X25367Y141667D01*
X24700Y141500D01*
X24117Y141583D01*
X23533Y141833D01*
X23200Y142167D01*
G01X28800Y139833D02*
Y144833D01*
G01Y144083D02*
X29217Y144500D01*
X29633Y144750D01*
X30300Y144833D01*
X30883Y144750D01*
X31467Y144333D01*
X31717Y143750D01*
X31800Y143167D01*
X31717Y142583D01*
X31467Y142000D01*
X30967Y141667D01*
X30300Y141500D01*
X29717Y141583D01*
X29133Y141833D01*
X28800Y142167D01*
G01X34650Y143750D02*
X37317D01*
X37067Y144333D01*
X36650Y144667D01*
X36067Y144833D01*
X35483Y144750D01*
X34983Y144500D01*
X34650Y143917D01*
X34483Y143417D01*
Y142917D01*
X34650Y142417D01*
X35067Y141917D01*
X35567Y141583D01*
X36150Y141500D01*
X36733Y141667D01*
X37317Y142167D01*
G01X40333Y141500D02*
Y144833D01*
G01Y144167D02*
X40750Y144500D01*
X41167Y144750D01*
X41750Y144833D01*
X42167Y144750D01*
X42667Y144500D01*
G01X51033Y141500D02*
Y146500D01*
X53033D01*
X53700Y146250D01*
X54200Y145667D01*
X54367Y145000D01*
X54200Y144333D01*
X53783Y143833D01*
X53033Y143583D01*
X51033D01*
G01X58300Y141500D02*
Y146500D01*
G01X65400Y141500D02*
Y144833D01*
G01Y144250D02*
X65067Y144583D01*
X64567Y144750D01*
X63983Y144833D01*
X63400Y144667D01*
X62900Y144333D01*
X62567Y143833D01*
X62400Y143167D01*
X62567Y142500D01*
X62900Y142000D01*
X63400Y141667D01*
X63983Y141500D01*
X64567Y141583D01*
X65067Y141833D01*
X65400Y142167D01*
G01X69500Y146500D02*
Y141500D01*
G01X68333Y144833D02*
X70667D01*
G01X75100D02*
Y141500D01*
G01Y146167D02*
X74933Y146250D01*
Y146417D01*
X75100Y146500D01*
X75267Y146417D01*
Y146250D01*
X75100Y146167D01*
G01X79283Y141500D02*
Y144833D01*
G01Y144000D02*
X79617Y144417D01*
X80117Y144750D01*
X80783Y144833D01*
X81367Y144750D01*
X81867Y144417D01*
X82117Y143833D01*
Y141500D01*
G01X85133Y140250D02*
X85717Y139917D01*
X86383Y139833D01*
X86967Y139917D01*
X87467Y140333D01*
X87800Y140917D01*
Y144833D01*
G01Y144167D02*
X87467Y144500D01*
X86967Y144750D01*
X86383Y144833D01*
X85717Y144667D01*
X85300Y144333D01*
X84967Y143750D01*
X84800Y143167D01*
X84883Y142667D01*
X85217Y142083D01*
X85717Y141667D01*
X86383Y141500D01*
X86883Y141583D01*
X87467Y141917D01*
X87800Y142250D01*
G01X0Y120500D02*
X694500D01*
G01X1500Y175500D02*
X694500D01*
G01X11667Y459000D02*
Y464000D01*
X13333D01*
X14000Y463750D01*
X14500Y463417D01*
X14917Y462917D01*
X15250Y462333D01*
X15333Y461500D01*
X15250Y460667D01*
X14917Y460083D01*
X14500Y459583D01*
X14000Y459250D01*
X13333Y459000D01*
X11667D01*
G01X17933D02*
Y462333D01*
G01Y461667D02*
X18350Y462000D01*
X18767Y462250D01*
X19350Y462333D01*
X19767Y462250D01*
X20267Y462000D01*
G01X24700Y462333D02*
Y459000D01*
G01Y463667D02*
X24533Y463750D01*
Y463917D01*
X24700Y464000D01*
X24867Y463917D01*
Y463750D01*
X24700Y463667D01*
G01X30300Y459000D02*
Y464000D01*
G01X35900Y459000D02*
Y464000D01*
G01X24960Y626740D02*
X26960D01*
G01X25960D02*
Y621740D01*
G01X24960D02*
X26960D01*
G01X30143D02*
Y625073D01*
G01Y624240D02*
X30477Y624657D01*
X30977Y624990D01*
X31643Y625073D01*
X32227Y624990D01*
X32727Y624657D01*
X32977Y624073D01*
Y621740D01*
G01X35743D02*
Y625073D01*
G01Y624240D02*
X36077Y624657D01*
X36577Y624990D01*
X37243Y625073D01*
X37827Y624990D01*
X38327Y624657D01*
X38577Y624073D01*
Y621740D01*
G01X41510Y623990D02*
X44177D01*
X43927Y624573D01*
X43510Y624907D01*
X42927Y625073D01*
X42343Y624990D01*
X41843Y624740D01*
X41510Y624157D01*
X41343Y623657D01*
Y623157D01*
X41510Y622657D01*
X41927Y622157D01*
X42427Y621823D01*
X43010Y621740D01*
X43593Y621907D01*
X44177Y622407D01*
G01X47193Y621740D02*
Y625073D01*
G01Y624407D02*
X47610Y624740D01*
X48027Y624990D01*
X48610Y625073D01*
X49027Y624990D01*
X49527Y624740D01*
G01X59560Y621740D02*
Y626740D01*
G01X66660Y621740D02*
Y625073D01*
G01Y624490D02*
X66327Y624823D01*
X65827Y624990D01*
X65243Y625073D01*
X64660Y624907D01*
X64160Y624573D01*
X63827Y624073D01*
X63660Y623407D01*
X63827Y622740D01*
X64160Y622240D01*
X64660Y621907D01*
X65243Y621740D01*
X65827Y621823D01*
X66327Y622073D01*
X66660Y622407D01*
G01X69010Y620240D02*
X69510Y620073D01*
X70177Y620240D01*
X70593Y620573D01*
X70927Y620990D01*
X71427Y622323D01*
X72510Y625073D01*
G01X69843D02*
X71427Y622323D01*
G01X75110Y623990D02*
X77777D01*
X77527Y624573D01*
X77110Y624907D01*
X76527Y625073D01*
X75943Y624990D01*
X75443Y624740D01*
X75110Y624157D01*
X74943Y623657D01*
Y623157D01*
X75110Y622657D01*
X75527Y622157D01*
X76027Y621823D01*
X76610Y621740D01*
X77193Y621907D01*
X77777Y622407D01*
G01X80793Y621740D02*
Y625073D01*
G01Y624407D02*
X81210Y624740D01*
X81627Y624990D01*
X82210Y625073D01*
X82627Y624990D01*
X83127Y624740D01*
G01X0Y599000D02*
X694500D01*
G01X9917Y693667D02*
X10417Y694167D01*
X11000Y694417D01*
X11667Y694500D01*
X12500Y694333D01*
X13083Y693917D01*
X13250Y693417D01*
X13167Y692917D01*
X12833Y692500D01*
X11167Y691667D01*
X10417Y691083D01*
X9917Y690250D01*
X9750Y689500D01*
X13250D01*
G01X17100Y689333D02*
X16933Y689417D01*
Y689583D01*
X17100Y689667D01*
X17267Y689583D01*
Y689417D01*
X17100Y689333D01*
G01X22700Y694500D02*
Y689500D01*
G01X20783Y694500D02*
X24617D01*
G01X28300Y689500D02*
X27800Y689583D01*
X27300Y689917D01*
X26967Y690500D01*
X26800Y691167D01*
X26967Y691833D01*
X27300Y692417D01*
X27800Y692750D01*
X28300Y692833D01*
X28800Y692750D01*
X29300Y692417D01*
X29633Y691833D01*
X29717Y691167D01*
X29633Y690500D01*
X29300Y689917D01*
X28800Y689583D01*
X28300Y689500D01*
G01X33900D02*
Y694500D01*
G01X38250Y691750D02*
X40917D01*
X40667Y692333D01*
X40250Y692667D01*
X39667Y692833D01*
X39083Y692750D01*
X38583Y692500D01*
X38250Y691917D01*
X38083Y691417D01*
Y690917D01*
X38250Y690417D01*
X38667Y689917D01*
X39167Y689583D01*
X39750Y689500D01*
X40333Y689667D01*
X40917Y690167D01*
G01X43933Y689500D02*
Y692833D01*
G01Y692167D02*
X44350Y692500D01*
X44767Y692750D01*
X45350Y692833D01*
X45767Y692750D01*
X46267Y692500D01*
G01X52200Y689500D02*
Y692833D01*
G01Y692250D02*
X51867Y692583D01*
X51367Y692750D01*
X50783Y692833D01*
X50200Y692667D01*
X49700Y692333D01*
X49367Y691833D01*
X49200Y691167D01*
X49367Y690500D01*
X49700Y690000D01*
X50200Y689667D01*
X50783Y689500D01*
X51367Y689583D01*
X51867Y689833D01*
X52200Y690167D01*
G01X54883Y689500D02*
Y692833D01*
G01Y692000D02*
X55217Y692417D01*
X55717Y692750D01*
X56383Y692833D01*
X56967Y692750D01*
X57467Y692417D01*
X57717Y691833D01*
Y689500D01*
G01X63233Y692417D02*
X62650Y692750D01*
X62150Y692833D01*
X61483Y692667D01*
X60983Y692333D01*
X60650Y691750D01*
X60567Y691167D01*
X60650Y690583D01*
X60983Y690083D01*
X61483Y689667D01*
X62150Y689500D01*
X62733Y689667D01*
X63233Y690000D01*
G01X66250Y691750D02*
X68917D01*
X68667Y692333D01*
X68250Y692667D01*
X67667Y692833D01*
X67083Y692750D01*
X66583Y692500D01*
X66250Y691917D01*
X66083Y691417D01*
Y690917D01*
X66250Y690417D01*
X66667Y689917D01*
X67167Y689583D01*
X67750Y689500D01*
X68333Y689667D01*
X68917Y690167D01*
G01X78700Y694500D02*
Y689500D01*
G01X77533Y692833D02*
X79867D01*
G01X85800Y689500D02*
Y692833D01*
G01Y692250D02*
X85467Y692583D01*
X84967Y692750D01*
X84383Y692833D01*
X83800Y692667D01*
X83300Y692333D01*
X82967Y691833D01*
X82800Y691167D01*
X82967Y690500D01*
X83300Y690000D01*
X83800Y689667D01*
X84383Y689500D01*
X84967Y689583D01*
X85467Y689833D01*
X85800Y690167D01*
G01X88400Y689500D02*
Y694500D01*
G01Y692000D02*
X88817Y692500D01*
X89317Y692750D01*
X89817Y692833D01*
X90567Y692667D01*
X91067Y692333D01*
X91400Y691750D01*
Y691083D01*
X91233Y690417D01*
X90900Y689917D01*
X90317Y689583D01*
X89817Y689500D01*
X89317Y689583D01*
X88817Y689833D01*
X88400Y690250D01*
G01X95500Y689500D02*
Y694500D01*
G01X99850Y691750D02*
X102517D01*
X102267Y692333D01*
X101850Y692667D01*
X101267Y692833D01*
X100683Y692750D01*
X100183Y692500D01*
X99850Y691917D01*
X99683Y691417D01*
Y690917D01*
X99850Y690417D01*
X100267Y689917D01*
X100767Y689583D01*
X101350Y689500D01*
X101933Y689667D01*
X102517Y690167D01*
G01X106700Y689333D02*
X106533Y689417D01*
Y689583D01*
X106700Y689667D01*
X106867Y689583D01*
Y689417D01*
X106700Y689333D01*
G01Y691583D02*
X106533Y691667D01*
Y691833D01*
X106700Y691917D01*
X106867Y691833D01*
Y691667D01*
X106700Y691583D01*
G01X34000Y663333D02*
Y668333D01*
G01Y667583D02*
X34417Y668000D01*
X34833Y668250D01*
X35500Y668333D01*
X36083Y668250D01*
X36667Y667833D01*
X36917Y667250D01*
X37000Y666667D01*
X36917Y666083D01*
X36667Y665500D01*
X36167Y665167D01*
X35500Y665000D01*
X34917Y665083D01*
X34333Y665333D01*
X34000Y665667D01*
G01X39933Y665000D02*
Y668333D01*
G01Y667667D02*
X40350Y668000D01*
X40767Y668250D01*
X41350Y668333D01*
X41767Y668250D01*
X42267Y668000D01*
G01X46700Y665000D02*
X46200Y665083D01*
X45700Y665417D01*
X45367Y666000D01*
X45200Y666667D01*
X45367Y667333D01*
X45700Y667917D01*
X46200Y668250D01*
X46700Y668333D01*
X47200Y668250D01*
X47700Y667917D01*
X48033Y667333D01*
X48117Y666667D01*
X48033Y666000D01*
X47700Y665417D01*
X47200Y665083D01*
X46700Y665000D01*
G01X53633Y667917D02*
X53050Y668250D01*
X52550Y668333D01*
X51883Y668167D01*
X51383Y667833D01*
X51050Y667250D01*
X50967Y666667D01*
X51050Y666083D01*
X51383Y665583D01*
X51883Y665167D01*
X52550Y665000D01*
X53133Y665167D01*
X53633Y665500D01*
G01X56650Y667250D02*
X59317D01*
X59067Y667833D01*
X58650Y668167D01*
X58067Y668333D01*
X57483Y668250D01*
X56983Y668000D01*
X56650Y667417D01*
X56483Y666917D01*
Y666417D01*
X56650Y665917D01*
X57067Y665417D01*
X57567Y665083D01*
X58150Y665000D01*
X58733Y665167D01*
X59317Y665667D01*
G01X62250Y665583D02*
X62667Y665250D01*
X63250Y665000D01*
X63750D01*
X64250Y665167D01*
X64583Y665417D01*
X64750Y665750D01*
X64667Y666250D01*
X64333Y666500D01*
X62833Y667000D01*
X62500Y667583D01*
X62667Y668000D01*
X63000Y668250D01*
X63500Y668333D01*
X64000Y668250D01*
X64500Y668000D01*
G01X67850Y665583D02*
X68267Y665250D01*
X68850Y665000D01*
X69350D01*
X69850Y665167D01*
X70183Y665417D01*
X70350Y665750D01*
X70267Y666250D01*
X69933Y666500D01*
X68433Y667000D01*
X68100Y667583D01*
X68267Y668000D01*
X68600Y668250D01*
X69100Y668333D01*
X69600Y668250D01*
X70100Y668000D01*
G01X0Y679000D02*
X694500D01*
G01X-1000Y654000D02*
X694500D01*
G01X0Y850500D02*
Y709000D01*
X694500D01*
Y850500D01*
G01X7000Y832500D02*
Y837500D01*
X6000Y836500D01*
G01Y832500D02*
X8000D01*
G01X12600Y832333D02*
X12433Y832417D01*
Y832583D01*
X12600Y832667D01*
X12767Y832583D01*
Y832417D01*
X12600Y832333D01*
G01X16450Y833167D02*
X17117Y832750D01*
X17867Y832500D01*
X18533D01*
X19200Y832750D01*
X19700Y833167D01*
X19950Y833750D01*
X19783Y834333D01*
X19367Y834833D01*
X18617Y835167D01*
X17617Y835333D01*
X17033Y835667D01*
X16783Y836250D01*
X16950Y836833D01*
X17367Y837250D01*
X17950Y837500D01*
X18533D01*
X19117Y837333D01*
X19617Y836917D01*
G01X22300Y830833D02*
Y835833D01*
G01Y835083D02*
X22717Y835500D01*
X23133Y835750D01*
X23800Y835833D01*
X24383Y835750D01*
X24967Y835333D01*
X25217Y834750D01*
X25300Y834167D01*
X25217Y833583D01*
X24967Y833000D01*
X24467Y832667D01*
X23800Y832500D01*
X23217Y832583D01*
X22633Y832833D01*
X22300Y833167D01*
G01X28150Y834750D02*
X30817D01*
X30567Y835333D01*
X30150Y835667D01*
X29567Y835833D01*
X28983Y835750D01*
X28483Y835500D01*
X28150Y834917D01*
X27983Y834417D01*
Y833917D01*
X28150Y833417D01*
X28567Y832917D01*
X29067Y832583D01*
X29650Y832500D01*
X30233Y832667D01*
X30817Y833167D01*
G01X36333Y835417D02*
X35750Y835750D01*
X35250Y835833D01*
X34583Y835667D01*
X34083Y835333D01*
X33750Y834750D01*
X33667Y834167D01*
X33750Y833583D01*
X34083Y833083D01*
X34583Y832667D01*
X35250Y832500D01*
X35833Y832667D01*
X36333Y833000D01*
G01X40600Y835833D02*
Y832500D01*
G01Y837167D02*
X40433Y837250D01*
Y837417D01*
X40600Y837500D01*
X40767Y837417D01*
Y837250D01*
X40600Y837167D01*
G01X45700Y832500D02*
Y836750D01*
X45867Y837167D01*
X46200Y837417D01*
X46700Y837500D01*
X47200Y837333D01*
X47450Y836917D01*
G01X46450Y835500D02*
X44783D01*
G01X51800Y835833D02*
Y832500D01*
G01Y837167D02*
X51633Y837250D01*
Y837417D01*
X51800Y837500D01*
X51967Y837417D01*
Y837250D01*
X51800Y837167D01*
G01X58733Y835417D02*
X58150Y835750D01*
X57650Y835833D01*
X56983Y835667D01*
X56483Y835333D01*
X56150Y834750D01*
X56067Y834167D01*
X56150Y833583D01*
X56483Y833083D01*
X56983Y832667D01*
X57650Y832500D01*
X58233Y832667D01*
X58733Y833000D01*
G01X64500Y832500D02*
Y835833D01*
G01Y835250D02*
X64167Y835583D01*
X63667Y835750D01*
X63083Y835833D01*
X62500Y835667D01*
X62000Y835333D01*
X61667Y834833D01*
X61500Y834167D01*
X61667Y833500D01*
X62000Y833000D01*
X62500Y832667D01*
X63083Y832500D01*
X63667Y832583D01*
X64167Y832833D01*
X64500Y833167D01*
G01X68600Y837500D02*
Y832500D01*
G01X67433Y835833D02*
X69767D01*
G01X74200D02*
Y832500D01*
G01Y837167D02*
X74033Y837250D01*
Y837417D01*
X74200Y837500D01*
X74367Y837417D01*
Y837250D01*
X74200Y837167D01*
G01X79800Y832500D02*
X79300Y832583D01*
X78800Y832917D01*
X78467Y833500D01*
X78300Y834167D01*
X78467Y834833D01*
X78800Y835417D01*
X79300Y835750D01*
X79800Y835833D01*
X80300Y835750D01*
X80800Y835417D01*
X81133Y834833D01*
X81217Y834167D01*
X81133Y833500D01*
X80800Y832917D01*
X80300Y832583D01*
X79800Y832500D01*
G01X83983D02*
Y835833D01*
G01Y835000D02*
X84317Y835417D01*
X84817Y835750D01*
X85483Y835833D01*
X86067Y835750D01*
X86567Y835417D01*
X86817Y834833D01*
Y832500D01*
G01X98100Y837500D02*
Y832500D01*
G01Y833250D02*
X97767Y832833D01*
X97267Y832583D01*
X96683Y832500D01*
X96017Y832667D01*
X95517Y833083D01*
X95183Y833583D01*
X95100Y834167D01*
X95183Y834750D01*
X95517Y835250D01*
X96017Y835667D01*
X96683Y835833D01*
X97267Y835750D01*
X97683Y835583D01*
X98100Y835250D01*
G01X102200Y832500D02*
X101700Y832583D01*
X101200Y832917D01*
X100867Y833500D01*
X100700Y834167D01*
X100867Y834833D01*
X101200Y835417D01*
X101700Y835750D01*
X102200Y835833D01*
X102700Y835750D01*
X103200Y835417D01*
X103533Y834833D01*
X103617Y834167D01*
X103533Y833500D01*
X103200Y832917D01*
X102700Y832583D01*
X102200Y832500D01*
G01X109133Y835417D02*
X108550Y835750D01*
X108050Y835833D01*
X107383Y835667D01*
X106883Y835333D01*
X106550Y834750D01*
X106467Y834167D01*
X106550Y833583D01*
X106883Y833083D01*
X107383Y832667D01*
X108050Y832500D01*
X108633Y832667D01*
X109133Y833000D01*
G01X111983Y835833D02*
Y833500D01*
X112317Y832917D01*
X112817Y832583D01*
X113400Y832500D01*
X113983Y832583D01*
X114483Y832917D01*
X114817Y833500D01*
G01Y832500D02*
Y835833D01*
G01X116500Y832500D02*
Y835833D01*
G01Y834917D02*
X116750Y835333D01*
X117167Y835667D01*
X117750Y835833D01*
X118333Y835667D01*
X118750Y835333D01*
X119000Y834917D01*
Y832500D01*
G01Y834917D02*
X119250Y835333D01*
X119667Y835667D01*
X120250Y835833D01*
X120833Y835667D01*
X121250Y835333D01*
X121500Y834833D01*
Y832500D01*
G01X123350Y834750D02*
X126017D01*
X125767Y835333D01*
X125350Y835667D01*
X124767Y835833D01*
X124183Y835750D01*
X123683Y835500D01*
X123350Y834917D01*
X123183Y834417D01*
Y833917D01*
X123350Y833417D01*
X123767Y832917D01*
X124267Y832583D01*
X124850Y832500D01*
X125433Y832667D01*
X126017Y833167D01*
G01X128783Y832500D02*
Y835833D01*
G01Y835000D02*
X129117Y835417D01*
X129617Y835750D01*
X130283Y835833D01*
X130867Y835750D01*
X131367Y835417D01*
X131617Y834833D01*
Y832500D01*
G01X135800Y837500D02*
Y832500D01*
G01X134633Y835833D02*
X136967D01*
G01X141400Y832333D02*
X141233Y832417D01*
Y832583D01*
X141400Y832667D01*
X141567Y832583D01*
Y832417D01*
X141400Y832333D01*
G01Y834583D02*
X141233Y834667D01*
Y834833D01*
X141400Y834917D01*
X141567Y834833D01*
Y834667D01*
X141400Y834583D01*
G01X0Y820500D02*
X694500D01*
G01X0Y850500D02*
X694500D01*
G01X67000Y725433D02*
X66833Y725517D01*
Y725683D01*
X67000Y725767D01*
X67167Y725683D01*
Y725517D01*
X67000Y725433D01*
G01Y734433D02*
X66833Y734517D01*
Y734683D01*
X67000Y734767D01*
X67167Y734683D01*
Y734517D01*
X67000Y734433D01*
G01X71000Y729600D02*
X73000D01*
G01X72000D02*
Y724600D01*
G01X71000D02*
X73000D01*
G01X75933D02*
Y729600D01*
X77933D01*
X78600Y729350D01*
X79100Y728767D01*
X79267Y728100D01*
X79100Y727433D01*
X78683Y726933D01*
X77933Y726683D01*
X75933D01*
G01X85033Y729183D02*
X84533Y729433D01*
X83950Y729600D01*
X83283D01*
X82533Y729350D01*
X81950Y728933D01*
X81533Y728433D01*
X81200Y727600D01*
X81117Y726850D01*
X81283Y726100D01*
X81533Y725600D01*
X82033Y725100D01*
X82617Y724767D01*
X83200Y724600D01*
X83783D01*
X84367Y724767D01*
X84867Y725017D01*
X85283Y725350D01*
G01X87717Y726267D02*
X89883D01*
G01X92733Y729600D02*
Y724600D01*
X96067D01*
G01X98917Y726267D02*
X101083D01*
G01X105600Y724600D02*
Y729600D01*
X104600Y728600D01*
G01Y724600D02*
X106600D01*
G01X111200Y729600D02*
X110533Y729433D01*
X110033Y729017D01*
X109700Y728517D01*
X109450Y727850D01*
X109367Y727100D01*
X109450Y726350D01*
X109700Y725683D01*
X110033Y725183D01*
X110533Y724767D01*
X111200Y724600D01*
X111867Y724767D01*
X112367Y725183D01*
X112700Y725683D01*
X112950Y726350D01*
X113033Y727100D01*
X112950Y727850D01*
X112700Y728517D01*
X112367Y729017D01*
X111867Y729433D01*
X111200Y729600D01*
G01X115383Y725183D02*
X115967Y724767D01*
X116633Y724600D01*
X117300Y724767D01*
X117883Y725267D01*
X118300Y726017D01*
X118467Y726767D01*
Y727683D01*
X118300Y728433D01*
X117883Y729100D01*
X117383Y729433D01*
X116800Y729600D01*
X116133Y729433D01*
X115633Y729100D01*
X115300Y728600D01*
X115133Y727933D01*
X115300Y727350D01*
X115717Y726767D01*
X116217Y726433D01*
X116800Y726350D01*
X117467Y726517D01*
X117967Y726933D01*
X118467Y727683D01*
G01X126250Y725267D02*
X126917Y724850D01*
X127667Y724600D01*
X128333D01*
X129000Y724850D01*
X129500Y725267D01*
X129750Y725850D01*
X129583Y726433D01*
X129167Y726933D01*
X128417Y727267D01*
X127417Y727433D01*
X126833Y727767D01*
X126583Y728350D01*
X126750Y728933D01*
X127167Y729350D01*
X127750Y729600D01*
X128333D01*
X128917Y729433D01*
X129417Y729017D01*
G01X132100Y722933D02*
Y727933D01*
G01Y727183D02*
X132517Y727600D01*
X132933Y727850D01*
X133600Y727933D01*
X134183Y727850D01*
X134767Y727433D01*
X135017Y726850D01*
X135100Y726267D01*
X135017Y725683D01*
X134767Y725100D01*
X134267Y724767D01*
X133600Y724600D01*
X133017Y724683D01*
X132433Y724933D01*
X132100Y725267D01*
G01X137950Y726850D02*
X140617D01*
X140367Y727433D01*
X139950Y727767D01*
X139367Y727933D01*
X138783Y727850D01*
X138283Y727600D01*
X137950Y727017D01*
X137783Y726517D01*
Y726017D01*
X137950Y725517D01*
X138367Y725017D01*
X138867Y724683D01*
X139450Y724600D01*
X140033Y724767D01*
X140617Y725267D01*
G01X146133Y727517D02*
X145550Y727850D01*
X145050Y727933D01*
X144383Y727767D01*
X143883Y727433D01*
X143550Y726850D01*
X143467Y726267D01*
X143550Y725683D01*
X143883Y725183D01*
X144383Y724767D01*
X145050Y724600D01*
X145633Y724767D01*
X146133Y725100D01*
G01X150400Y727933D02*
Y724600D01*
G01Y729267D02*
X150233Y729350D01*
Y729517D01*
X150400Y729600D01*
X150567Y729517D01*
Y729350D01*
X150400Y729267D01*
G01X155500Y724600D02*
Y728850D01*
X155667Y729267D01*
X156000Y729517D01*
X156500Y729600D01*
X157000Y729433D01*
X157250Y729017D01*
G01X156250Y727600D02*
X154583D01*
G01X161600Y727933D02*
Y724600D01*
G01Y729267D02*
X161433Y729350D01*
Y729517D01*
X161600Y729600D01*
X161767Y729517D01*
Y729350D01*
X161600Y729267D01*
G01X168533Y727517D02*
X167950Y727850D01*
X167450Y727933D01*
X166783Y727767D01*
X166283Y727433D01*
X165950Y726850D01*
X165867Y726267D01*
X165950Y725683D01*
X166283Y725183D01*
X166783Y724767D01*
X167450Y724600D01*
X168033Y724767D01*
X168533Y725100D01*
G01X174300Y724600D02*
Y727933D01*
G01Y727350D02*
X173967Y727683D01*
X173467Y727850D01*
X172883Y727933D01*
X172300Y727767D01*
X171800Y727433D01*
X171467Y726933D01*
X171300Y726267D01*
X171467Y725600D01*
X171800Y725100D01*
X172300Y724767D01*
X172883Y724600D01*
X173467Y724683D01*
X173967Y724933D01*
X174300Y725267D01*
G01X178400Y729600D02*
Y724600D01*
G01X177233Y727933D02*
X179567D01*
G01X184000D02*
Y724600D01*
G01Y729267D02*
X183833Y729350D01*
Y729517D01*
X184000Y729600D01*
X184167Y729517D01*
Y729350D01*
X184000Y729267D01*
G01X189600Y724600D02*
X189100Y724683D01*
X188600Y725017D01*
X188267Y725600D01*
X188100Y726267D01*
X188267Y726933D01*
X188600Y727517D01*
X189100Y727850D01*
X189600Y727933D01*
X190100Y727850D01*
X190600Y727517D01*
X190933Y726933D01*
X191017Y726267D01*
X190933Y725600D01*
X190600Y725017D01*
X190100Y724683D01*
X189600Y724600D01*
G01X193783D02*
Y727933D01*
G01Y727100D02*
X194117Y727517D01*
X194617Y727850D01*
X195283Y727933D01*
X195867Y727850D01*
X196367Y727517D01*
X196617Y726933D01*
Y724600D01*
G01X205900D02*
Y728850D01*
X206067Y729267D01*
X206400Y729517D01*
X206900Y729600D01*
X207400Y729433D01*
X207650Y729017D01*
G01X206650Y727600D02*
X204983D01*
G01X212000Y724600D02*
X211500Y724683D01*
X211000Y725017D01*
X210667Y725600D01*
X210500Y726267D01*
X210667Y726933D01*
X211000Y727517D01*
X211500Y727850D01*
X212000Y727933D01*
X212500Y727850D01*
X213000Y727517D01*
X213333Y726933D01*
X213417Y726267D01*
X213333Y725600D01*
X213000Y725017D01*
X212500Y724683D01*
X212000Y724600D01*
G01X216433D02*
Y727933D01*
G01Y727267D02*
X216850Y727600D01*
X217267Y727850D01*
X217850Y727933D01*
X218267Y727850D01*
X218767Y727600D01*
G01X227133Y724600D02*
Y729600D01*
X229217D01*
X229883Y729350D01*
X230300Y729017D01*
X230467Y728350D01*
X230300Y727683D01*
X229800Y727267D01*
X229217Y727017D01*
X227133D01*
G01X229217D02*
X230467Y724600D01*
G01X233150Y726850D02*
X235817D01*
X235567Y727433D01*
X235150Y727767D01*
X234567Y727933D01*
X233983Y727850D01*
X233483Y727600D01*
X233150Y727017D01*
X232983Y726517D01*
Y726017D01*
X233150Y725517D01*
X233567Y725017D01*
X234067Y724683D01*
X234650Y724600D01*
X235233Y724767D01*
X235817Y725267D01*
G01X238750Y725183D02*
X239167Y724850D01*
X239750Y724600D01*
X240250D01*
X240750Y724767D01*
X241083Y725017D01*
X241250Y725350D01*
X241167Y725850D01*
X240833Y726100D01*
X239333Y726600D01*
X239000Y727183D01*
X239167Y727600D01*
X239500Y727850D01*
X240000Y727933D01*
X240500Y727850D01*
X241000Y727600D01*
G01X245600Y727933D02*
Y724600D01*
G01Y729267D02*
X245433Y729350D01*
Y729517D01*
X245600Y729600D01*
X245767Y729517D01*
Y729350D01*
X245600Y729267D01*
G01X249783Y724600D02*
Y727933D01*
G01Y727100D02*
X250117Y727517D01*
X250617Y727850D01*
X251283Y727933D01*
X251867Y727850D01*
X252367Y727517D01*
X252617Y726933D01*
Y724600D01*
G01X261400Y729600D02*
X263400D01*
G01X262400D02*
Y724600D01*
G01X261400D02*
X263400D01*
G01X265500D02*
Y727933D01*
G01Y727017D02*
X265750Y727433D01*
X266167Y727767D01*
X266750Y727933D01*
X267333Y727767D01*
X267750Y727433D01*
X268000Y727017D01*
Y724600D01*
G01Y727017D02*
X268250Y727433D01*
X268667Y727767D01*
X269250Y727933D01*
X269833Y727767D01*
X270250Y727433D01*
X270500Y726933D01*
Y724600D01*
G01X272100Y722933D02*
Y727933D01*
G01Y727183D02*
X272517Y727600D01*
X272933Y727850D01*
X273600Y727933D01*
X274183Y727850D01*
X274767Y727433D01*
X275017Y726850D01*
X275100Y726267D01*
X275017Y725683D01*
X274767Y725100D01*
X274267Y724767D01*
X273600Y724600D01*
X273017Y724683D01*
X272433Y724933D01*
X272100Y725267D01*
G01X278033Y724600D02*
Y727933D01*
G01Y727267D02*
X278450Y727600D01*
X278867Y727850D01*
X279450Y727933D01*
X279867Y727850D01*
X280367Y727600D01*
G01X283550Y726850D02*
X286217D01*
X285967Y727433D01*
X285550Y727767D01*
X284967Y727933D01*
X284383Y727850D01*
X283883Y727600D01*
X283550Y727017D01*
X283383Y726517D01*
Y726017D01*
X283550Y725517D01*
X283967Y725017D01*
X284467Y724683D01*
X285050Y724600D01*
X285633Y724767D01*
X286217Y725267D01*
G01X289233Y723350D02*
X289817Y723017D01*
X290483Y722933D01*
X291067Y723017D01*
X291567Y723433D01*
X291900Y724017D01*
Y727933D01*
G01Y727267D02*
X291567Y727600D01*
X291067Y727850D01*
X290483Y727933D01*
X289817Y727767D01*
X289400Y727433D01*
X289067Y726850D01*
X288900Y726267D01*
X288983Y725767D01*
X289317Y725183D01*
X289817Y724767D01*
X290483Y724600D01*
X290983Y724683D01*
X291567Y725017D01*
X291900Y725350D01*
G01X294583Y724600D02*
Y727933D01*
G01Y727100D02*
X294917Y727517D01*
X295417Y727850D01*
X296083Y727933D01*
X296667Y727850D01*
X297167Y727517D01*
X297417Y726933D01*
Y724600D01*
G01X303100D02*
Y727933D01*
G01Y727350D02*
X302767Y727683D01*
X302267Y727850D01*
X301683Y727933D01*
X301100Y727767D01*
X300600Y727433D01*
X300267Y726933D01*
X300100Y726267D01*
X300267Y725600D01*
X300600Y725100D01*
X301100Y724767D01*
X301683Y724600D01*
X302267Y724683D01*
X302767Y724933D01*
X303100Y725267D01*
G01X307200Y729600D02*
Y724600D01*
G01X306033Y727933D02*
X308367D01*
G01X311550Y726850D02*
X314217D01*
X313967Y727433D01*
X313550Y727767D01*
X312967Y727933D01*
X312383Y727850D01*
X311883Y727600D01*
X311550Y727017D01*
X311383Y726517D01*
Y726017D01*
X311550Y725517D01*
X311967Y725017D01*
X312467Y724683D01*
X313050Y724600D01*
X313633Y724767D01*
X314217Y725267D01*
G01X319900Y729600D02*
Y724600D01*
G01Y725350D02*
X319567Y724933D01*
X319067Y724683D01*
X318483Y724600D01*
X317817Y724767D01*
X317317Y725183D01*
X316983Y725683D01*
X316900Y726267D01*
X316983Y726850D01*
X317317Y727350D01*
X317817Y727767D01*
X318483Y727933D01*
X319067Y727850D01*
X319483Y727683D01*
X319900Y727350D01*
G01X328017Y724600D02*
Y729600D01*
X331183D01*
G01X330017Y727183D02*
X328017D01*
G01X336700Y724600D02*
Y727933D01*
G01Y727350D02*
X336367Y727683D01*
X335867Y727850D01*
X335283Y727933D01*
X334700Y727767D01*
X334200Y727433D01*
X333867Y726933D01*
X333700Y726267D01*
X333867Y725600D01*
X334200Y725100D01*
X334700Y724767D01*
X335283Y724600D01*
X335867Y724683D01*
X336367Y724933D01*
X336700Y725267D01*
G01X339300Y724600D02*
Y729600D01*
G01Y727100D02*
X339717Y727600D01*
X340217Y727850D01*
X340717Y727933D01*
X341467Y727767D01*
X341967Y727433D01*
X342300Y726850D01*
Y726183D01*
X342133Y725517D01*
X341800Y725017D01*
X341217Y724683D01*
X340717Y724600D01*
X340217Y724683D01*
X339717Y724933D01*
X339300Y725350D01*
G01X345233Y724600D02*
Y727933D01*
G01Y727267D02*
X345650Y727600D01*
X346067Y727850D01*
X346650Y727933D01*
X347067Y727850D01*
X347567Y727600D01*
G01X352000Y727933D02*
Y724600D01*
G01Y729267D02*
X351833Y729350D01*
Y729517D01*
X352000Y729600D01*
X352167Y729517D01*
Y729350D01*
X352000Y729267D01*
G01X358933Y727517D02*
X358350Y727850D01*
X357850Y727933D01*
X357183Y727767D01*
X356683Y727433D01*
X356350Y726850D01*
X356267Y726267D01*
X356350Y725683D01*
X356683Y725183D01*
X357183Y724767D01*
X357850Y724600D01*
X358433Y724767D01*
X358933Y725100D01*
G01X362783Y722933D02*
X361950Y723767D01*
X361533Y724600D01*
Y727933D01*
X361950Y728767D01*
X362783Y729600D01*
G01X367133Y724600D02*
Y729600D01*
X369133D01*
X369800Y729350D01*
X370300Y728767D01*
X370467Y728100D01*
X370300Y727433D01*
X369883Y726933D01*
X369133Y726683D01*
X367133D01*
G01X373233Y724600D02*
Y727933D01*
G01Y727267D02*
X373650Y727600D01*
X374067Y727850D01*
X374650Y727933D01*
X375067Y727850D01*
X375567Y727600D01*
G01X378750Y726850D02*
X381417D01*
X381167Y727433D01*
X380750Y727767D01*
X380167Y727933D01*
X379583Y727850D01*
X379083Y727600D01*
X378750Y727017D01*
X378583Y726517D01*
Y726017D01*
X378750Y725517D01*
X379167Y725017D01*
X379667Y724683D01*
X380250Y724600D01*
X380833Y724767D01*
X381417Y725267D01*
G01X384100Y722933D02*
Y727933D01*
G01Y727183D02*
X384517Y727600D01*
X384933Y727850D01*
X385600Y727933D01*
X386183Y727850D01*
X386767Y727433D01*
X387017Y726850D01*
X387100Y726267D01*
X387017Y725683D01*
X386767Y725100D01*
X386267Y724767D01*
X385600Y724600D01*
X385017Y724683D01*
X384433Y724933D01*
X384100Y725267D01*
G01X390033Y724600D02*
Y727933D01*
G01Y727267D02*
X390450Y727600D01*
X390867Y727850D01*
X391450Y727933D01*
X391867Y727850D01*
X392367Y727600D01*
G01X395550Y726850D02*
X398217D01*
X397967Y727433D01*
X397550Y727767D01*
X396967Y727933D01*
X396383Y727850D01*
X395883Y727600D01*
X395550Y727017D01*
X395383Y726517D01*
Y726017D01*
X395550Y725517D01*
X395967Y725017D01*
X396467Y724683D01*
X397050Y724600D01*
X397633Y724767D01*
X398217Y725267D01*
G01X401233Y723350D02*
X401817Y723017D01*
X402483Y722933D01*
X403067Y723017D01*
X403567Y723433D01*
X403900Y724017D01*
Y727933D01*
G01Y727267D02*
X403567Y727600D01*
X403067Y727850D01*
X402483Y727933D01*
X401817Y727767D01*
X401400Y727433D01*
X401067Y726850D01*
X400900Y726267D01*
X400983Y725767D01*
X401317Y725183D01*
X401817Y724767D01*
X402483Y724600D01*
X402983Y724683D01*
X403567Y725017D01*
X403900Y725350D01*
G01X408417Y722933D02*
X409250Y723767D01*
X409667Y724600D01*
Y727933D01*
X409250Y728767D01*
X408417Y729600D01*
G01X418700Y724600D02*
Y728850D01*
X418867Y729267D01*
X419200Y729517D01*
X419700Y729600D01*
X420200Y729433D01*
X420450Y729017D01*
G01X419450Y727600D02*
X417783D01*
G01X424800Y724600D02*
X424300Y724683D01*
X423800Y725017D01*
X423467Y725600D01*
X423300Y726267D01*
X423467Y726933D01*
X423800Y727517D01*
X424300Y727850D01*
X424800Y727933D01*
X425300Y727850D01*
X425800Y727517D01*
X426133Y726933D01*
X426217Y726267D01*
X426133Y725600D01*
X425800Y725017D01*
X425300Y724683D01*
X424800Y724600D01*
G01X429233D02*
Y727933D01*
G01Y727267D02*
X429650Y727600D01*
X430067Y727850D01*
X430650Y727933D01*
X431067Y727850D01*
X431567Y727600D01*
G01X439433Y724600D02*
Y729600D01*
X441600Y725433D01*
X443767Y729600D01*
Y724600D01*
G01X445783Y727933D02*
Y725600D01*
X446117Y725017D01*
X446617Y724683D01*
X447200Y724600D01*
X447783Y724683D01*
X448283Y725017D01*
X448617Y725600D01*
G01Y724600D02*
Y727933D01*
G01X452800Y724600D02*
Y729600D01*
G01X458400D02*
Y724600D01*
G01X457233Y727933D02*
X459567D01*
G01X464000D02*
Y724600D01*
G01Y729267D02*
X463833Y729350D01*
Y729517D01*
X464000Y729600D01*
X464167Y729517D01*
Y729350D01*
X464000Y729267D01*
G01X469600Y724600D02*
Y729600D01*
G01X476700Y724600D02*
Y727933D01*
G01Y727350D02*
X476367Y727683D01*
X475867Y727850D01*
X475283Y727933D01*
X474700Y727767D01*
X474200Y727433D01*
X473867Y726933D01*
X473700Y726267D01*
X473867Y725600D01*
X474200Y725100D01*
X474700Y724767D01*
X475283Y724600D01*
X475867Y724683D01*
X476367Y724933D01*
X476700Y725267D01*
G01X479050Y723100D02*
X479550Y722933D01*
X480217Y723100D01*
X480633Y723433D01*
X480967Y723850D01*
X481467Y725183D01*
X482550Y727933D01*
G01X479883D02*
X481467Y725183D01*
G01X485150Y726850D02*
X487817D01*
X487567Y727433D01*
X487150Y727767D01*
X486567Y727933D01*
X485983Y727850D01*
X485483Y727600D01*
X485150Y727017D01*
X484983Y726517D01*
Y726017D01*
X485150Y725517D01*
X485567Y725017D01*
X486067Y724683D01*
X486650Y724600D01*
X487233Y724767D01*
X487817Y725267D01*
G01X490833Y724600D02*
Y727933D01*
G01Y727267D02*
X491250Y727600D01*
X491667Y727850D01*
X492250Y727933D01*
X492667Y727850D01*
X493167Y727600D01*
G01X501533Y724600D02*
Y729600D01*
X503533D01*
X504200Y729350D01*
X504700Y728767D01*
X504867Y728100D01*
X504700Y727433D01*
X504283Y726933D01*
X503533Y726683D01*
X501533D01*
G01X507633Y724600D02*
Y727933D01*
G01Y727267D02*
X508050Y727600D01*
X508467Y727850D01*
X509050Y727933D01*
X509467Y727850D01*
X509967Y727600D01*
G01X514400Y727933D02*
Y724600D01*
G01Y729267D02*
X514233Y729350D01*
Y729517D01*
X514400Y729600D01*
X514567Y729517D01*
Y729350D01*
X514400Y729267D01*
G01X518583Y724600D02*
Y727933D01*
G01Y727100D02*
X518917Y727517D01*
X519417Y727850D01*
X520083Y727933D01*
X520667Y727850D01*
X521167Y727517D01*
X521417Y726933D01*
Y724600D01*
G01X525600Y729600D02*
Y724600D01*
G01X524433Y727933D02*
X526767D01*
G01X529950Y726850D02*
X532617D01*
X532367Y727433D01*
X531950Y727767D01*
X531367Y727933D01*
X530783Y727850D01*
X530283Y727600D01*
X529950Y727017D01*
X529783Y726517D01*
Y726017D01*
X529950Y725517D01*
X530367Y725017D01*
X530867Y724683D01*
X531450Y724600D01*
X532033Y724767D01*
X532617Y725267D01*
G01X538300Y729600D02*
Y724600D01*
G01Y725350D02*
X537967Y724933D01*
X537467Y724683D01*
X536883Y724600D01*
X536217Y724767D01*
X535717Y725183D01*
X535383Y725683D01*
X535300Y726267D01*
X535383Y726850D01*
X535717Y727350D01*
X536217Y727767D01*
X536883Y727933D01*
X537467Y727850D01*
X537883Y727683D01*
X538300Y727350D01*
G01X548667Y727267D02*
X549000Y727517D01*
X549250Y727933D01*
X549417Y728517D01*
X549250Y729017D01*
X548917Y729350D01*
X548333Y729600D01*
X546083D01*
Y724600D01*
X548833D01*
X549417Y724933D01*
X549750Y725433D01*
X549917Y726017D01*
X549750Y726600D01*
X549250Y727100D01*
X548667Y727267D01*
X546083D01*
G01X553600Y724600D02*
X553100Y724683D01*
X552600Y725017D01*
X552267Y725600D01*
X552100Y726267D01*
X552267Y726933D01*
X552600Y727517D01*
X553100Y727850D01*
X553600Y727933D01*
X554100Y727850D01*
X554600Y727517D01*
X554933Y726933D01*
X555017Y726267D01*
X554933Y725600D01*
X554600Y725017D01*
X554100Y724683D01*
X553600Y724600D01*
G01X560700D02*
Y727933D01*
G01Y727350D02*
X560367Y727683D01*
X559867Y727850D01*
X559283Y727933D01*
X558700Y727767D01*
X558200Y727433D01*
X557867Y726933D01*
X557700Y726267D01*
X557867Y725600D01*
X558200Y725100D01*
X558700Y724767D01*
X559283Y724600D01*
X559867Y724683D01*
X560367Y724933D01*
X560700Y725267D01*
G01X563633Y724600D02*
Y727933D01*
G01Y727267D02*
X564050Y727600D01*
X564467Y727850D01*
X565050Y727933D01*
X565467Y727850D01*
X565967Y727600D01*
G01X571900Y729600D02*
Y724600D01*
G01Y725350D02*
X571567Y724933D01*
X571067Y724683D01*
X570483Y724600D01*
X569817Y724767D01*
X569317Y725183D01*
X568983Y725683D01*
X568900Y726267D01*
X568983Y726850D01*
X569317Y727350D01*
X569817Y727767D01*
X570483Y727933D01*
X571067Y727850D01*
X571483Y727683D01*
X571900Y727350D01*
G01X574750Y725183D02*
X575167Y724850D01*
X575750Y724600D01*
X576250D01*
X576750Y724767D01*
X577083Y725017D01*
X577250Y725350D01*
X577167Y725850D01*
X576833Y726100D01*
X575333Y726600D01*
X575000Y727183D01*
X575167Y727600D01*
X575500Y727850D01*
X576000Y727933D01*
X576500Y727850D01*
X577000Y727600D01*
G01X71000Y738600D02*
X73000D01*
G01X72000D02*
Y733600D01*
G01X71000D02*
X73000D01*
G01X75933D02*
Y738600D01*
X77933D01*
X78600Y738350D01*
X79100Y737767D01*
X79267Y737100D01*
X79100Y736433D01*
X78683Y735933D01*
X77933Y735683D01*
X75933D01*
G01X85033Y738183D02*
X84533Y738433D01*
X83950Y738600D01*
X83283D01*
X82533Y738350D01*
X81950Y737933D01*
X81533Y737433D01*
X81200Y736600D01*
X81117Y735850D01*
X81283Y735100D01*
X81533Y734600D01*
X82033Y734100D01*
X82617Y733767D01*
X83200Y733600D01*
X83783D01*
X84367Y733767D01*
X84867Y734017D01*
X85283Y734350D01*
G01X87717Y735267D02*
X89883D01*
G01X92233Y733600D02*
Y738600D01*
X94400Y734433D01*
X96567Y738600D01*
Y733600D01*
G01X98417D02*
Y738600D01*
X101583D01*
G01X100417Y736183D02*
X98417D01*
G01X104517Y735267D02*
X106683D01*
G01X111200Y733600D02*
Y738600D01*
X110200Y737600D01*
G01Y733600D02*
X112200D01*
G01X114967Y734350D02*
X115467Y733933D01*
X116050Y733683D01*
X116800Y733600D01*
X117550Y733767D01*
X118133Y734100D01*
X118550Y734683D01*
X118633Y735350D01*
X118467Y736017D01*
X118050Y736433D01*
X117467Y736767D01*
X116883Y736850D01*
X116300Y736767D01*
X115550Y736433D01*
X115800Y738600D01*
X118050D01*
G01X122400D02*
X121733Y738433D01*
X121233Y738017D01*
X120900Y737517D01*
X120650Y736850D01*
X120567Y736100D01*
X120650Y735350D01*
X120900Y734683D01*
X121233Y734183D01*
X121733Y733767D01*
X122400Y733600D01*
X123067Y733767D01*
X123567Y734183D01*
X123900Y734683D01*
X124150Y735350D01*
X124233Y736100D01*
X124150Y736850D01*
X123900Y737517D01*
X123567Y738017D01*
X123067Y738433D01*
X122400Y738600D01*
G01X131433Y733600D02*
Y738600D01*
X133600Y734433D01*
X135767Y738600D01*
Y733600D01*
G01X137950Y735850D02*
X140617D01*
X140367Y736433D01*
X139950Y736767D01*
X139367Y736933D01*
X138783Y736850D01*
X138283Y736600D01*
X137950Y736017D01*
X137783Y735517D01*
Y735017D01*
X137950Y734517D01*
X138367Y734017D01*
X138867Y733683D01*
X139450Y733600D01*
X140033Y733767D01*
X140617Y734267D01*
G01X144800Y738600D02*
Y733600D01*
G01X143633Y736933D02*
X145967D01*
G01X151900Y733600D02*
Y736933D01*
G01Y736350D02*
X151567Y736683D01*
X151067Y736850D01*
X150483Y736933D01*
X149900Y736767D01*
X149400Y736433D01*
X149067Y735933D01*
X148900Y735267D01*
X149067Y734600D01*
X149400Y734100D01*
X149900Y733767D01*
X150483Y733600D01*
X151067Y733683D01*
X151567Y733933D01*
X151900Y734267D01*
G01X156000Y733600D02*
Y738600D01*
G01X165617Y733600D02*
Y738600D01*
X168783D01*
G01X167617Y736183D02*
X165617D01*
G01X172800Y733600D02*
X172300Y733683D01*
X171800Y734017D01*
X171467Y734600D01*
X171300Y735267D01*
X171467Y735933D01*
X171800Y736517D01*
X172300Y736850D01*
X172800Y736933D01*
X173300Y736850D01*
X173800Y736517D01*
X174133Y735933D01*
X174217Y735267D01*
X174133Y734600D01*
X173800Y734017D01*
X173300Y733683D01*
X172800Y733600D01*
G01X178400Y736933D02*
Y733600D01*
G01Y738267D02*
X178233Y738350D01*
Y738517D01*
X178400Y738600D01*
X178567Y738517D01*
Y738350D01*
X178400Y738267D01*
G01X184000Y733600D02*
Y738600D01*
G01X194700Y733600D02*
Y737850D01*
X194867Y738267D01*
X195200Y738517D01*
X195700Y738600D01*
X196200Y738433D01*
X196450Y738017D01*
G01X195450Y736600D02*
X193783D01*
G01X200800Y733600D02*
X200300Y733683D01*
X199800Y734017D01*
X199467Y734600D01*
X199300Y735267D01*
X199467Y735933D01*
X199800Y736517D01*
X200300Y736850D01*
X200800Y736933D01*
X201300Y736850D01*
X201800Y736517D01*
X202133Y735933D01*
X202217Y735267D01*
X202133Y734600D01*
X201800Y734017D01*
X201300Y733683D01*
X200800Y733600D01*
G01X205233D02*
Y736933D01*
G01Y736267D02*
X205650Y736600D01*
X206067Y736850D01*
X206650Y736933D01*
X207067Y736850D01*
X207567Y736600D01*
G01X215933Y733600D02*
Y738600D01*
X217933D01*
X218600Y738350D01*
X219100Y737767D01*
X219267Y737100D01*
X219100Y736433D01*
X218683Y735933D01*
X217933Y735683D01*
X215933D01*
G01X222033Y733600D02*
Y736933D01*
G01Y736267D02*
X222450Y736600D01*
X222867Y736850D01*
X223450Y736933D01*
X223867Y736850D01*
X224367Y736600D01*
G01X228800Y736933D02*
Y733600D01*
G01Y738267D02*
X228633Y738350D01*
Y738517D01*
X228800Y738600D01*
X228967Y738517D01*
Y738350D01*
X228800Y738267D01*
G01X232983Y733600D02*
Y736933D01*
G01Y736100D02*
X233317Y736517D01*
X233817Y736850D01*
X234483Y736933D01*
X235067Y736850D01*
X235567Y736517D01*
X235817Y735933D01*
Y733600D01*
G01X240000Y738600D02*
Y733600D01*
G01X238833Y736933D02*
X241167D01*
G01X244350Y735850D02*
X247017D01*
X246767Y736433D01*
X246350Y736767D01*
X245767Y736933D01*
X245183Y736850D01*
X244683Y736600D01*
X244350Y736017D01*
X244183Y735517D01*
Y735017D01*
X244350Y734517D01*
X244767Y734017D01*
X245267Y733683D01*
X245850Y733600D01*
X246433Y733767D01*
X247017Y734267D01*
G01X252700Y738600D02*
Y733600D01*
G01Y734350D02*
X252367Y733933D01*
X251867Y733683D01*
X251283Y733600D01*
X250617Y733767D01*
X250117Y734183D01*
X249783Y734683D01*
X249700Y735267D01*
X249783Y735850D01*
X250117Y736350D01*
X250617Y736767D01*
X251283Y736933D01*
X251867Y736850D01*
X252283Y736683D01*
X252700Y736350D01*
G01X259900Y738600D02*
X261067Y733600D01*
X262400Y738600D01*
X263733Y733600D01*
X264900Y738600D01*
G01X268000Y736933D02*
Y733600D01*
G01Y738267D02*
X267833Y738350D01*
Y738517D01*
X268000Y738600D01*
X268167Y738517D01*
Y738350D01*
X268000Y738267D01*
G01X272433Y733600D02*
Y736933D01*
G01Y736267D02*
X272850Y736600D01*
X273267Y736850D01*
X273850Y736933D01*
X274267Y736850D01*
X274767Y736600D01*
G01X279200Y736933D02*
Y733600D01*
G01Y738267D02*
X279033Y738350D01*
Y738517D01*
X279200Y738600D01*
X279367Y738517D01*
Y738350D01*
X279200Y738267D01*
G01X283383Y733600D02*
Y736933D01*
G01Y736100D02*
X283717Y736517D01*
X284217Y736850D01*
X284883Y736933D01*
X285467Y736850D01*
X285967Y736517D01*
X286217Y735933D01*
Y733600D01*
G01X289233Y732350D02*
X289817Y732017D01*
X290483Y731933D01*
X291067Y732017D01*
X291567Y732433D01*
X291900Y733017D01*
Y736933D01*
G01Y736267D02*
X291567Y736600D01*
X291067Y736850D01*
X290483Y736933D01*
X289817Y736767D01*
X289400Y736433D01*
X289067Y735850D01*
X288900Y735267D01*
X288983Y734767D01*
X289317Y734183D01*
X289817Y733767D01*
X290483Y733600D01*
X290983Y733683D01*
X291567Y734017D01*
X291900Y734350D01*
G01X299517Y733600D02*
X301600Y738600D01*
X303683Y733600D01*
G01X302933Y735350D02*
X300267D01*
G01X305700Y731933D02*
Y736933D01*
G01Y736183D02*
X306117Y736600D01*
X306533Y736850D01*
X307200Y736933D01*
X307783Y736850D01*
X308367Y736433D01*
X308617Y735850D01*
X308700Y735267D01*
X308617Y734683D01*
X308367Y734100D01*
X307867Y733767D01*
X307200Y733600D01*
X306617Y733683D01*
X306033Y733933D01*
X305700Y734267D01*
G01X311300Y731933D02*
Y736933D01*
G01Y736183D02*
X311717Y736600D01*
X312133Y736850D01*
X312800Y736933D01*
X313383Y736850D01*
X313967Y736433D01*
X314217Y735850D01*
X314300Y735267D01*
X314217Y734683D01*
X313967Y734100D01*
X313467Y733767D01*
X312800Y733600D01*
X312217Y733683D01*
X311633Y733933D01*
X311300Y734267D01*
G01X318400Y733600D02*
Y738600D01*
G01X324000Y736933D02*
Y733600D01*
G01Y738267D02*
X323833Y738350D01*
Y738517D01*
X324000Y738600D01*
X324167Y738517D01*
Y738350D01*
X324000Y738267D01*
G01X330933Y736517D02*
X330350Y736850D01*
X329850Y736933D01*
X329183Y736767D01*
X328683Y736433D01*
X328350Y735850D01*
X328267Y735267D01*
X328350Y734683D01*
X328683Y734183D01*
X329183Y733767D01*
X329850Y733600D01*
X330433Y733767D01*
X330933Y734100D01*
G01X336700Y733600D02*
Y736933D01*
G01Y736350D02*
X336367Y736683D01*
X335867Y736850D01*
X335283Y736933D01*
X334700Y736767D01*
X334200Y736433D01*
X333867Y735933D01*
X333700Y735267D01*
X333867Y734600D01*
X334200Y734100D01*
X334700Y733767D01*
X335283Y733600D01*
X335867Y733683D01*
X336367Y733933D01*
X336700Y734267D01*
G01X340800Y738600D02*
Y733600D01*
G01X339633Y736933D02*
X341967D01*
G01X346400D02*
Y733600D01*
G01Y738267D02*
X346233Y738350D01*
Y738517D01*
X346400Y738600D01*
X346567Y738517D01*
Y738350D01*
X346400Y738267D01*
G01X352000Y733600D02*
X351500Y733683D01*
X351000Y734017D01*
X350667Y734600D01*
X350500Y735267D01*
X350667Y735933D01*
X351000Y736517D01*
X351500Y736850D01*
X352000Y736933D01*
X352500Y736850D01*
X353000Y736517D01*
X353333Y735933D01*
X353417Y735267D01*
X353333Y734600D01*
X353000Y734017D01*
X352500Y733683D01*
X352000Y733600D01*
G01X356183D02*
Y736933D01*
G01Y736100D02*
X356517Y736517D01*
X357017Y736850D01*
X357683Y736933D01*
X358267Y736850D01*
X358767Y736517D01*
X359017Y735933D01*
Y733600D01*
G01X361950Y734183D02*
X362367Y733850D01*
X362950Y733600D01*
X363450D01*
X363950Y733767D01*
X364283Y734017D01*
X364450Y734350D01*
X364367Y734850D01*
X364033Y735100D01*
X362533Y735600D01*
X362200Y736183D01*
X362367Y736600D01*
X362700Y736850D01*
X363200Y736933D01*
X363700Y736850D01*
X364200Y736600D01*
G01X67000Y743433D02*
X66833Y743517D01*
Y743683D01*
X67000Y743767D01*
X67167Y743683D01*
Y743517D01*
X67000Y743433D01*
G01Y752433D02*
X66833Y752517D01*
Y752683D01*
X67000Y752767D01*
X67167Y752683D01*
Y752517D01*
X67000Y752433D01*
G01Y761433D02*
X66833Y761517D01*
Y761683D01*
X67000Y761767D01*
X67167Y761683D01*
Y761517D01*
X67000Y761433D01*
G01Y770433D02*
X66833Y770517D01*
Y770683D01*
X67000Y770767D01*
X67167Y770683D01*
Y770517D01*
X67000Y770433D01*
G01X71000Y747600D02*
X73000D01*
G01X72000D02*
Y742600D01*
G01X71000D02*
X73000D01*
G01X75933D02*
Y747600D01*
X77933D01*
X78600Y747350D01*
X79100Y746767D01*
X79267Y746100D01*
X79100Y745433D01*
X78683Y744933D01*
X77933Y744683D01*
X75933D01*
G01X85033Y747183D02*
X84533Y747433D01*
X83950Y747600D01*
X83283D01*
X82533Y747350D01*
X81950Y746933D01*
X81533Y746433D01*
X81200Y745600D01*
X81117Y744850D01*
X81283Y744100D01*
X81533Y743600D01*
X82033Y743100D01*
X82617Y742767D01*
X83200Y742600D01*
X83783D01*
X84367Y742767D01*
X84867Y743017D01*
X85283Y743350D01*
G01X87717Y744267D02*
X89883D01*
G01X95400Y742600D02*
Y747600D01*
X92317Y744017D01*
X96483D01*
G01X100000Y742600D02*
Y747600D01*
X99000Y746600D01*
G01Y742600D02*
X101000D01*
G01X105600Y747600D02*
X104933Y747433D01*
X104433Y747017D01*
X104100Y746517D01*
X103850Y745850D01*
X103767Y745100D01*
X103850Y744350D01*
X104100Y743683D01*
X104433Y743183D01*
X104933Y742767D01*
X105600Y742600D01*
X106267Y742767D01*
X106767Y743183D01*
X107100Y743683D01*
X107350Y744350D01*
X107433Y745100D01*
X107350Y745850D01*
X107100Y746517D01*
X106767Y747017D01*
X106267Y747433D01*
X105600Y747600D01*
G01X111200Y742600D02*
Y747600D01*
X110200Y746600D01*
G01Y742600D02*
X112200D01*
G01X120650Y743267D02*
X121317Y742850D01*
X122067Y742600D01*
X122733D01*
X123400Y742850D01*
X123900Y743267D01*
X124150Y743850D01*
X123983Y744433D01*
X123567Y744933D01*
X122817Y745267D01*
X121817Y745433D01*
X121233Y745767D01*
X120983Y746350D01*
X121150Y746933D01*
X121567Y747350D01*
X122150Y747600D01*
X122733D01*
X123317Y747433D01*
X123817Y747017D01*
G01X126500Y740933D02*
Y745933D01*
G01Y745183D02*
X126917Y745600D01*
X127333Y745850D01*
X128000Y745933D01*
X128583Y745850D01*
X129167Y745433D01*
X129417Y744850D01*
X129500Y744267D01*
X129417Y743683D01*
X129167Y743100D01*
X128667Y742767D01*
X128000Y742600D01*
X127417Y742683D01*
X126833Y742933D01*
X126500Y743267D01*
G01X132350Y744850D02*
X135017D01*
X134767Y745433D01*
X134350Y745767D01*
X133767Y745933D01*
X133183Y745850D01*
X132683Y745600D01*
X132350Y745017D01*
X132183Y744517D01*
Y744017D01*
X132350Y743517D01*
X132767Y743017D01*
X133267Y742683D01*
X133850Y742600D01*
X134433Y742767D01*
X135017Y743267D01*
G01X140533Y745517D02*
X139950Y745850D01*
X139450Y745933D01*
X138783Y745767D01*
X138283Y745433D01*
X137950Y744850D01*
X137867Y744267D01*
X137950Y743683D01*
X138283Y743183D01*
X138783Y742767D01*
X139450Y742600D01*
X140033Y742767D01*
X140533Y743100D01*
G01X144800Y745933D02*
Y742600D01*
G01Y747267D02*
X144633Y747350D01*
Y747517D01*
X144800Y747600D01*
X144967Y747517D01*
Y747350D01*
X144800Y747267D01*
G01X149900Y742600D02*
Y746850D01*
X150067Y747267D01*
X150400Y747517D01*
X150900Y747600D01*
X151400Y747433D01*
X151650Y747017D01*
G01X150650Y745600D02*
X148983D01*
G01X156000Y745933D02*
Y742600D01*
G01Y747267D02*
X155833Y747350D01*
Y747517D01*
X156000Y747600D01*
X156167Y747517D01*
Y747350D01*
X156000Y747267D01*
G01X162933Y745517D02*
X162350Y745850D01*
X161850Y745933D01*
X161183Y745767D01*
X160683Y745433D01*
X160350Y744850D01*
X160267Y744267D01*
X160350Y743683D01*
X160683Y743183D01*
X161183Y742767D01*
X161850Y742600D01*
X162433Y742767D01*
X162933Y743100D01*
G01X168700Y742600D02*
Y745933D01*
G01Y745350D02*
X168367Y745683D01*
X167867Y745850D01*
X167283Y745933D01*
X166700Y745767D01*
X166200Y745433D01*
X165867Y744933D01*
X165700Y744267D01*
X165867Y743600D01*
X166200Y743100D01*
X166700Y742767D01*
X167283Y742600D01*
X167867Y742683D01*
X168367Y742933D01*
X168700Y743267D01*
G01X172800Y747600D02*
Y742600D01*
G01X171633Y745933D02*
X173967D01*
G01X178400D02*
Y742600D01*
G01Y747267D02*
X178233Y747350D01*
Y747517D01*
X178400Y747600D01*
X178567Y747517D01*
Y747350D01*
X178400Y747267D01*
G01X184000Y742600D02*
X183500Y742683D01*
X183000Y743017D01*
X182667Y743600D01*
X182500Y744267D01*
X182667Y744933D01*
X183000Y745517D01*
X183500Y745850D01*
X184000Y745933D01*
X184500Y745850D01*
X185000Y745517D01*
X185333Y744933D01*
X185417Y744267D01*
X185333Y743600D01*
X185000Y743017D01*
X184500Y742683D01*
X184000Y742600D01*
G01X188183D02*
Y745933D01*
G01Y745100D02*
X188517Y745517D01*
X189017Y745850D01*
X189683Y745933D01*
X190267Y745850D01*
X190767Y745517D01*
X191017Y744933D01*
Y742600D01*
G01X200300D02*
Y746850D01*
X200467Y747267D01*
X200800Y747517D01*
X201300Y747600D01*
X201800Y747433D01*
X202050Y747017D01*
G01X201050Y745600D02*
X199383D01*
G01X206400Y742600D02*
X205900Y742683D01*
X205400Y743017D01*
X205067Y743600D01*
X204900Y744267D01*
X205067Y744933D01*
X205400Y745517D01*
X205900Y745850D01*
X206400Y745933D01*
X206900Y745850D01*
X207400Y745517D01*
X207733Y744933D01*
X207817Y744267D01*
X207733Y743600D01*
X207400Y743017D01*
X206900Y742683D01*
X206400Y742600D01*
G01X210833D02*
Y745933D01*
G01Y745267D02*
X211250Y745600D01*
X211667Y745850D01*
X212250Y745933D01*
X212667Y745850D01*
X213167Y745600D01*
G01X223867Y745267D02*
X224200Y745517D01*
X224450Y745933D01*
X224617Y746517D01*
X224450Y747017D01*
X224117Y747350D01*
X223533Y747600D01*
X221283D01*
Y742600D01*
X224033D01*
X224617Y742933D01*
X224950Y743433D01*
X225117Y744017D01*
X224950Y744600D01*
X224450Y745100D01*
X223867Y745267D01*
X221283D01*
G01X230300Y742600D02*
Y745933D01*
G01Y745350D02*
X229967Y745683D01*
X229467Y745850D01*
X228883Y745933D01*
X228300Y745767D01*
X227800Y745433D01*
X227467Y744933D01*
X227300Y744267D01*
X227467Y743600D01*
X227800Y743100D01*
X228300Y742767D01*
X228883Y742600D01*
X229467Y742683D01*
X229967Y742933D01*
X230300Y743267D01*
G01X233150Y743183D02*
X233567Y742850D01*
X234150Y742600D01*
X234650D01*
X235150Y742767D01*
X235483Y743017D01*
X235650Y743350D01*
X235567Y743850D01*
X235233Y744100D01*
X233733Y744600D01*
X233400Y745183D01*
X233567Y745600D01*
X233900Y745850D01*
X234400Y745933D01*
X234900Y745850D01*
X235400Y745600D01*
G01X238750Y744850D02*
X241417D01*
X241167Y745433D01*
X240750Y745767D01*
X240167Y745933D01*
X239583Y745850D01*
X239083Y745600D01*
X238750Y745017D01*
X238583Y744517D01*
Y744017D01*
X238750Y743517D01*
X239167Y743017D01*
X239667Y742683D01*
X240250Y742600D01*
X240833Y742767D01*
X241417Y743267D01*
G01X249033Y742600D02*
Y747600D01*
X251200Y743433D01*
X253367Y747600D01*
Y742600D01*
G01X258300D02*
Y745933D01*
G01Y745350D02*
X257967Y745683D01*
X257467Y745850D01*
X256883Y745933D01*
X256300Y745767D01*
X255800Y745433D01*
X255467Y744933D01*
X255300Y744267D01*
X255467Y743600D01*
X255800Y743100D01*
X256300Y742767D01*
X256883Y742600D01*
X257467Y742683D01*
X257967Y742933D01*
X258300Y743267D01*
G01X262400Y747600D02*
Y742600D01*
G01X261233Y745933D02*
X263567D01*
G01X266750Y744850D02*
X269417D01*
X269167Y745433D01*
X268750Y745767D01*
X268167Y745933D01*
X267583Y745850D01*
X267083Y745600D01*
X266750Y745017D01*
X266583Y744517D01*
Y744017D01*
X266750Y743517D01*
X267167Y743017D01*
X267667Y742683D01*
X268250Y742600D01*
X268833Y742767D01*
X269417Y743267D01*
G01X272433Y742600D02*
Y745933D01*
G01Y745267D02*
X272850Y745600D01*
X273267Y745850D01*
X273850Y745933D01*
X274267Y745850D01*
X274767Y745600D01*
G01X279200Y745933D02*
Y742600D01*
G01Y747267D02*
X279033Y747350D01*
Y747517D01*
X279200Y747600D01*
X279367Y747517D01*
Y747350D01*
X279200Y747267D01*
G01X286300Y742600D02*
Y745933D01*
G01Y745350D02*
X285967Y745683D01*
X285467Y745850D01*
X284883Y745933D01*
X284300Y745767D01*
X283800Y745433D01*
X283467Y744933D01*
X283300Y744267D01*
X283467Y743600D01*
X283800Y743100D01*
X284300Y742767D01*
X284883Y742600D01*
X285467Y742683D01*
X285967Y742933D01*
X286300Y743267D01*
G01X290400Y742600D02*
Y747600D01*
G01X294750Y743183D02*
X295167Y742850D01*
X295750Y742600D01*
X296250D01*
X296750Y742767D01*
X297083Y743017D01*
X297250Y743350D01*
X297167Y743850D01*
X296833Y744100D01*
X295333Y744600D01*
X295000Y745183D01*
X295167Y745600D01*
X295500Y745850D01*
X296000Y745933D01*
X296500Y745850D01*
X297000Y745600D01*
G01X306700Y742600D02*
Y746850D01*
X306867Y747267D01*
X307200Y747517D01*
X307700Y747600D01*
X308200Y747433D01*
X308450Y747017D01*
G01X307450Y745600D02*
X305783D01*
G01X312800Y742600D02*
X312300Y742683D01*
X311800Y743017D01*
X311467Y743600D01*
X311300Y744267D01*
X311467Y744933D01*
X311800Y745517D01*
X312300Y745850D01*
X312800Y745933D01*
X313300Y745850D01*
X313800Y745517D01*
X314133Y744933D01*
X314217Y744267D01*
X314133Y743600D01*
X313800Y743017D01*
X313300Y742683D01*
X312800Y742600D01*
G01X317233D02*
Y745933D01*
G01Y745267D02*
X317650Y745600D01*
X318067Y745850D01*
X318650Y745933D01*
X319067Y745850D01*
X319567Y745600D01*
G01X327933Y742600D02*
Y747600D01*
X330017D01*
X330683Y747350D01*
X331100Y747017D01*
X331267Y746350D01*
X331100Y745683D01*
X330600Y745267D01*
X330017Y745017D01*
X327933D01*
G01X330017D02*
X331267Y742600D01*
G01X335200Y745933D02*
Y742600D01*
G01Y747267D02*
X335033Y747350D01*
Y747517D01*
X335200Y747600D01*
X335367Y747517D01*
Y747350D01*
X335200Y747267D01*
G01X339633Y741350D02*
X340217Y741017D01*
X340883Y740933D01*
X341467Y741017D01*
X341967Y741433D01*
X342300Y742017D01*
Y745933D01*
G01Y745267D02*
X341967Y745600D01*
X341467Y745850D01*
X340883Y745933D01*
X340217Y745767D01*
X339800Y745433D01*
X339467Y744850D01*
X339300Y744267D01*
X339383Y743767D01*
X339717Y743183D01*
X340217Y742767D01*
X340883Y742600D01*
X341383Y742683D01*
X341967Y743017D01*
X342300Y743350D01*
G01X346400Y745933D02*
Y742600D01*
G01Y747267D02*
X346233Y747350D01*
Y747517D01*
X346400Y747600D01*
X346567Y747517D01*
Y747350D01*
X346400Y747267D01*
G01X353500Y747600D02*
Y742600D01*
G01Y743350D02*
X353167Y742933D01*
X352667Y742683D01*
X352083Y742600D01*
X351417Y742767D01*
X350917Y743183D01*
X350583Y743683D01*
X350500Y744267D01*
X350583Y744850D01*
X350917Y745350D01*
X351417Y745767D01*
X352083Y745933D01*
X352667Y745850D01*
X353083Y745683D01*
X353500Y745350D01*
G01X364700Y742600D02*
Y745933D01*
G01Y745350D02*
X364367Y745683D01*
X363867Y745850D01*
X363283Y745933D01*
X362700Y745767D01*
X362200Y745433D01*
X361867Y744933D01*
X361700Y744267D01*
X361867Y743600D01*
X362200Y743100D01*
X362700Y742767D01*
X363283Y742600D01*
X363867Y742683D01*
X364367Y742933D01*
X364700Y743267D01*
G01X367383Y742600D02*
Y745933D01*
G01Y745100D02*
X367717Y745517D01*
X368217Y745850D01*
X368883Y745933D01*
X369467Y745850D01*
X369967Y745517D01*
X370217Y744933D01*
Y742600D01*
G01X375900Y747600D02*
Y742600D01*
G01Y743350D02*
X375567Y742933D01*
X375067Y742683D01*
X374483Y742600D01*
X373817Y742767D01*
X373317Y743183D01*
X372983Y743683D01*
X372900Y744267D01*
X372983Y744850D01*
X373317Y745350D01*
X373817Y745767D01*
X374483Y745933D01*
X375067Y745850D01*
X375483Y745683D01*
X375900Y745350D01*
G01X383433Y742600D02*
Y747600D01*
X385600Y743433D01*
X387767Y747600D01*
Y742600D01*
G01X389783Y745933D02*
Y743600D01*
X390117Y743017D01*
X390617Y742683D01*
X391200Y742600D01*
X391783Y742683D01*
X392283Y743017D01*
X392617Y743600D01*
G01Y742600D02*
Y745933D01*
G01X396800Y742600D02*
Y747600D01*
G01X402400D02*
Y742600D01*
G01X401233Y745933D02*
X403567D01*
G01X408000D02*
Y742600D01*
G01Y747267D02*
X407833Y747350D01*
Y747517D01*
X408000Y747600D01*
X408167Y747517D01*
Y747350D01*
X408000Y747267D01*
G01X413600Y742600D02*
Y747600D01*
G01X420700Y742600D02*
Y745933D01*
G01Y745350D02*
X420367Y745683D01*
X419867Y745850D01*
X419283Y745933D01*
X418700Y745767D01*
X418200Y745433D01*
X417867Y744933D01*
X417700Y744267D01*
X417867Y743600D01*
X418200Y743100D01*
X418700Y742767D01*
X419283Y742600D01*
X419867Y742683D01*
X420367Y742933D01*
X420700Y743267D01*
G01X423050Y741100D02*
X423550Y740933D01*
X424217Y741100D01*
X424633Y741433D01*
X424967Y741850D01*
X425467Y743183D01*
X426550Y745933D01*
G01X423883D02*
X425467Y743183D01*
G01X429150Y744850D02*
X431817D01*
X431567Y745433D01*
X431150Y745767D01*
X430567Y745933D01*
X429983Y745850D01*
X429483Y745600D01*
X429150Y745017D01*
X428983Y744517D01*
Y744017D01*
X429150Y743517D01*
X429567Y743017D01*
X430067Y742683D01*
X430650Y742600D01*
X431233Y742767D01*
X431817Y743267D01*
G01X434833Y742600D02*
Y745933D01*
G01Y745267D02*
X435250Y745600D01*
X435667Y745850D01*
X436250Y745933D01*
X436667Y745850D01*
X437167Y745600D01*
G01X445533Y742600D02*
Y747600D01*
X447533D01*
X448200Y747350D01*
X448700Y746767D01*
X448867Y746100D01*
X448700Y745433D01*
X448283Y744933D01*
X447533Y744683D01*
X445533D01*
G01X451633Y742600D02*
Y745933D01*
G01Y745267D02*
X452050Y745600D01*
X452467Y745850D01*
X453050Y745933D01*
X453467Y745850D01*
X453967Y745600D01*
G01X458400Y745933D02*
Y742600D01*
G01Y747267D02*
X458233Y747350D01*
Y747517D01*
X458400Y747600D01*
X458567Y747517D01*
Y747350D01*
X458400Y747267D01*
G01X462583Y742600D02*
Y745933D01*
G01Y745100D02*
X462917Y745517D01*
X463417Y745850D01*
X464083Y745933D01*
X464667Y745850D01*
X465167Y745517D01*
X465417Y744933D01*
Y742600D01*
G01X469600Y747600D02*
Y742600D01*
G01X468433Y745933D02*
X470767D01*
G01X473950Y744850D02*
X476617D01*
X476367Y745433D01*
X475950Y745767D01*
X475367Y745933D01*
X474783Y745850D01*
X474283Y745600D01*
X473950Y745017D01*
X473783Y744517D01*
Y744017D01*
X473950Y743517D01*
X474367Y743017D01*
X474867Y742683D01*
X475450Y742600D01*
X476033Y742767D01*
X476617Y743267D01*
G01X482300Y747600D02*
Y742600D01*
G01Y743350D02*
X481967Y742933D01*
X481467Y742683D01*
X480883Y742600D01*
X480217Y742767D01*
X479717Y743183D01*
X479383Y743683D01*
X479300Y744267D01*
X479383Y744850D01*
X479717Y745350D01*
X480217Y745767D01*
X480883Y745933D01*
X481467Y745850D01*
X481883Y745683D01*
X482300Y745350D01*
G01X492667Y745267D02*
X493000Y745517D01*
X493250Y745933D01*
X493417Y746517D01*
X493250Y747017D01*
X492917Y747350D01*
X492333Y747600D01*
X490083D01*
Y742600D01*
X492833D01*
X493417Y742933D01*
X493750Y743433D01*
X493917Y744017D01*
X493750Y744600D01*
X493250Y745100D01*
X492667Y745267D01*
X490083D01*
G01X497600Y742600D02*
X497100Y742683D01*
X496600Y743017D01*
X496267Y743600D01*
X496100Y744267D01*
X496267Y744933D01*
X496600Y745517D01*
X497100Y745850D01*
X497600Y745933D01*
X498100Y745850D01*
X498600Y745517D01*
X498933Y744933D01*
X499017Y744267D01*
X498933Y743600D01*
X498600Y743017D01*
X498100Y742683D01*
X497600Y742600D01*
G01X504700D02*
Y745933D01*
G01Y745350D02*
X504367Y745683D01*
X503867Y745850D01*
X503283Y745933D01*
X502700Y745767D01*
X502200Y745433D01*
X501867Y744933D01*
X501700Y744267D01*
X501867Y743600D01*
X502200Y743100D01*
X502700Y742767D01*
X503283Y742600D01*
X503867Y742683D01*
X504367Y742933D01*
X504700Y743267D01*
G01X507633Y742600D02*
Y745933D01*
G01Y745267D02*
X508050Y745600D01*
X508467Y745850D01*
X509050Y745933D01*
X509467Y745850D01*
X509967Y745600D01*
G01X515900Y747600D02*
Y742600D01*
G01Y743350D02*
X515567Y742933D01*
X515067Y742683D01*
X514483Y742600D01*
X513817Y742767D01*
X513317Y743183D01*
X512983Y743683D01*
X512900Y744267D01*
X512983Y744850D01*
X513317Y745350D01*
X513817Y745767D01*
X514483Y745933D01*
X515067Y745850D01*
X515483Y745683D01*
X515900Y745350D01*
G01X518750Y743183D02*
X519167Y742850D01*
X519750Y742600D01*
X520250D01*
X520750Y742767D01*
X521083Y743017D01*
X521250Y743350D01*
X521167Y743850D01*
X520833Y744100D01*
X519333Y744600D01*
X519000Y745183D01*
X519167Y745600D01*
X519500Y745850D01*
X520000Y745933D01*
X520500Y745850D01*
X521000Y745600D01*
G01X71000Y756600D02*
X73000D01*
G01X72000D02*
Y751600D01*
G01X71000D02*
X73000D01*
G01X75933D02*
Y756600D01*
X77933D01*
X78600Y756350D01*
X79100Y755767D01*
X79267Y755100D01*
X79100Y754433D01*
X78683Y753933D01*
X77933Y753683D01*
X75933D01*
G01X85033Y756183D02*
X84533Y756433D01*
X83950Y756600D01*
X83283D01*
X82533Y756350D01*
X81950Y755933D01*
X81533Y755433D01*
X81200Y754600D01*
X81117Y753850D01*
X81283Y753100D01*
X81533Y752600D01*
X82033Y752100D01*
X82617Y751767D01*
X83200Y751600D01*
X83783D01*
X84367Y751767D01*
X84867Y752017D01*
X85283Y752350D01*
G01X87717Y753267D02*
X89883D01*
G01X94400Y756600D02*
Y751600D01*
G01X92483Y756600D02*
X96317D01*
G01X97833Y751600D02*
Y756600D01*
X100000Y752433D01*
X102167Y756600D01*
Y751600D01*
G01X104517Y753267D02*
X106683D01*
G01X109617Y753683D02*
X110200Y754267D01*
X110700Y754600D01*
X111367Y754767D01*
X111950Y754600D01*
X112367Y754267D01*
X112700Y753767D01*
X112783Y753183D01*
X112700Y752683D01*
X112367Y752183D01*
X111867Y751767D01*
X111283Y751600D01*
X110617Y751767D01*
X110033Y752267D01*
X109700Y753017D01*
X109617Y753850D01*
X109783Y754933D01*
X110033Y755517D01*
X110450Y756100D01*
X111033Y756517D01*
X111617Y756600D01*
X112200Y756433D01*
X112617Y756017D01*
G01X114967Y752350D02*
X115467Y751933D01*
X116050Y751683D01*
X116800Y751600D01*
X117550Y751767D01*
X118133Y752100D01*
X118550Y752683D01*
X118633Y753350D01*
X118467Y754017D01*
X118050Y754433D01*
X117467Y754767D01*
X116883Y754850D01*
X116300Y754767D01*
X115550Y754433D01*
X115800Y756600D01*
X118050D01*
G01X122400D02*
X121733Y756433D01*
X121233Y756017D01*
X120900Y755517D01*
X120650Y754850D01*
X120567Y754100D01*
X120650Y753350D01*
X120900Y752683D01*
X121233Y752183D01*
X121733Y751767D01*
X122400Y751600D01*
X123067Y751767D01*
X123567Y752183D01*
X123900Y752683D01*
X124150Y753350D01*
X124233Y754100D01*
X124150Y754850D01*
X123900Y755517D01*
X123567Y756017D01*
X123067Y756433D01*
X122400Y756600D01*
G01X133600D02*
Y751600D01*
G01X131683Y756600D02*
X135517D01*
G01X137950Y753850D02*
X140617D01*
X140367Y754433D01*
X139950Y754767D01*
X139367Y754933D01*
X138783Y754850D01*
X138283Y754600D01*
X137950Y754017D01*
X137783Y753517D01*
Y753017D01*
X137950Y752517D01*
X138367Y752017D01*
X138867Y751683D01*
X139450Y751600D01*
X140033Y751767D01*
X140617Y752267D01*
G01X143550Y752183D02*
X143967Y751850D01*
X144550Y751600D01*
X145050D01*
X145550Y751767D01*
X145883Y752017D01*
X146050Y752350D01*
X145967Y752850D01*
X145633Y753100D01*
X144133Y753600D01*
X143800Y754183D01*
X143967Y754600D01*
X144300Y754850D01*
X144800Y754933D01*
X145300Y754850D01*
X145800Y754600D01*
G01X150400Y756600D02*
Y751600D01*
G01X149233Y754933D02*
X151567D01*
G01X159433Y751600D02*
Y756600D01*
X161600Y752433D01*
X163767Y756600D01*
Y751600D01*
G01X165950Y753850D02*
X168617D01*
X168367Y754433D01*
X167950Y754767D01*
X167367Y754933D01*
X166783Y754850D01*
X166283Y754600D01*
X165950Y754017D01*
X165783Y753517D01*
Y753017D01*
X165950Y752517D01*
X166367Y752017D01*
X166867Y751683D01*
X167450Y751600D01*
X168033Y751767D01*
X168617Y752267D01*
G01X172800Y756600D02*
Y751600D01*
G01X171633Y754933D02*
X173967D01*
G01X176983Y751600D02*
Y756600D01*
G01Y754183D02*
X177400Y754600D01*
X177817Y754850D01*
X178483Y754933D01*
X178983Y754850D01*
X179567Y754517D01*
X179817Y754017D01*
Y751600D01*
G01X184000D02*
X183500Y751683D01*
X183000Y752017D01*
X182667Y752600D01*
X182500Y753267D01*
X182667Y753933D01*
X183000Y754517D01*
X183500Y754850D01*
X184000Y754933D01*
X184500Y754850D01*
X185000Y754517D01*
X185333Y753933D01*
X185417Y753267D01*
X185333Y752600D01*
X185000Y752017D01*
X184500Y751683D01*
X184000Y751600D01*
G01X191100Y756600D02*
Y751600D01*
G01Y752350D02*
X190767Y751933D01*
X190267Y751683D01*
X189683Y751600D01*
X189017Y751767D01*
X188517Y752183D01*
X188183Y752683D01*
X188100Y753267D01*
X188183Y753850D01*
X188517Y754350D01*
X189017Y754767D01*
X189683Y754933D01*
X190267Y754850D01*
X190683Y754683D01*
X191100Y754350D01*
G01X193950Y752183D02*
X194367Y751850D01*
X194950Y751600D01*
X195450D01*
X195950Y751767D01*
X196283Y752017D01*
X196450Y752350D01*
X196367Y752850D01*
X196033Y753100D01*
X194533Y753600D01*
X194200Y754183D01*
X194367Y754600D01*
X194700Y754850D01*
X195200Y754933D01*
X195700Y754850D01*
X196200Y754600D01*
G01X204233Y751600D02*
Y756600D01*
X206400Y752433D01*
X208567Y756600D01*
Y751600D01*
G01X213500D02*
Y754933D01*
G01Y754350D02*
X213167Y754683D01*
X212667Y754850D01*
X212083Y754933D01*
X211500Y754767D01*
X211000Y754433D01*
X210667Y753933D01*
X210500Y753267D01*
X210667Y752600D01*
X211000Y752100D01*
X211500Y751767D01*
X212083Y751600D01*
X212667Y751683D01*
X213167Y751933D01*
X213500Y752267D01*
G01X216183Y751600D02*
Y754933D01*
G01Y754100D02*
X216517Y754517D01*
X217017Y754850D01*
X217683Y754933D01*
X218267Y754850D01*
X218767Y754517D01*
X219017Y753933D01*
Y751600D01*
G01X221783Y754933D02*
Y752600D01*
X222117Y752017D01*
X222617Y751683D01*
X223200Y751600D01*
X223783Y751683D01*
X224283Y752017D01*
X224617Y752600D01*
G01Y751600D02*
Y754933D01*
G01X230300Y751600D02*
Y754933D01*
G01Y754350D02*
X229967Y754683D01*
X229467Y754850D01*
X228883Y754933D01*
X228300Y754767D01*
X227800Y754433D01*
X227467Y753933D01*
X227300Y753267D01*
X227467Y752600D01*
X227800Y752100D01*
X228300Y751767D01*
X228883Y751600D01*
X229467Y751683D01*
X229967Y751933D01*
X230300Y752267D01*
G01X234400Y751600D02*
Y756600D01*
G01X71000Y765600D02*
X73000D01*
G01X72000D02*
Y760600D01*
G01X71000D02*
X73000D01*
G01X75933D02*
Y765600D01*
X77933D01*
X78600Y765350D01*
X79100Y764767D01*
X79267Y764100D01*
X79100Y763433D01*
X78683Y762933D01*
X77933Y762683D01*
X75933D01*
G01X85033Y765183D02*
X84533Y765433D01*
X83950Y765600D01*
X83283D01*
X82533Y765350D01*
X81950Y764933D01*
X81533Y764433D01*
X81200Y763600D01*
X81117Y762850D01*
X81283Y762100D01*
X81533Y761600D01*
X82033Y761100D01*
X82617Y760767D01*
X83200Y760600D01*
X83783D01*
X84367Y760767D01*
X84867Y761017D01*
X85283Y761350D01*
G01X87717Y762267D02*
X89883D01*
G01X92817Y762683D02*
X93400Y763267D01*
X93900Y763600D01*
X94567Y763767D01*
X95150Y763600D01*
X95567Y763267D01*
X95900Y762767D01*
X95983Y762183D01*
X95900Y761683D01*
X95567Y761183D01*
X95067Y760767D01*
X94483Y760600D01*
X93817Y760767D01*
X93233Y761267D01*
X92900Y762017D01*
X92817Y762850D01*
X92983Y763933D01*
X93233Y764517D01*
X93650Y765100D01*
X94233Y765517D01*
X94817Y765600D01*
X95400Y765433D01*
X95817Y765017D01*
G01X100000Y765600D02*
X99333Y765433D01*
X98833Y765017D01*
X98500Y764517D01*
X98250Y763850D01*
X98167Y763100D01*
X98250Y762350D01*
X98500Y761683D01*
X98833Y761183D01*
X99333Y760767D01*
X100000Y760600D01*
X100667Y760767D01*
X101167Y761183D01*
X101500Y761683D01*
X101750Y762350D01*
X101833Y763100D01*
X101750Y763850D01*
X101500Y764517D01*
X101167Y765017D01*
X100667Y765433D01*
X100000Y765600D01*
G01X105600Y760600D02*
Y765600D01*
X104600Y764600D01*
G01Y760600D02*
X106600D01*
G01X109617Y762683D02*
X110200Y763267D01*
X110700Y763600D01*
X111367Y763767D01*
X111950Y763600D01*
X112367Y763267D01*
X112700Y762767D01*
X112783Y762183D01*
X112700Y761683D01*
X112367Y761183D01*
X111867Y760767D01*
X111283Y760600D01*
X110617Y760767D01*
X110033Y761267D01*
X109700Y762017D01*
X109617Y762850D01*
X109783Y763933D01*
X110033Y764517D01*
X110450Y765100D01*
X111033Y765517D01*
X111617Y765600D01*
X112200Y765433D01*
X112617Y765017D01*
G01X122400Y760600D02*
X121733Y760683D01*
X121150Y761017D01*
X120650Y761517D01*
X120317Y762100D01*
X120150Y762767D01*
Y763433D01*
X120317Y764100D01*
X120650Y764683D01*
X121150Y765183D01*
X121733Y765517D01*
X122400Y765600D01*
X123067Y765517D01*
X123650Y765183D01*
X124150Y764683D01*
X124483Y764100D01*
X124650Y763433D01*
Y762767D01*
X124483Y762100D01*
X124150Y761517D01*
X123650Y761017D01*
X123067Y760683D01*
X122400Y760600D01*
G01X123067Y761933D02*
X124067Y760600D01*
G01X126583Y763933D02*
Y761600D01*
X126917Y761017D01*
X127417Y760683D01*
X128000Y760600D01*
X128583Y760683D01*
X129083Y761017D01*
X129417Y761600D01*
G01Y760600D02*
Y763933D01*
G01X135100Y760600D02*
Y763933D01*
G01Y763350D02*
X134767Y763683D01*
X134267Y763850D01*
X133683Y763933D01*
X133100Y763767D01*
X132600Y763433D01*
X132267Y762933D01*
X132100Y762267D01*
X132267Y761600D01*
X132600Y761100D01*
X133100Y760767D01*
X133683Y760600D01*
X134267Y760683D01*
X134767Y760933D01*
X135100Y761267D01*
G01X139200Y760600D02*
Y765600D01*
G01X144800Y763933D02*
Y760600D01*
G01Y765267D02*
X144633Y765350D01*
Y765517D01*
X144800Y765600D01*
X144967Y765517D01*
Y765350D01*
X144800Y765267D01*
G01X149900Y760600D02*
Y764850D01*
X150067Y765267D01*
X150400Y765517D01*
X150900Y765600D01*
X151400Y765433D01*
X151650Y765017D01*
G01X150650Y763600D02*
X148983D01*
G01X156000Y763933D02*
Y760600D01*
G01Y765267D02*
X155833Y765350D01*
Y765517D01*
X156000Y765600D01*
X156167Y765517D01*
Y765350D01*
X156000Y765267D01*
G01X162933Y763517D02*
X162350Y763850D01*
X161850Y763933D01*
X161183Y763767D01*
X160683Y763433D01*
X160350Y762850D01*
X160267Y762267D01*
X160350Y761683D01*
X160683Y761183D01*
X161183Y760767D01*
X161850Y760600D01*
X162433Y760767D01*
X162933Y761100D01*
G01X168700Y760600D02*
Y763933D01*
G01Y763350D02*
X168367Y763683D01*
X167867Y763850D01*
X167283Y763933D01*
X166700Y763767D01*
X166200Y763433D01*
X165867Y762933D01*
X165700Y762267D01*
X165867Y761600D01*
X166200Y761100D01*
X166700Y760767D01*
X167283Y760600D01*
X167867Y760683D01*
X168367Y760933D01*
X168700Y761267D01*
G01X172800Y765600D02*
Y760600D01*
G01X171633Y763933D02*
X173967D01*
G01X178400D02*
Y760600D01*
G01Y765267D02*
X178233Y765350D01*
Y765517D01*
X178400Y765600D01*
X178567Y765517D01*
Y765350D01*
X178400Y765267D01*
G01X184000Y760600D02*
X183500Y760683D01*
X183000Y761017D01*
X182667Y761600D01*
X182500Y762267D01*
X182667Y762933D01*
X183000Y763517D01*
X183500Y763850D01*
X184000Y763933D01*
X184500Y763850D01*
X185000Y763517D01*
X185333Y762933D01*
X185417Y762267D01*
X185333Y761600D01*
X185000Y761017D01*
X184500Y760683D01*
X184000Y760600D01*
G01X188183D02*
Y763933D01*
G01Y763100D02*
X188517Y763517D01*
X189017Y763850D01*
X189683Y763933D01*
X190267Y763850D01*
X190767Y763517D01*
X191017Y762933D01*
Y760600D01*
G01X203300Y758933D02*
X199133Y763933D01*
Y764767D01*
X199967Y765600D01*
X200800D01*
X201633Y764767D01*
Y763933D01*
X200800Y763100D01*
X199133Y762267D01*
X198300Y761433D01*
Y759767D01*
X199133Y758933D01*
X201633D01*
X203300Y760600D01*
G01X210333D02*
Y765600D01*
X212333D01*
X213000Y765350D01*
X213500Y764767D01*
X213667Y764100D01*
X213500Y763433D01*
X213083Y762933D01*
X212333Y762683D01*
X210333D01*
G01X216350Y762850D02*
X219017D01*
X218767Y763433D01*
X218350Y763767D01*
X217767Y763933D01*
X217183Y763850D01*
X216683Y763600D01*
X216350Y763017D01*
X216183Y762517D01*
Y762017D01*
X216350Y761517D01*
X216767Y761017D01*
X217267Y760683D01*
X217850Y760600D01*
X218433Y760767D01*
X219017Y761267D01*
G01X222033Y760600D02*
Y763933D01*
G01Y763267D02*
X222450Y763600D01*
X222867Y763850D01*
X223450Y763933D01*
X223867Y763850D01*
X224367Y763600D01*
G01X228300Y760600D02*
Y764850D01*
X228467Y765267D01*
X228800Y765517D01*
X229300Y765600D01*
X229800Y765433D01*
X230050Y765017D01*
G01X229050Y763600D02*
X227383D01*
G01X234400Y760600D02*
X233900Y760683D01*
X233400Y761017D01*
X233067Y761600D01*
X232900Y762267D01*
X233067Y762933D01*
X233400Y763517D01*
X233900Y763850D01*
X234400Y763933D01*
X234900Y763850D01*
X235400Y763517D01*
X235733Y762933D01*
X235817Y762267D01*
X235733Y761600D01*
X235400Y761017D01*
X234900Y760683D01*
X234400Y760600D01*
G01X238833D02*
Y763933D01*
G01Y763267D02*
X239250Y763600D01*
X239667Y763850D01*
X240250Y763933D01*
X240667Y763850D01*
X241167Y763600D01*
G01X243100Y760600D02*
Y763933D01*
G01Y763017D02*
X243350Y763433D01*
X243767Y763767D01*
X244350Y763933D01*
X244933Y763767D01*
X245350Y763433D01*
X245600Y763017D01*
Y760600D01*
G01Y763017D02*
X245850Y763433D01*
X246267Y763767D01*
X246850Y763933D01*
X247433Y763767D01*
X247850Y763433D01*
X248100Y762933D01*
Y760600D01*
G01X252700D02*
Y763933D01*
G01Y763350D02*
X252367Y763683D01*
X251867Y763850D01*
X251283Y763933D01*
X250700Y763767D01*
X250200Y763433D01*
X249867Y762933D01*
X249700Y762267D01*
X249867Y761600D01*
X250200Y761100D01*
X250700Y760767D01*
X251283Y760600D01*
X251867Y760683D01*
X252367Y760933D01*
X252700Y761267D01*
G01X255383Y760600D02*
Y763933D01*
G01Y763100D02*
X255717Y763517D01*
X256217Y763850D01*
X256883Y763933D01*
X257467Y763850D01*
X257967Y763517D01*
X258217Y762933D01*
Y760600D01*
G01X263733Y763517D02*
X263150Y763850D01*
X262650Y763933D01*
X261983Y763767D01*
X261483Y763433D01*
X261150Y762850D01*
X261067Y762267D01*
X261150Y761683D01*
X261483Y761183D01*
X261983Y760767D01*
X262650Y760600D01*
X263233Y760767D01*
X263733Y761100D01*
G01X266750Y762850D02*
X269417D01*
X269167Y763433D01*
X268750Y763767D01*
X268167Y763933D01*
X267583Y763850D01*
X267083Y763600D01*
X266750Y763017D01*
X266583Y762517D01*
Y762017D01*
X266750Y761517D01*
X267167Y761017D01*
X267667Y760683D01*
X268250Y760600D01*
X268833Y760767D01*
X269417Y761267D01*
G01X277450D02*
X278117Y760850D01*
X278867Y760600D01*
X279533D01*
X280200Y760850D01*
X280700Y761267D01*
X280950Y761850D01*
X280783Y762433D01*
X280367Y762933D01*
X279617Y763267D01*
X278617Y763433D01*
X278033Y763767D01*
X277783Y764350D01*
X277950Y764933D01*
X278367Y765350D01*
X278950Y765600D01*
X279533D01*
X280117Y765433D01*
X280617Y765017D01*
G01X283300Y758933D02*
Y763933D01*
G01Y763183D02*
X283717Y763600D01*
X284133Y763850D01*
X284800Y763933D01*
X285383Y763850D01*
X285967Y763433D01*
X286217Y762850D01*
X286300Y762267D01*
X286217Y761683D01*
X285967Y761100D01*
X285467Y760767D01*
X284800Y760600D01*
X284217Y760683D01*
X283633Y760933D01*
X283300Y761267D01*
G01X289150Y762850D02*
X291817D01*
X291567Y763433D01*
X291150Y763767D01*
X290567Y763933D01*
X289983Y763850D01*
X289483Y763600D01*
X289150Y763017D01*
X288983Y762517D01*
Y762017D01*
X289150Y761517D01*
X289567Y761017D01*
X290067Y760683D01*
X290650Y760600D01*
X291233Y760767D01*
X291817Y761267D01*
G01X297333Y763517D02*
X296750Y763850D01*
X296250Y763933D01*
X295583Y763767D01*
X295083Y763433D01*
X294750Y762850D01*
X294667Y762267D01*
X294750Y761683D01*
X295083Y761183D01*
X295583Y760767D01*
X296250Y760600D01*
X296833Y760767D01*
X297333Y761100D01*
G01X301600Y763933D02*
Y760600D01*
G01Y765267D02*
X301433Y765350D01*
Y765517D01*
X301600Y765600D01*
X301767Y765517D01*
Y765350D01*
X301600Y765267D01*
G01X306700Y760600D02*
Y764850D01*
X306867Y765267D01*
X307200Y765517D01*
X307700Y765600D01*
X308200Y765433D01*
X308450Y765017D01*
G01X307450Y763600D02*
X305783D01*
G01X312800Y763933D02*
Y760600D01*
G01Y765267D02*
X312633Y765350D01*
Y765517D01*
X312800Y765600D01*
X312967Y765517D01*
Y765350D01*
X312800Y765267D01*
G01X319733Y763517D02*
X319150Y763850D01*
X318650Y763933D01*
X317983Y763767D01*
X317483Y763433D01*
X317150Y762850D01*
X317067Y762267D01*
X317150Y761683D01*
X317483Y761183D01*
X317983Y760767D01*
X318650Y760600D01*
X319233Y760767D01*
X319733Y761100D01*
G01X325500Y760600D02*
Y763933D01*
G01Y763350D02*
X325167Y763683D01*
X324667Y763850D01*
X324083Y763933D01*
X323500Y763767D01*
X323000Y763433D01*
X322667Y762933D01*
X322500Y762267D01*
X322667Y761600D01*
X323000Y761100D01*
X323500Y760767D01*
X324083Y760600D01*
X324667Y760683D01*
X325167Y760933D01*
X325500Y761267D01*
G01X329600Y765600D02*
Y760600D01*
G01X328433Y763933D02*
X330767D01*
G01X335200D02*
Y760600D01*
G01Y765267D02*
X335033Y765350D01*
Y765517D01*
X335200Y765600D01*
X335367Y765517D01*
Y765350D01*
X335200Y765267D01*
G01X340800Y760600D02*
X340300Y760683D01*
X339800Y761017D01*
X339467Y761600D01*
X339300Y762267D01*
X339467Y762933D01*
X339800Y763517D01*
X340300Y763850D01*
X340800Y763933D01*
X341300Y763850D01*
X341800Y763517D01*
X342133Y762933D01*
X342217Y762267D01*
X342133Y761600D01*
X341800Y761017D01*
X341300Y760683D01*
X340800Y760600D01*
G01X344983D02*
Y763933D01*
G01Y763100D02*
X345317Y763517D01*
X345817Y763850D01*
X346483Y763933D01*
X347067Y763850D01*
X347567Y763517D01*
X347817Y762933D01*
Y760600D01*
G01X357100D02*
Y764850D01*
X357267Y765267D01*
X357600Y765517D01*
X358100Y765600D01*
X358600Y765433D01*
X358850Y765017D01*
G01X357850Y763600D02*
X356183D01*
G01X363200Y760600D02*
X362700Y760683D01*
X362200Y761017D01*
X361867Y761600D01*
X361700Y762267D01*
X361867Y762933D01*
X362200Y763517D01*
X362700Y763850D01*
X363200Y763933D01*
X363700Y763850D01*
X364200Y763517D01*
X364533Y762933D01*
X364617Y762267D01*
X364533Y761600D01*
X364200Y761017D01*
X363700Y760683D01*
X363200Y760600D01*
G01X367633D02*
Y763933D01*
G01Y763267D02*
X368050Y763600D01*
X368467Y763850D01*
X369050Y763933D01*
X369467Y763850D01*
X369967Y763600D01*
G01X378250Y760600D02*
Y765600D01*
G01X381750D02*
Y760600D01*
G01Y763100D02*
X378250D01*
G01X385600Y763933D02*
Y760600D01*
G01Y765267D02*
X385433Y765350D01*
Y765517D01*
X385600Y765600D01*
X385767Y765517D01*
Y765350D01*
X385600Y765267D01*
G01X390033Y759350D02*
X390617Y759017D01*
X391283Y758933D01*
X391867Y759017D01*
X392367Y759433D01*
X392700Y760017D01*
Y763933D01*
G01Y763267D02*
X392367Y763600D01*
X391867Y763850D01*
X391283Y763933D01*
X390617Y763767D01*
X390200Y763433D01*
X389867Y762850D01*
X389700Y762267D01*
X389783Y761767D01*
X390117Y761183D01*
X390617Y760767D01*
X391283Y760600D01*
X391783Y760683D01*
X392367Y761017D01*
X392700Y761350D01*
G01X395383Y760600D02*
Y765600D01*
G01Y763183D02*
X395800Y763600D01*
X396217Y763850D01*
X396883Y763933D01*
X397383Y763850D01*
X397967Y763517D01*
X398217Y763017D01*
Y760600D01*
G01X406167D02*
Y765600D01*
X407833D01*
X408500Y765350D01*
X409000Y765017D01*
X409417Y764517D01*
X409750Y763933D01*
X409833Y763100D01*
X409750Y762267D01*
X409417Y761683D01*
X409000Y761183D01*
X408500Y760850D01*
X407833Y760600D01*
X406167D01*
G01X412350Y762850D02*
X415017D01*
X414767Y763433D01*
X414350Y763767D01*
X413767Y763933D01*
X413183Y763850D01*
X412683Y763600D01*
X412350Y763017D01*
X412183Y762517D01*
Y762017D01*
X412350Y761517D01*
X412767Y761017D01*
X413267Y760683D01*
X413850Y760600D01*
X414433Y760767D01*
X415017Y761267D01*
G01X417783Y760600D02*
Y763933D01*
G01Y763100D02*
X418117Y763517D01*
X418617Y763850D01*
X419283Y763933D01*
X419867Y763850D01*
X420367Y763517D01*
X420617Y762933D01*
Y760600D01*
G01X423550Y761183D02*
X423967Y760850D01*
X424550Y760600D01*
X425050D01*
X425550Y760767D01*
X425883Y761017D01*
X426050Y761350D01*
X425967Y761850D01*
X425633Y762100D01*
X424133Y762600D01*
X423800Y763183D01*
X423967Y763600D01*
X424300Y763850D01*
X424800Y763933D01*
X425300Y763850D01*
X425800Y763600D01*
G01X430400Y763933D02*
Y760600D01*
G01Y765267D02*
X430233Y765350D01*
Y765517D01*
X430400Y765600D01*
X430567Y765517D01*
Y765350D01*
X430400Y765267D01*
G01X436000Y765600D02*
Y760600D01*
G01X434833Y763933D02*
X437167D01*
G01X439850Y759100D02*
X440350Y758933D01*
X441017Y759100D01*
X441433Y759433D01*
X441767Y759850D01*
X442267Y761183D01*
X443350Y763933D01*
G01X440683D02*
X442267Y761183D01*
G01X451800Y765600D02*
X453800D01*
G01X452800D02*
Y760600D01*
G01X451800D02*
X453800D01*
G01X456983D02*
Y763933D01*
G01Y763100D02*
X457317Y763517D01*
X457817Y763850D01*
X458483Y763933D01*
X459067Y763850D01*
X459567Y763517D01*
X459817Y762933D01*
Y760600D01*
G01X464000Y765600D02*
Y760600D01*
G01X462833Y763933D02*
X465167D01*
G01X468350Y762850D02*
X471017D01*
X470767Y763433D01*
X470350Y763767D01*
X469767Y763933D01*
X469183Y763850D01*
X468683Y763600D01*
X468350Y763017D01*
X468183Y762517D01*
Y762017D01*
X468350Y761517D01*
X468767Y761017D01*
X469267Y760683D01*
X469850Y760600D01*
X470433Y760767D01*
X471017Y761267D01*
G01X474033Y760600D02*
Y763933D01*
G01Y763267D02*
X474450Y763600D01*
X474867Y763850D01*
X475450Y763933D01*
X475867Y763850D01*
X476367Y763600D01*
G01X482133Y763517D02*
X481550Y763850D01*
X481050Y763933D01*
X480383Y763767D01*
X479883Y763433D01*
X479550Y762850D01*
X479467Y762267D01*
X479550Y761683D01*
X479883Y761183D01*
X480383Y760767D01*
X481050Y760600D01*
X481633Y760767D01*
X482133Y761100D01*
G01X486400Y760600D02*
X485900Y760683D01*
X485400Y761017D01*
X485067Y761600D01*
X484900Y762267D01*
X485067Y762933D01*
X485400Y763517D01*
X485900Y763850D01*
X486400Y763933D01*
X486900Y763850D01*
X487400Y763517D01*
X487733Y762933D01*
X487817Y762267D01*
X487733Y761600D01*
X487400Y761017D01*
X486900Y760683D01*
X486400Y760600D01*
G01X490583D02*
Y763933D01*
G01Y763100D02*
X490917Y763517D01*
X491417Y763850D01*
X492083Y763933D01*
X492667Y763850D01*
X493167Y763517D01*
X493417Y762933D01*
Y760600D01*
G01X496183D02*
Y763933D01*
G01Y763100D02*
X496517Y763517D01*
X497017Y763850D01*
X497683Y763933D01*
X498267Y763850D01*
X498767Y763517D01*
X499017Y762933D01*
Y760600D01*
G01X501950Y762850D02*
X504617D01*
X504367Y763433D01*
X503950Y763767D01*
X503367Y763933D01*
X502783Y763850D01*
X502283Y763600D01*
X501950Y763017D01*
X501783Y762517D01*
Y762017D01*
X501950Y761517D01*
X502367Y761017D01*
X502867Y760683D01*
X503450Y760600D01*
X504033Y760767D01*
X504617Y761267D01*
G01X510133Y763517D02*
X509550Y763850D01*
X509050Y763933D01*
X508383Y763767D01*
X507883Y763433D01*
X507550Y762850D01*
X507467Y762267D01*
X507550Y761683D01*
X507883Y761183D01*
X508383Y760767D01*
X509050Y760600D01*
X509633Y760767D01*
X510133Y761100D01*
G01X514400Y765600D02*
Y760600D01*
G01X513233Y763933D02*
X515567D01*
G01X519583Y758933D02*
X518750Y759767D01*
X518333Y760600D01*
Y763933D01*
X518750Y764767D01*
X519583Y765600D01*
G01X523850Y760600D02*
Y765600D01*
G01X527350D02*
Y760600D01*
G01Y763100D02*
X523850D01*
G01X529367Y760600D02*
Y765600D01*
X531033D01*
X531700Y765350D01*
X532200Y765017D01*
X532617Y764517D01*
X532950Y763933D01*
X533033Y763100D01*
X532950Y762267D01*
X532617Y761683D01*
X532200Y761183D01*
X531700Y760850D01*
X531033Y760600D01*
X529367D01*
G01X535800Y765600D02*
X537800D01*
G01X536800D02*
Y760600D01*
G01X535800D02*
X537800D01*
G01X542817Y758933D02*
X543650Y759767D01*
X544067Y760600D01*
Y763933D01*
X543650Y764767D01*
X542817Y765600D01*
G01X551933D02*
Y760600D01*
X555267D01*
G01X560700D02*
Y763933D01*
G01Y763350D02*
X560367Y763683D01*
X559867Y763850D01*
X559283Y763933D01*
X558700Y763767D01*
X558200Y763433D01*
X557867Y762933D01*
X557700Y762267D01*
X557867Y761600D01*
X558200Y761100D01*
X558700Y760767D01*
X559283Y760600D01*
X559867Y760683D01*
X560367Y760933D01*
X560700Y761267D01*
G01X563050Y759100D02*
X563550Y758933D01*
X564217Y759100D01*
X564633Y759433D01*
X564967Y759850D01*
X565467Y761183D01*
X566550Y763933D01*
G01X563883D02*
X565467Y761183D01*
G01X569150Y762850D02*
X571817D01*
X571567Y763433D01*
X571150Y763767D01*
X570567Y763933D01*
X569983Y763850D01*
X569483Y763600D01*
X569150Y763017D01*
X568983Y762517D01*
Y762017D01*
X569150Y761517D01*
X569567Y761017D01*
X570067Y760683D01*
X570650Y760600D01*
X571233Y760767D01*
X571817Y761267D01*
G01X574833Y760600D02*
Y763933D01*
G01Y763267D02*
X575250Y763600D01*
X575667Y763850D01*
X576250Y763933D01*
X576667Y763850D01*
X577167Y763600D01*
G01X580350Y761183D02*
X580767Y760850D01*
X581350Y760600D01*
X581850D01*
X582350Y760767D01*
X582683Y761017D01*
X582850Y761350D01*
X582767Y761850D01*
X582433Y762100D01*
X580933Y762600D01*
X580600Y763183D01*
X580767Y763600D01*
X581100Y763850D01*
X581600Y763933D01*
X582100Y763850D01*
X582600Y763600D01*
G01X592800Y760600D02*
X592300Y760683D01*
X591800Y761017D01*
X591467Y761600D01*
X591300Y762267D01*
X591467Y762933D01*
X591800Y763517D01*
X592300Y763850D01*
X592800Y763933D01*
X593300Y763850D01*
X593800Y763517D01*
X594133Y762933D01*
X594217Y762267D01*
X594133Y761600D01*
X593800Y761017D01*
X593300Y760683D01*
X592800Y760600D01*
G01X597233D02*
Y763933D01*
G01Y763267D02*
X597650Y763600D01*
X598067Y763850D01*
X598650Y763933D01*
X599067Y763850D01*
X599567Y763600D01*
G01X610267Y763267D02*
X610600Y763517D01*
X610850Y763933D01*
X611017Y764517D01*
X610850Y765017D01*
X610517Y765350D01*
X609933Y765600D01*
X607683D01*
Y760600D01*
X610433D01*
X611017Y760933D01*
X611350Y761433D01*
X611517Y762017D01*
X611350Y762600D01*
X610850Y763100D01*
X610267Y763267D01*
X607683D01*
G01X615200Y760600D02*
X614700Y760683D01*
X614200Y761017D01*
X613867Y761600D01*
X613700Y762267D01*
X613867Y762933D01*
X614200Y763517D01*
X614700Y763850D01*
X615200Y763933D01*
X615700Y763850D01*
X616200Y763517D01*
X616533Y762933D01*
X616617Y762267D01*
X616533Y761600D01*
X616200Y761017D01*
X615700Y760683D01*
X615200Y760600D01*
G01X622300D02*
Y763933D01*
G01Y763350D02*
X621967Y763683D01*
X621467Y763850D01*
X620883Y763933D01*
X620300Y763767D01*
X619800Y763433D01*
X619467Y762933D01*
X619300Y762267D01*
X619467Y761600D01*
X619800Y761100D01*
X620300Y760767D01*
X620883Y760600D01*
X621467Y760683D01*
X621967Y760933D01*
X622300Y761267D01*
G01X625233Y760600D02*
Y763933D01*
G01Y763267D02*
X625650Y763600D01*
X626067Y763850D01*
X626650Y763933D01*
X627067Y763850D01*
X627567Y763600D01*
G01X633500Y765600D02*
Y760600D01*
G01Y761350D02*
X633167Y760933D01*
X632667Y760683D01*
X632083Y760600D01*
X631417Y760767D01*
X630917Y761183D01*
X630583Y761683D01*
X630500Y762267D01*
X630583Y762850D01*
X630917Y763350D01*
X631417Y763767D01*
X632083Y763933D01*
X632667Y763850D01*
X633083Y763683D01*
X633500Y763350D01*
G01X636350Y761183D02*
X636767Y760850D01*
X637350Y760600D01*
X637850D01*
X638350Y760767D01*
X638683Y761017D01*
X638850Y761350D01*
X638767Y761850D01*
X638433Y762100D01*
X636933Y762600D01*
X636600Y763183D01*
X636767Y763600D01*
X637100Y763850D01*
X637600Y763933D01*
X638100Y763850D01*
X638600Y763600D01*
G01X643617Y758933D02*
X644450Y759767D01*
X644867Y760600D01*
Y763933D01*
X644450Y764767D01*
X643617Y765600D01*
G01X71000Y774600D02*
X73000D01*
G01X72000D02*
Y769600D01*
G01X71000D02*
X73000D01*
G01X75933D02*
Y774600D01*
X77933D01*
X78600Y774350D01*
X79100Y773767D01*
X79267Y773100D01*
X79100Y772433D01*
X78683Y771933D01*
X77933Y771683D01*
X75933D01*
G01X85033Y774183D02*
X84533Y774433D01*
X83950Y774600D01*
X83283D01*
X82533Y774350D01*
X81950Y773933D01*
X81533Y773433D01*
X81200Y772600D01*
X81117Y771850D01*
X81283Y771100D01*
X81533Y770600D01*
X82033Y770100D01*
X82617Y769767D01*
X83200Y769600D01*
X83783D01*
X84367Y769767D01*
X84867Y770017D01*
X85283Y770350D01*
G01X87717Y771267D02*
X89883D01*
G01X92817Y771683D02*
X93400Y772267D01*
X93900Y772600D01*
X94567Y772767D01*
X95150Y772600D01*
X95567Y772267D01*
X95900Y771767D01*
X95983Y771183D01*
X95900Y770683D01*
X95567Y770183D01*
X95067Y769767D01*
X94483Y769600D01*
X93817Y769767D01*
X93233Y770267D01*
X92900Y771017D01*
X92817Y771850D01*
X92983Y772933D01*
X93233Y773517D01*
X93650Y774100D01*
X94233Y774517D01*
X94817Y774600D01*
X95400Y774433D01*
X95817Y774017D01*
G01X100000Y774600D02*
X99333Y774433D01*
X98833Y774017D01*
X98500Y773517D01*
X98250Y772850D01*
X98167Y772100D01*
X98250Y771350D01*
X98500Y770683D01*
X98833Y770183D01*
X99333Y769767D01*
X100000Y769600D01*
X100667Y769767D01*
X101167Y770183D01*
X101500Y770683D01*
X101750Y771350D01*
X101833Y772100D01*
X101750Y772850D01*
X101500Y773517D01*
X101167Y774017D01*
X100667Y774433D01*
X100000Y774600D01*
G01X105600Y769600D02*
Y774600D01*
X104600Y773600D01*
G01Y769600D02*
X106600D01*
G01X109617Y773767D02*
X110117Y774267D01*
X110700Y774517D01*
X111367Y774600D01*
X112200Y774433D01*
X112783Y774017D01*
X112950Y773517D01*
X112867Y773017D01*
X112533Y772600D01*
X110867Y771767D01*
X110117Y771183D01*
X109617Y770350D01*
X109450Y769600D01*
X112950D01*
G01X122400D02*
X121733Y769683D01*
X121150Y770017D01*
X120650Y770517D01*
X120317Y771100D01*
X120150Y771767D01*
Y772433D01*
X120317Y773100D01*
X120650Y773683D01*
X121150Y774183D01*
X121733Y774517D01*
X122400Y774600D01*
X123067Y774517D01*
X123650Y774183D01*
X124150Y773683D01*
X124483Y773100D01*
X124650Y772433D01*
Y771767D01*
X124483Y771100D01*
X124150Y770517D01*
X123650Y770017D01*
X123067Y769683D01*
X122400Y769600D01*
G01X123067Y770933D02*
X124067Y769600D01*
G01X126583Y772933D02*
Y770600D01*
X126917Y770017D01*
X127417Y769683D01*
X128000Y769600D01*
X128583Y769683D01*
X129083Y770017D01*
X129417Y770600D01*
G01Y769600D02*
Y772933D01*
G01X135100Y769600D02*
Y772933D01*
G01Y772350D02*
X134767Y772683D01*
X134267Y772850D01*
X133683Y772933D01*
X133100Y772767D01*
X132600Y772433D01*
X132267Y771933D01*
X132100Y771267D01*
X132267Y770600D01*
X132600Y770100D01*
X133100Y769767D01*
X133683Y769600D01*
X134267Y769683D01*
X134767Y769933D01*
X135100Y770267D01*
G01X139200Y769600D02*
Y774600D01*
G01X144800Y772933D02*
Y769600D01*
G01Y774267D02*
X144633Y774350D01*
Y774517D01*
X144800Y774600D01*
X144967Y774517D01*
Y774350D01*
X144800Y774267D01*
G01X149900Y769600D02*
Y773850D01*
X150067Y774267D01*
X150400Y774517D01*
X150900Y774600D01*
X151400Y774433D01*
X151650Y774017D01*
G01X150650Y772600D02*
X148983D01*
G01X156000Y772933D02*
Y769600D01*
G01Y774267D02*
X155833Y774350D01*
Y774517D01*
X156000Y774600D01*
X156167Y774517D01*
Y774350D01*
X156000Y774267D01*
G01X162933Y772517D02*
X162350Y772850D01*
X161850Y772933D01*
X161183Y772767D01*
X160683Y772433D01*
X160350Y771850D01*
X160267Y771267D01*
X160350Y770683D01*
X160683Y770183D01*
X161183Y769767D01*
X161850Y769600D01*
X162433Y769767D01*
X162933Y770100D01*
G01X168700Y769600D02*
Y772933D01*
G01Y772350D02*
X168367Y772683D01*
X167867Y772850D01*
X167283Y772933D01*
X166700Y772767D01*
X166200Y772433D01*
X165867Y771933D01*
X165700Y771267D01*
X165867Y770600D01*
X166200Y770100D01*
X166700Y769767D01*
X167283Y769600D01*
X167867Y769683D01*
X168367Y769933D01*
X168700Y770267D01*
G01X172800Y774600D02*
Y769600D01*
G01X171633Y772933D02*
X173967D01*
G01X178400D02*
Y769600D01*
G01Y774267D02*
X178233Y774350D01*
Y774517D01*
X178400Y774600D01*
X178567Y774517D01*
Y774350D01*
X178400Y774267D01*
G01X184000Y769600D02*
X183500Y769683D01*
X183000Y770017D01*
X182667Y770600D01*
X182500Y771267D01*
X182667Y771933D01*
X183000Y772517D01*
X183500Y772850D01*
X184000Y772933D01*
X184500Y772850D01*
X185000Y772517D01*
X185333Y771933D01*
X185417Y771267D01*
X185333Y770600D01*
X185000Y770017D01*
X184500Y769683D01*
X184000Y769600D01*
G01X188183D02*
Y772933D01*
G01Y772100D02*
X188517Y772517D01*
X189017Y772850D01*
X189683Y772933D01*
X190267Y772850D01*
X190767Y772517D01*
X191017Y771933D01*
Y769600D01*
G01X202300D02*
Y772933D01*
G01Y772350D02*
X201967Y772683D01*
X201467Y772850D01*
X200883Y772933D01*
X200300Y772767D01*
X199800Y772433D01*
X199467Y771933D01*
X199300Y771267D01*
X199467Y770600D01*
X199800Y770100D01*
X200300Y769767D01*
X200883Y769600D01*
X201467Y769683D01*
X201967Y769933D01*
X202300Y770267D01*
G01X204983Y769600D02*
Y772933D01*
G01Y772100D02*
X205317Y772517D01*
X205817Y772850D01*
X206483Y772933D01*
X207067Y772850D01*
X207567Y772517D01*
X207817Y771933D01*
Y769600D01*
G01X213500Y774600D02*
Y769600D01*
G01Y770350D02*
X213167Y769933D01*
X212667Y769683D01*
X212083Y769600D01*
X211417Y769767D01*
X210917Y770183D01*
X210583Y770683D01*
X210500Y771267D01*
X210583Y771850D01*
X210917Y772350D01*
X211417Y772767D01*
X212083Y772933D01*
X212667Y772850D01*
X213083Y772683D01*
X213500Y772350D01*
G01X221533Y769600D02*
Y774600D01*
X223533D01*
X224200Y774350D01*
X224700Y773767D01*
X224867Y773100D01*
X224700Y772433D01*
X224283Y771933D01*
X223533Y771683D01*
X221533D01*
G01X227550Y771850D02*
X230217D01*
X229967Y772433D01*
X229550Y772767D01*
X228967Y772933D01*
X228383Y772850D01*
X227883Y772600D01*
X227550Y772017D01*
X227383Y771517D01*
Y771017D01*
X227550Y770517D01*
X227967Y770017D01*
X228467Y769683D01*
X229050Y769600D01*
X229633Y769767D01*
X230217Y770267D01*
G01X233233Y769600D02*
Y772933D01*
G01Y772267D02*
X233650Y772600D01*
X234067Y772850D01*
X234650Y772933D01*
X235067Y772850D01*
X235567Y772600D01*
G01X239500Y769600D02*
Y773850D01*
X239667Y774267D01*
X240000Y774517D01*
X240500Y774600D01*
X241000Y774433D01*
X241250Y774017D01*
G01X240250Y772600D02*
X238583D01*
G01X245600Y769600D02*
X245100Y769683D01*
X244600Y770017D01*
X244267Y770600D01*
X244100Y771267D01*
X244267Y771933D01*
X244600Y772517D01*
X245100Y772850D01*
X245600Y772933D01*
X246100Y772850D01*
X246600Y772517D01*
X246933Y771933D01*
X247017Y771267D01*
X246933Y770600D01*
X246600Y770017D01*
X246100Y769683D01*
X245600Y769600D01*
G01X250033D02*
Y772933D01*
G01Y772267D02*
X250450Y772600D01*
X250867Y772850D01*
X251450Y772933D01*
X251867Y772850D01*
X252367Y772600D01*
G01X254300Y769600D02*
Y772933D01*
G01Y772017D02*
X254550Y772433D01*
X254967Y772767D01*
X255550Y772933D01*
X256133Y772767D01*
X256550Y772433D01*
X256800Y772017D01*
Y769600D01*
G01Y772017D02*
X257050Y772433D01*
X257467Y772767D01*
X258050Y772933D01*
X258633Y772767D01*
X259050Y772433D01*
X259300Y771933D01*
Y769600D01*
G01X263900D02*
Y772933D01*
G01Y772350D02*
X263567Y772683D01*
X263067Y772850D01*
X262483Y772933D01*
X261900Y772767D01*
X261400Y772433D01*
X261067Y771933D01*
X260900Y771267D01*
X261067Y770600D01*
X261400Y770100D01*
X261900Y769767D01*
X262483Y769600D01*
X263067Y769683D01*
X263567Y769933D01*
X263900Y770267D01*
G01X266583Y769600D02*
Y772933D01*
G01Y772100D02*
X266917Y772517D01*
X267417Y772850D01*
X268083Y772933D01*
X268667Y772850D01*
X269167Y772517D01*
X269417Y771933D01*
Y769600D01*
G01X274933Y772517D02*
X274350Y772850D01*
X273850Y772933D01*
X273183Y772767D01*
X272683Y772433D01*
X272350Y771850D01*
X272267Y771267D01*
X272350Y770683D01*
X272683Y770183D01*
X273183Y769767D01*
X273850Y769600D01*
X274433Y769767D01*
X274933Y770100D01*
G01X277950Y771850D02*
X280617D01*
X280367Y772433D01*
X279950Y772767D01*
X279367Y772933D01*
X278783Y772850D01*
X278283Y772600D01*
X277950Y772017D01*
X277783Y771517D01*
Y771017D01*
X277950Y770517D01*
X278367Y770017D01*
X278867Y769683D01*
X279450Y769600D01*
X280033Y769767D01*
X280617Y770267D01*
G01X288650D02*
X289317Y769850D01*
X290067Y769600D01*
X290733D01*
X291400Y769850D01*
X291900Y770267D01*
X292150Y770850D01*
X291983Y771433D01*
X291567Y771933D01*
X290817Y772267D01*
X289817Y772433D01*
X289233Y772767D01*
X288983Y773350D01*
X289150Y773933D01*
X289567Y774350D01*
X290150Y774600D01*
X290733D01*
X291317Y774433D01*
X291817Y774017D01*
G01X294500Y767933D02*
Y772933D01*
G01Y772183D02*
X294917Y772600D01*
X295333Y772850D01*
X296000Y772933D01*
X296583Y772850D01*
X297167Y772433D01*
X297417Y771850D01*
X297500Y771267D01*
X297417Y770683D01*
X297167Y770100D01*
X296667Y769767D01*
X296000Y769600D01*
X295417Y769683D01*
X294833Y769933D01*
X294500Y770267D01*
G01X300350Y771850D02*
X303017D01*
X302767Y772433D01*
X302350Y772767D01*
X301767Y772933D01*
X301183Y772850D01*
X300683Y772600D01*
X300350Y772017D01*
X300183Y771517D01*
Y771017D01*
X300350Y770517D01*
X300767Y770017D01*
X301267Y769683D01*
X301850Y769600D01*
X302433Y769767D01*
X303017Y770267D01*
G01X308533Y772517D02*
X307950Y772850D01*
X307450Y772933D01*
X306783Y772767D01*
X306283Y772433D01*
X305950Y771850D01*
X305867Y771267D01*
X305950Y770683D01*
X306283Y770183D01*
X306783Y769767D01*
X307450Y769600D01*
X308033Y769767D01*
X308533Y770100D01*
G01X312800Y772933D02*
Y769600D01*
G01Y774267D02*
X312633Y774350D01*
Y774517D01*
X312800Y774600D01*
X312967Y774517D01*
Y774350D01*
X312800Y774267D01*
G01X317900Y769600D02*
Y773850D01*
X318067Y774267D01*
X318400Y774517D01*
X318900Y774600D01*
X319400Y774433D01*
X319650Y774017D01*
G01X318650Y772600D02*
X316983D01*
G01X324000Y772933D02*
Y769600D01*
G01Y774267D02*
X323833Y774350D01*
Y774517D01*
X324000Y774600D01*
X324167Y774517D01*
Y774350D01*
X324000Y774267D01*
G01X330933Y772517D02*
X330350Y772850D01*
X329850Y772933D01*
X329183Y772767D01*
X328683Y772433D01*
X328350Y771850D01*
X328267Y771267D01*
X328350Y770683D01*
X328683Y770183D01*
X329183Y769767D01*
X329850Y769600D01*
X330433Y769767D01*
X330933Y770100D01*
G01X336700Y769600D02*
Y772933D01*
G01Y772350D02*
X336367Y772683D01*
X335867Y772850D01*
X335283Y772933D01*
X334700Y772767D01*
X334200Y772433D01*
X333867Y771933D01*
X333700Y771267D01*
X333867Y770600D01*
X334200Y770100D01*
X334700Y769767D01*
X335283Y769600D01*
X335867Y769683D01*
X336367Y769933D01*
X336700Y770267D01*
G01X340800Y774600D02*
Y769600D01*
G01X339633Y772933D02*
X341967D01*
G01X346400D02*
Y769600D01*
G01Y774267D02*
X346233Y774350D01*
Y774517D01*
X346400Y774600D01*
X346567Y774517D01*
Y774350D01*
X346400Y774267D01*
G01X352000Y769600D02*
X351500Y769683D01*
X351000Y770017D01*
X350667Y770600D01*
X350500Y771267D01*
X350667Y771933D01*
X351000Y772517D01*
X351500Y772850D01*
X352000Y772933D01*
X352500Y772850D01*
X353000Y772517D01*
X353333Y771933D01*
X353417Y771267D01*
X353333Y770600D01*
X353000Y770017D01*
X352500Y769683D01*
X352000Y769600D01*
G01X356183D02*
Y772933D01*
G01Y772100D02*
X356517Y772517D01*
X357017Y772850D01*
X357683Y772933D01*
X358267Y772850D01*
X358767Y772517D01*
X359017Y771933D01*
Y769600D01*
G01X368300D02*
Y773850D01*
X368467Y774267D01*
X368800Y774517D01*
X369300Y774600D01*
X369800Y774433D01*
X370050Y774017D01*
G01X369050Y772600D02*
X367383D01*
G01X374400Y769600D02*
X373900Y769683D01*
X373400Y770017D01*
X373067Y770600D01*
X372900Y771267D01*
X373067Y771933D01*
X373400Y772517D01*
X373900Y772850D01*
X374400Y772933D01*
X374900Y772850D01*
X375400Y772517D01*
X375733Y771933D01*
X375817Y771267D01*
X375733Y770600D01*
X375400Y770017D01*
X374900Y769683D01*
X374400Y769600D01*
G01X378833D02*
Y772933D01*
G01Y772267D02*
X379250Y772600D01*
X379667Y772850D01*
X380250Y772933D01*
X380667Y772850D01*
X381167Y772600D01*
G01X389533Y769600D02*
Y774600D01*
X391617D01*
X392283Y774350D01*
X392700Y774017D01*
X392867Y773350D01*
X392700Y772683D01*
X392200Y772267D01*
X391617Y772017D01*
X389533D01*
G01X391617D02*
X392867Y769600D01*
G01X396800Y772933D02*
Y769600D01*
G01Y774267D02*
X396633Y774350D01*
Y774517D01*
X396800Y774600D01*
X396967Y774517D01*
Y774350D01*
X396800Y774267D01*
G01X401233Y768350D02*
X401817Y768017D01*
X402483Y767933D01*
X403067Y768017D01*
X403567Y768433D01*
X403900Y769017D01*
Y772933D01*
G01Y772267D02*
X403567Y772600D01*
X403067Y772850D01*
X402483Y772933D01*
X401817Y772767D01*
X401400Y772433D01*
X401067Y771850D01*
X400900Y771267D01*
X400983Y770767D01*
X401317Y770183D01*
X401817Y769767D01*
X402483Y769600D01*
X402983Y769683D01*
X403567Y770017D01*
X403900Y770350D01*
G01X408000Y772933D02*
Y769600D01*
G01Y774267D02*
X407833Y774350D01*
Y774517D01*
X408000Y774600D01*
X408167Y774517D01*
Y774350D01*
X408000Y774267D01*
G01X415100Y774600D02*
Y769600D01*
G01Y770350D02*
X414767Y769933D01*
X414267Y769683D01*
X413683Y769600D01*
X413017Y769767D01*
X412517Y770183D01*
X412183Y770683D01*
X412100Y771267D01*
X412183Y771850D01*
X412517Y772350D01*
X413017Y772767D01*
X413683Y772933D01*
X414267Y772850D01*
X414683Y772683D01*
X415100Y772350D01*
G01X423133Y769600D02*
Y774600D01*
X425133D01*
X425800Y774350D01*
X426300Y773767D01*
X426467Y773100D01*
X426300Y772433D01*
X425883Y771933D01*
X425133Y771683D01*
X423133D01*
G01X429233Y769600D02*
Y772933D01*
G01Y772267D02*
X429650Y772600D01*
X430067Y772850D01*
X430650Y772933D01*
X431067Y772850D01*
X431567Y772600D01*
G01X436000Y772933D02*
Y769600D01*
G01Y774267D02*
X435833Y774350D01*
Y774517D01*
X436000Y774600D01*
X436167Y774517D01*
Y774350D01*
X436000Y774267D01*
G01X440183Y769600D02*
Y772933D01*
G01Y772100D02*
X440517Y772517D01*
X441017Y772850D01*
X441683Y772933D01*
X442267Y772850D01*
X442767Y772517D01*
X443017Y771933D01*
Y769600D01*
G01X447200Y774600D02*
Y769600D01*
G01X446033Y772933D02*
X448367D01*
G01X451550Y771850D02*
X454217D01*
X453967Y772433D01*
X453550Y772767D01*
X452967Y772933D01*
X452383Y772850D01*
X451883Y772600D01*
X451550Y772017D01*
X451383Y771517D01*
Y771017D01*
X451550Y770517D01*
X451967Y770017D01*
X452467Y769683D01*
X453050Y769600D01*
X453633Y769767D01*
X454217Y770267D01*
G01X459900Y774600D02*
Y769600D01*
G01Y770350D02*
X459567Y769933D01*
X459067Y769683D01*
X458483Y769600D01*
X457817Y769767D01*
X457317Y770183D01*
X456983Y770683D01*
X456900Y771267D01*
X456983Y771850D01*
X457317Y772350D01*
X457817Y772767D01*
X458483Y772933D01*
X459067Y772850D01*
X459483Y772683D01*
X459900Y772350D01*
G01X470267Y772267D02*
X470600Y772517D01*
X470850Y772933D01*
X471017Y773517D01*
X470850Y774017D01*
X470517Y774350D01*
X469933Y774600D01*
X467683D01*
Y769600D01*
X470433D01*
X471017Y769933D01*
X471350Y770433D01*
X471517Y771017D01*
X471350Y771600D01*
X470850Y772100D01*
X470267Y772267D01*
X467683D01*
G01X475200Y769600D02*
X474700Y769683D01*
X474200Y770017D01*
X473867Y770600D01*
X473700Y771267D01*
X473867Y771933D01*
X474200Y772517D01*
X474700Y772850D01*
X475200Y772933D01*
X475700Y772850D01*
X476200Y772517D01*
X476533Y771933D01*
X476617Y771267D01*
X476533Y770600D01*
X476200Y770017D01*
X475700Y769683D01*
X475200Y769600D01*
G01X482300D02*
Y772933D01*
G01Y772350D02*
X481967Y772683D01*
X481467Y772850D01*
X480883Y772933D01*
X480300Y772767D01*
X479800Y772433D01*
X479467Y771933D01*
X479300Y771267D01*
X479467Y770600D01*
X479800Y770100D01*
X480300Y769767D01*
X480883Y769600D01*
X481467Y769683D01*
X481967Y769933D01*
X482300Y770267D01*
G01X485233Y769600D02*
Y772933D01*
G01Y772267D02*
X485650Y772600D01*
X486067Y772850D01*
X486650Y772933D01*
X487067Y772850D01*
X487567Y772600D01*
G01X493500Y774600D02*
Y769600D01*
G01Y770350D02*
X493167Y769933D01*
X492667Y769683D01*
X492083Y769600D01*
X491417Y769767D01*
X490917Y770183D01*
X490583Y770683D01*
X490500Y771267D01*
X490583Y771850D01*
X490917Y772350D01*
X491417Y772767D01*
X492083Y772933D01*
X492667Y772850D01*
X493083Y772683D01*
X493500Y772350D01*
G01X496350Y770183D02*
X496767Y769850D01*
X497350Y769600D01*
X497850D01*
X498350Y769767D01*
X498683Y770017D01*
X498850Y770350D01*
X498767Y770850D01*
X498433Y771100D01*
X496933Y771600D01*
X496600Y772183D01*
X496767Y772600D01*
X497100Y772850D01*
X497600Y772933D01*
X498100Y772850D01*
X498600Y772600D01*
G01X67000Y779433D02*
X66833Y779517D01*
Y779683D01*
X67000Y779767D01*
X67167Y779683D01*
Y779517D01*
X67000Y779433D01*
G01Y786333D02*
X66833Y786417D01*
Y786583D01*
X67000Y786667D01*
X67167Y786583D01*
Y786417D01*
X67000Y786333D01*
G01X71000Y783600D02*
X73000D01*
G01X72000D02*
Y778600D01*
G01X71000D02*
X73000D01*
G01X75933D02*
Y783600D01*
X77933D01*
X78600Y783350D01*
X79100Y782767D01*
X79267Y782100D01*
X79100Y781433D01*
X78683Y780933D01*
X77933Y780683D01*
X75933D01*
G01X85033Y783183D02*
X84533Y783433D01*
X83950Y783600D01*
X83283D01*
X82533Y783350D01*
X81950Y782933D01*
X81533Y782433D01*
X81200Y781600D01*
X81117Y780850D01*
X81283Y780100D01*
X81533Y779600D01*
X82033Y779100D01*
X82617Y778767D01*
X83200Y778600D01*
X83783D01*
X84367Y778767D01*
X84867Y779017D01*
X85283Y779350D01*
G01X87717Y780267D02*
X89883D01*
G01X92817Y780683D02*
X93400Y781267D01*
X93900Y781600D01*
X94567Y781767D01*
X95150Y781600D01*
X95567Y781267D01*
X95900Y780767D01*
X95983Y780183D01*
X95900Y779683D01*
X95567Y779183D01*
X95067Y778767D01*
X94483Y778600D01*
X93817Y778767D01*
X93233Y779267D01*
X92900Y780017D01*
X92817Y780850D01*
X92983Y781933D01*
X93233Y782517D01*
X93650Y783100D01*
X94233Y783517D01*
X94817Y783600D01*
X95400Y783433D01*
X95817Y783017D01*
G01X100000Y783600D02*
X99333Y783433D01*
X98833Y783017D01*
X98500Y782517D01*
X98250Y781850D01*
X98167Y781100D01*
X98250Y780350D01*
X98500Y779683D01*
X98833Y779183D01*
X99333Y778767D01*
X100000Y778600D01*
X100667Y778767D01*
X101167Y779183D01*
X101500Y779683D01*
X101750Y780350D01*
X101833Y781100D01*
X101750Y781850D01*
X101500Y782517D01*
X101167Y783017D01*
X100667Y783433D01*
X100000Y783600D01*
G01X105600Y778600D02*
Y783600D01*
X104600Y782600D01*
G01Y778600D02*
X106600D01*
G01X111200D02*
Y783600D01*
X110200Y782600D01*
G01Y778600D02*
X112200D01*
G01X122900Y781100D02*
X124567D01*
Y779600D01*
X124067Y779100D01*
X123483Y778767D01*
X122650Y778600D01*
X121817Y778767D01*
X121233Y779100D01*
X120733Y779600D01*
X120400Y780183D01*
X120233Y780850D01*
Y781433D01*
X120400Y781933D01*
X120733Y782517D01*
X121233Y783017D01*
X121733Y783350D01*
X122400Y783600D01*
X122983D01*
X123650Y783433D01*
X124150Y783100D01*
G01X126750Y780850D02*
X129417D01*
X129167Y781433D01*
X128750Y781767D01*
X128167Y781933D01*
X127583Y781850D01*
X127083Y781600D01*
X126750Y781017D01*
X126583Y780517D01*
Y780017D01*
X126750Y779517D01*
X127167Y779017D01*
X127667Y778683D01*
X128250Y778600D01*
X128833Y778767D01*
X129417Y779267D01*
G01X132183Y778600D02*
Y781933D01*
G01Y781100D02*
X132517Y781517D01*
X133017Y781850D01*
X133683Y781933D01*
X134267Y781850D01*
X134767Y781517D01*
X135017Y780933D01*
Y778600D01*
G01X137950Y780850D02*
X140617D01*
X140367Y781433D01*
X139950Y781767D01*
X139367Y781933D01*
X138783Y781850D01*
X138283Y781600D01*
X137950Y781017D01*
X137783Y780517D01*
Y780017D01*
X137950Y779517D01*
X138367Y779017D01*
X138867Y778683D01*
X139450Y778600D01*
X140033Y778767D01*
X140617Y779267D01*
G01X143633Y778600D02*
Y781933D01*
G01Y781267D02*
X144050Y781600D01*
X144467Y781850D01*
X145050Y781933D01*
X145467Y781850D01*
X145967Y781600D01*
G01X150400Y781933D02*
Y778600D01*
G01Y783267D02*
X150233Y783350D01*
Y783517D01*
X150400Y783600D01*
X150567Y783517D01*
Y783350D01*
X150400Y783267D01*
G01X157333Y781517D02*
X156750Y781850D01*
X156250Y781933D01*
X155583Y781767D01*
X155083Y781433D01*
X154750Y780850D01*
X154667Y780267D01*
X154750Y779683D01*
X155083Y779183D01*
X155583Y778767D01*
X156250Y778600D01*
X156833Y778767D01*
X157333Y779100D01*
G01X165533Y778600D02*
Y783600D01*
X167533D01*
X168200Y783350D01*
X168700Y782767D01*
X168867Y782100D01*
X168700Y781433D01*
X168283Y780933D01*
X167533Y780683D01*
X165533D01*
G01X171550Y780850D02*
X174217D01*
X173967Y781433D01*
X173550Y781767D01*
X172967Y781933D01*
X172383Y781850D01*
X171883Y781600D01*
X171550Y781017D01*
X171383Y780517D01*
Y780017D01*
X171550Y779517D01*
X171967Y779017D01*
X172467Y778683D01*
X173050Y778600D01*
X173633Y778767D01*
X174217Y779267D01*
G01X177233Y778600D02*
Y781933D01*
G01Y781267D02*
X177650Y781600D01*
X178067Y781850D01*
X178650Y781933D01*
X179067Y781850D01*
X179567Y781600D01*
G01X183500Y778600D02*
Y782850D01*
X183667Y783267D01*
X184000Y783517D01*
X184500Y783600D01*
X185000Y783433D01*
X185250Y783017D01*
G01X184250Y781600D02*
X182583D01*
G01X189600Y778600D02*
X189100Y778683D01*
X188600Y779017D01*
X188267Y779600D01*
X188100Y780267D01*
X188267Y780933D01*
X188600Y781517D01*
X189100Y781850D01*
X189600Y781933D01*
X190100Y781850D01*
X190600Y781517D01*
X190933Y780933D01*
X191017Y780267D01*
X190933Y779600D01*
X190600Y779017D01*
X190100Y778683D01*
X189600Y778600D01*
G01X194033D02*
Y781933D01*
G01Y781267D02*
X194450Y781600D01*
X194867Y781850D01*
X195450Y781933D01*
X195867Y781850D01*
X196367Y781600D01*
G01X198300Y778600D02*
Y781933D01*
G01Y781017D02*
X198550Y781433D01*
X198967Y781767D01*
X199550Y781933D01*
X200133Y781767D01*
X200550Y781433D01*
X200800Y781017D01*
Y778600D01*
G01Y781017D02*
X201050Y781433D01*
X201467Y781767D01*
X202050Y781933D01*
X202633Y781767D01*
X203050Y781433D01*
X203300Y780933D01*
Y778600D01*
G01X207900D02*
Y781933D01*
G01Y781350D02*
X207567Y781683D01*
X207067Y781850D01*
X206483Y781933D01*
X205900Y781767D01*
X205400Y781433D01*
X205067Y780933D01*
X204900Y780267D01*
X205067Y779600D01*
X205400Y779100D01*
X205900Y778767D01*
X206483Y778600D01*
X207067Y778683D01*
X207567Y778933D01*
X207900Y779267D01*
G01X210583Y778600D02*
Y781933D01*
G01Y781100D02*
X210917Y781517D01*
X211417Y781850D01*
X212083Y781933D01*
X212667Y781850D01*
X213167Y781517D01*
X213417Y780933D01*
Y778600D01*
G01X218933Y781517D02*
X218350Y781850D01*
X217850Y781933D01*
X217183Y781767D01*
X216683Y781433D01*
X216350Y780850D01*
X216267Y780267D01*
X216350Y779683D01*
X216683Y779183D01*
X217183Y778767D01*
X217850Y778600D01*
X218433Y778767D01*
X218933Y779100D01*
G01X221950Y780850D02*
X224617D01*
X224367Y781433D01*
X223950Y781767D01*
X223367Y781933D01*
X222783Y781850D01*
X222283Y781600D01*
X221950Y781017D01*
X221783Y780517D01*
Y780017D01*
X221950Y779517D01*
X222367Y779017D01*
X222867Y778683D01*
X223450Y778600D01*
X224033Y778767D01*
X224617Y779267D01*
G01X232650D02*
X233317Y778850D01*
X234067Y778600D01*
X234733D01*
X235400Y778850D01*
X235900Y779267D01*
X236150Y779850D01*
X235983Y780433D01*
X235567Y780933D01*
X234817Y781267D01*
X233817Y781433D01*
X233233Y781767D01*
X232983Y782350D01*
X233150Y782933D01*
X233567Y783350D01*
X234150Y783600D01*
X234733D01*
X235317Y783433D01*
X235817Y783017D01*
G01X238500Y776933D02*
Y781933D01*
G01Y781183D02*
X238917Y781600D01*
X239333Y781850D01*
X240000Y781933D01*
X240583Y781850D01*
X241167Y781433D01*
X241417Y780850D01*
X241500Y780267D01*
X241417Y779683D01*
X241167Y779100D01*
X240667Y778767D01*
X240000Y778600D01*
X239417Y778683D01*
X238833Y778933D01*
X238500Y779267D01*
G01X244350Y780850D02*
X247017D01*
X246767Y781433D01*
X246350Y781767D01*
X245767Y781933D01*
X245183Y781850D01*
X244683Y781600D01*
X244350Y781017D01*
X244183Y780517D01*
Y780017D01*
X244350Y779517D01*
X244767Y779017D01*
X245267Y778683D01*
X245850Y778600D01*
X246433Y778767D01*
X247017Y779267D01*
G01X252533Y781517D02*
X251950Y781850D01*
X251450Y781933D01*
X250783Y781767D01*
X250283Y781433D01*
X249950Y780850D01*
X249867Y780267D01*
X249950Y779683D01*
X250283Y779183D01*
X250783Y778767D01*
X251450Y778600D01*
X252033Y778767D01*
X252533Y779100D01*
G01X256800Y781933D02*
Y778600D01*
G01Y783267D02*
X256633Y783350D01*
Y783517D01*
X256800Y783600D01*
X256967Y783517D01*
Y783350D01*
X256800Y783267D01*
G01X261900Y778600D02*
Y782850D01*
X262067Y783267D01*
X262400Y783517D01*
X262900Y783600D01*
X263400Y783433D01*
X263650Y783017D01*
G01X262650Y781600D02*
X260983D01*
G01X268000Y781933D02*
Y778600D01*
G01Y783267D02*
X267833Y783350D01*
Y783517D01*
X268000Y783600D01*
X268167Y783517D01*
Y783350D01*
X268000Y783267D01*
G01X274933Y781517D02*
X274350Y781850D01*
X273850Y781933D01*
X273183Y781767D01*
X272683Y781433D01*
X272350Y780850D01*
X272267Y780267D01*
X272350Y779683D01*
X272683Y779183D01*
X273183Y778767D01*
X273850Y778600D01*
X274433Y778767D01*
X274933Y779100D01*
G01X280700Y778600D02*
Y781933D01*
G01Y781350D02*
X280367Y781683D01*
X279867Y781850D01*
X279283Y781933D01*
X278700Y781767D01*
X278200Y781433D01*
X277867Y780933D01*
X277700Y780267D01*
X277867Y779600D01*
X278200Y779100D01*
X278700Y778767D01*
X279283Y778600D01*
X279867Y778683D01*
X280367Y778933D01*
X280700Y779267D01*
G01X284800Y783600D02*
Y778600D01*
G01X283633Y781933D02*
X285967D01*
G01X290400D02*
Y778600D01*
G01Y783267D02*
X290233Y783350D01*
Y783517D01*
X290400Y783600D01*
X290567Y783517D01*
Y783350D01*
X290400Y783267D01*
G01X296000Y778600D02*
X295500Y778683D01*
X295000Y779017D01*
X294667Y779600D01*
X294500Y780267D01*
X294667Y780933D01*
X295000Y781517D01*
X295500Y781850D01*
X296000Y781933D01*
X296500Y781850D01*
X297000Y781517D01*
X297333Y780933D01*
X297417Y780267D01*
X297333Y779600D01*
X297000Y779017D01*
X296500Y778683D01*
X296000Y778600D01*
G01X300183D02*
Y781933D01*
G01Y781100D02*
X300517Y781517D01*
X301017Y781850D01*
X301683Y781933D01*
X302267Y781850D01*
X302767Y781517D01*
X303017Y780933D01*
Y778600D01*
G01X312300D02*
Y782850D01*
X312467Y783267D01*
X312800Y783517D01*
X313300Y783600D01*
X313800Y783433D01*
X314050Y783017D01*
G01X313050Y781600D02*
X311383D01*
G01X318400Y778600D02*
X317900Y778683D01*
X317400Y779017D01*
X317067Y779600D01*
X316900Y780267D01*
X317067Y780933D01*
X317400Y781517D01*
X317900Y781850D01*
X318400Y781933D01*
X318900Y781850D01*
X319400Y781517D01*
X319733Y780933D01*
X319817Y780267D01*
X319733Y779600D01*
X319400Y779017D01*
X318900Y778683D01*
X318400Y778600D01*
G01X322833D02*
Y781933D01*
G01Y781267D02*
X323250Y781600D01*
X323667Y781850D01*
X324250Y781933D01*
X324667Y781850D01*
X325167Y781600D01*
G01X333533Y778600D02*
Y783600D01*
X335533D01*
X336200Y783350D01*
X336700Y782767D01*
X336867Y782100D01*
X336700Y781433D01*
X336283Y780933D01*
X335533Y780683D01*
X333533D01*
G01X339633Y778600D02*
Y781933D01*
G01Y781267D02*
X340050Y781600D01*
X340467Y781850D01*
X341050Y781933D01*
X341467Y781850D01*
X341967Y781600D01*
G01X346400Y781933D02*
Y778600D01*
G01Y783267D02*
X346233Y783350D01*
Y783517D01*
X346400Y783600D01*
X346567Y783517D01*
Y783350D01*
X346400Y783267D01*
G01X350583Y778600D02*
Y781933D01*
G01Y781100D02*
X350917Y781517D01*
X351417Y781850D01*
X352083Y781933D01*
X352667Y781850D01*
X353167Y781517D01*
X353417Y780933D01*
Y778600D01*
G01X357600Y783600D02*
Y778600D01*
G01X356433Y781933D02*
X358767D01*
G01X361950Y780850D02*
X364617D01*
X364367Y781433D01*
X363950Y781767D01*
X363367Y781933D01*
X362783Y781850D01*
X362283Y781600D01*
X361950Y781017D01*
X361783Y780517D01*
Y780017D01*
X361950Y779517D01*
X362367Y779017D01*
X362867Y778683D01*
X363450Y778600D01*
X364033Y778767D01*
X364617Y779267D01*
G01X370300Y783600D02*
Y778600D01*
G01Y779350D02*
X369967Y778933D01*
X369467Y778683D01*
X368883Y778600D01*
X368217Y778767D01*
X367717Y779183D01*
X367383Y779683D01*
X367300Y780267D01*
X367383Y780850D01*
X367717Y781350D01*
X368217Y781767D01*
X368883Y781933D01*
X369467Y781850D01*
X369883Y781683D01*
X370300Y781350D01*
G01X380667Y781267D02*
X381000Y781517D01*
X381250Y781933D01*
X381417Y782517D01*
X381250Y783017D01*
X380917Y783350D01*
X380333Y783600D01*
X378083D01*
Y778600D01*
X380833D01*
X381417Y778933D01*
X381750Y779433D01*
X381917Y780017D01*
X381750Y780600D01*
X381250Y781100D01*
X380667Y781267D01*
X378083D01*
G01X385600Y778600D02*
X385100Y778683D01*
X384600Y779017D01*
X384267Y779600D01*
X384100Y780267D01*
X384267Y780933D01*
X384600Y781517D01*
X385100Y781850D01*
X385600Y781933D01*
X386100Y781850D01*
X386600Y781517D01*
X386933Y780933D01*
X387017Y780267D01*
X386933Y779600D01*
X386600Y779017D01*
X386100Y778683D01*
X385600Y778600D01*
G01X392700D02*
Y781933D01*
G01Y781350D02*
X392367Y781683D01*
X391867Y781850D01*
X391283Y781933D01*
X390700Y781767D01*
X390200Y781433D01*
X389867Y780933D01*
X389700Y780267D01*
X389867Y779600D01*
X390200Y779100D01*
X390700Y778767D01*
X391283Y778600D01*
X391867Y778683D01*
X392367Y778933D01*
X392700Y779267D01*
G01X395633Y778600D02*
Y781933D01*
G01Y781267D02*
X396050Y781600D01*
X396467Y781850D01*
X397050Y781933D01*
X397467Y781850D01*
X397967Y781600D01*
G01X403900Y783600D02*
Y778600D01*
G01Y779350D02*
X403567Y778933D01*
X403067Y778683D01*
X402483Y778600D01*
X401817Y778767D01*
X401317Y779183D01*
X400983Y779683D01*
X400900Y780267D01*
X400983Y780850D01*
X401317Y781350D01*
X401817Y781767D01*
X402483Y781933D01*
X403067Y781850D01*
X403483Y781683D01*
X403900Y781350D01*
G01X406750Y779183D02*
X407167Y778850D01*
X407750Y778600D01*
X408250D01*
X408750Y778767D01*
X409083Y779017D01*
X409250Y779350D01*
X409167Y779850D01*
X408833Y780100D01*
X407333Y780600D01*
X407000Y781183D01*
X407167Y781600D01*
X407500Y781850D01*
X408000Y781933D01*
X408500Y781850D01*
X409000Y781600D01*
G01X71000Y791500D02*
X73000D01*
G01X72000D02*
Y786500D01*
G01X71000D02*
X73000D01*
G01X75933D02*
Y791500D01*
X77933D01*
X78600Y791250D01*
X79100Y790667D01*
X79267Y790000D01*
X79100Y789333D01*
X78683Y788833D01*
X77933Y788583D01*
X75933D01*
G01X85033Y791083D02*
X84533Y791333D01*
X83950Y791500D01*
X83283D01*
X82533Y791250D01*
X81950Y790833D01*
X81533Y790333D01*
X81200Y789500D01*
X81117Y788750D01*
X81283Y788000D01*
X81533Y787500D01*
X82033Y787000D01*
X82617Y786667D01*
X83200Y786500D01*
X83783D01*
X84367Y786667D01*
X84867Y786917D01*
X85283Y787250D01*
G01X87717Y788167D02*
X89883D01*
G01X92317Y786500D02*
X94400Y791500D01*
X96483Y786500D01*
G01X95733Y788250D02*
X93067D01*
G01X98917Y788167D02*
X101083D01*
G01X104017Y788583D02*
X104600Y789167D01*
X105100Y789500D01*
X105767Y789667D01*
X106350Y789500D01*
X106767Y789167D01*
X107100Y788667D01*
X107183Y788083D01*
X107100Y787583D01*
X106767Y787083D01*
X106267Y786667D01*
X105683Y786500D01*
X105017Y786667D01*
X104433Y787167D01*
X104100Y787917D01*
X104017Y788750D01*
X104183Y789833D01*
X104433Y790417D01*
X104850Y791000D01*
X105433Y791417D01*
X106017Y791500D01*
X106600Y791333D01*
X107017Y790917D01*
G01X111200Y791500D02*
X110533Y791333D01*
X110033Y790917D01*
X109700Y790417D01*
X109450Y789750D01*
X109367Y789000D01*
X109450Y788250D01*
X109700Y787583D01*
X110033Y787083D01*
X110533Y786667D01*
X111200Y786500D01*
X111867Y786667D01*
X112367Y787083D01*
X112700Y787583D01*
X112950Y788250D01*
X113033Y789000D01*
X112950Y789750D01*
X112700Y790417D01*
X112367Y790917D01*
X111867Y791333D01*
X111200Y791500D01*
G01X116800D02*
X116133Y791333D01*
X115633Y790917D01*
X115300Y790417D01*
X115050Y789750D01*
X114967Y789000D01*
X115050Y788250D01*
X115300Y787583D01*
X115633Y787083D01*
X116133Y786667D01*
X116800Y786500D01*
X117467Y786667D01*
X117967Y787083D01*
X118300Y787583D01*
X118550Y788250D01*
X118633Y789000D01*
X118550Y789750D01*
X118300Y790417D01*
X117967Y790917D01*
X117467Y791333D01*
X116800Y791500D01*
G01X125917Y786500D02*
X128000Y791500D01*
X130083Y786500D01*
G01X129333Y788250D02*
X126667D01*
G01X134933Y789417D02*
X134350Y789750D01*
X133850Y789833D01*
X133183Y789667D01*
X132683Y789333D01*
X132350Y788750D01*
X132267Y788167D01*
X132350Y787583D01*
X132683Y787083D01*
X133183Y786667D01*
X133850Y786500D01*
X134433Y786667D01*
X134933Y787000D01*
G01X140533Y789417D02*
X139950Y789750D01*
X139450Y789833D01*
X138783Y789667D01*
X138283Y789333D01*
X137950Y788750D01*
X137867Y788167D01*
X137950Y787583D01*
X138283Y787083D01*
X138783Y786667D01*
X139450Y786500D01*
X140033Y786667D01*
X140533Y787000D01*
G01X143550Y788750D02*
X146217D01*
X145967Y789333D01*
X145550Y789667D01*
X144967Y789833D01*
X144383Y789750D01*
X143883Y789500D01*
X143550Y788917D01*
X143383Y788417D01*
Y787917D01*
X143550Y787417D01*
X143967Y786917D01*
X144467Y786583D01*
X145050Y786500D01*
X145633Y786667D01*
X146217Y787167D01*
G01X148900Y784833D02*
Y789833D01*
G01Y789083D02*
X149317Y789500D01*
X149733Y789750D01*
X150400Y789833D01*
X150983Y789750D01*
X151567Y789333D01*
X151817Y788750D01*
X151900Y788167D01*
X151817Y787583D01*
X151567Y787000D01*
X151067Y786667D01*
X150400Y786500D01*
X149817Y786583D01*
X149233Y786833D01*
X148900Y787167D01*
G01X156000Y791500D02*
Y786500D01*
G01X154833Y789833D02*
X157167D01*
G01X163100Y786500D02*
Y789833D01*
G01Y789250D02*
X162767Y789583D01*
X162267Y789750D01*
X161683Y789833D01*
X161100Y789667D01*
X160600Y789333D01*
X160267Y788833D01*
X160100Y788167D01*
X160267Y787500D01*
X160600Y787000D01*
X161100Y786667D01*
X161683Y786500D01*
X162267Y786583D01*
X162767Y786833D01*
X163100Y787167D01*
G01X165700Y786500D02*
Y791500D01*
G01Y789000D02*
X166117Y789500D01*
X166617Y789750D01*
X167117Y789833D01*
X167867Y789667D01*
X168367Y789333D01*
X168700Y788750D01*
Y788083D01*
X168533Y787417D01*
X168200Y786917D01*
X167617Y786583D01*
X167117Y786500D01*
X166617Y786583D01*
X166117Y786833D01*
X165700Y787250D01*
G01X172800Y789833D02*
Y786500D01*
G01Y791167D02*
X172633Y791250D01*
Y791417D01*
X172800Y791500D01*
X172967Y791417D01*
Y791250D01*
X172800Y791167D01*
G01X178400Y786500D02*
Y791500D01*
G01X184000Y789833D02*
Y786500D01*
G01Y791167D02*
X183833Y791250D01*
Y791417D01*
X184000Y791500D01*
X184167Y791417D01*
Y791250D01*
X184000Y791167D01*
G01X189600Y791500D02*
Y786500D01*
G01X188433Y789833D02*
X190767D01*
G01X193450Y785000D02*
X193950Y784833D01*
X194617Y785000D01*
X195033Y785333D01*
X195367Y785750D01*
X195867Y787083D01*
X196950Y789833D01*
G01X194283D02*
X195867Y787083D01*
G01X206400Y786500D02*
X205900Y786583D01*
X205400Y786917D01*
X205067Y787500D01*
X204900Y788167D01*
X205067Y788833D01*
X205400Y789417D01*
X205900Y789750D01*
X206400Y789833D01*
X206900Y789750D01*
X207400Y789417D01*
X207733Y788833D01*
X207817Y788167D01*
X207733Y787500D01*
X207400Y786917D01*
X206900Y786583D01*
X206400Y786500D01*
G01X211500D02*
Y790750D01*
X211667Y791167D01*
X212000Y791417D01*
X212500Y791500D01*
X213000Y791333D01*
X213250Y790917D01*
G01X212250Y789500D02*
X210583D01*
G01X221533Y786500D02*
Y791500D01*
X223533D01*
X224200Y791250D01*
X224700Y790667D01*
X224867Y790000D01*
X224700Y789333D01*
X224283Y788833D01*
X223533Y788583D01*
X221533D01*
G01X227633Y786500D02*
Y789833D01*
G01Y789167D02*
X228050Y789500D01*
X228467Y789750D01*
X229050Y789833D01*
X229467Y789750D01*
X229967Y789500D01*
G01X234400Y789833D02*
Y786500D01*
G01Y791167D02*
X234233Y791250D01*
Y791417D01*
X234400Y791500D01*
X234567Y791417D01*
Y791250D01*
X234400Y791167D01*
G01X238583Y786500D02*
Y789833D01*
G01Y789000D02*
X238917Y789417D01*
X239417Y789750D01*
X240083Y789833D01*
X240667Y789750D01*
X241167Y789417D01*
X241417Y788833D01*
Y786500D01*
G01X245600Y791500D02*
Y786500D01*
G01X244433Y789833D02*
X246767D01*
G01X249950Y788750D02*
X252617D01*
X252367Y789333D01*
X251950Y789667D01*
X251367Y789833D01*
X250783Y789750D01*
X250283Y789500D01*
X249950Y788917D01*
X249783Y788417D01*
Y787917D01*
X249950Y787417D01*
X250367Y786917D01*
X250867Y786583D01*
X251450Y786500D01*
X252033Y786667D01*
X252617Y787167D01*
G01X258300Y791500D02*
Y786500D01*
G01Y787250D02*
X257967Y786833D01*
X257467Y786583D01*
X256883Y786500D01*
X256217Y786667D01*
X255717Y787083D01*
X255383Y787583D01*
X255300Y788167D01*
X255383Y788750D01*
X255717Y789250D01*
X256217Y789667D01*
X256883Y789833D01*
X257467Y789750D01*
X257883Y789583D01*
X258300Y789250D01*
G01X268667Y789167D02*
X269000Y789417D01*
X269250Y789833D01*
X269417Y790417D01*
X269250Y790917D01*
X268917Y791250D01*
X268333Y791500D01*
X266083D01*
Y786500D01*
X268833D01*
X269417Y786833D01*
X269750Y787333D01*
X269917Y787917D01*
X269750Y788500D01*
X269250Y789000D01*
X268667Y789167D01*
X266083D01*
G01X273600Y786500D02*
X273100Y786583D01*
X272600Y786917D01*
X272267Y787500D01*
X272100Y788167D01*
X272267Y788833D01*
X272600Y789417D01*
X273100Y789750D01*
X273600Y789833D01*
X274100Y789750D01*
X274600Y789417D01*
X274933Y788833D01*
X275017Y788167D01*
X274933Y787500D01*
X274600Y786917D01*
X274100Y786583D01*
X273600Y786500D01*
G01X280700D02*
Y789833D01*
G01Y789250D02*
X280367Y789583D01*
X279867Y789750D01*
X279283Y789833D01*
X278700Y789667D01*
X278200Y789333D01*
X277867Y788833D01*
X277700Y788167D01*
X277867Y787500D01*
X278200Y787000D01*
X278700Y786667D01*
X279283Y786500D01*
X279867Y786583D01*
X280367Y786833D01*
X280700Y787167D01*
G01X283633Y786500D02*
Y789833D01*
G01Y789167D02*
X284050Y789500D01*
X284467Y789750D01*
X285050Y789833D01*
X285467Y789750D01*
X285967Y789500D01*
G01X291900Y791500D02*
Y786500D01*
G01Y787250D02*
X291567Y786833D01*
X291067Y786583D01*
X290483Y786500D01*
X289817Y786667D01*
X289317Y787083D01*
X288983Y787583D01*
X288900Y788167D01*
X288983Y788750D01*
X289317Y789250D01*
X289817Y789667D01*
X290483Y789833D01*
X291067Y789750D01*
X291483Y789583D01*
X291900Y789250D01*
G01X294750Y787083D02*
X295167Y786750D01*
X295750Y786500D01*
X296250D01*
X296750Y786667D01*
X297083Y786917D01*
X297250Y787250D01*
X297167Y787750D01*
X296833Y788000D01*
X295333Y788500D01*
X295000Y789083D01*
X295167Y789500D01*
X295500Y789750D01*
X296000Y789833D01*
X296500Y789750D01*
X297000Y789500D01*
G01X57000Y802500D02*
X59000D01*
G01X58000D02*
Y797500D01*
G01X57000D02*
X59000D01*
G01X63100D02*
Y801750D01*
X63267Y802167D01*
X63600Y802417D01*
X64100Y802500D01*
X64600Y802333D01*
X64850Y801917D01*
G01X63850Y800500D02*
X62183D01*
G01X74800Y802500D02*
Y797500D01*
G01X73633Y800833D02*
X75967D01*
G01X78983Y797500D02*
Y802500D01*
G01Y800083D02*
X79400Y800500D01*
X79817Y800750D01*
X80483Y800833D01*
X80983Y800750D01*
X81567Y800417D01*
X81817Y799917D01*
Y797500D01*
G01X84750Y799750D02*
X87417D01*
X87167Y800333D01*
X86750Y800667D01*
X86167Y800833D01*
X85583Y800750D01*
X85083Y800500D01*
X84750Y799917D01*
X84583Y799417D01*
Y798917D01*
X84750Y798417D01*
X85167Y797917D01*
X85667Y797583D01*
X86250Y797500D01*
X86833Y797667D01*
X87417Y798167D01*
G01X98533Y800417D02*
X97950Y800750D01*
X97450Y800833D01*
X96783Y800667D01*
X96283Y800333D01*
X95950Y799750D01*
X95867Y799167D01*
X95950Y798583D01*
X96283Y798083D01*
X96783Y797667D01*
X97450Y797500D01*
X98033Y797667D01*
X98533Y798000D01*
G01X101633Y797500D02*
Y800833D01*
G01Y800167D02*
X102050Y800500D01*
X102467Y800750D01*
X103050Y800833D01*
X103467Y800750D01*
X103967Y800500D01*
G01X108400Y800833D02*
Y797500D01*
G01Y802167D02*
X108233Y802250D01*
Y802417D01*
X108400Y802500D01*
X108567Y802417D01*
Y802250D01*
X108400Y802167D01*
G01X114000Y802500D02*
Y797500D01*
G01X112833Y800833D02*
X115167D01*
G01X118350Y799750D02*
X121017D01*
X120767Y800333D01*
X120350Y800667D01*
X119767Y800833D01*
X119183Y800750D01*
X118683Y800500D01*
X118350Y799917D01*
X118183Y799417D01*
Y798917D01*
X118350Y798417D01*
X118767Y797917D01*
X119267Y797583D01*
X119850Y797500D01*
X120433Y797667D01*
X121017Y798167D01*
G01X124033Y797500D02*
Y800833D01*
G01Y800167D02*
X124450Y800500D01*
X124867Y800750D01*
X125450Y800833D01*
X125867Y800750D01*
X126367Y800500D01*
G01X130800Y800833D02*
Y797500D01*
G01Y802167D02*
X130633Y802250D01*
Y802417D01*
X130800Y802500D01*
X130967Y802417D01*
Y802250D01*
X130800Y802167D01*
G01X137900Y797500D02*
Y800833D01*
G01Y800250D02*
X137567Y800583D01*
X137067Y800750D01*
X136483Y800833D01*
X135900Y800667D01*
X135400Y800333D01*
X135067Y799833D01*
X134900Y799167D01*
X135067Y798500D01*
X135400Y798000D01*
X135900Y797667D01*
X136483Y797500D01*
X137067Y797583D01*
X137567Y797833D01*
X137900Y798167D01*
G01X147600Y800833D02*
Y797500D01*
G01Y802167D02*
X147433Y802250D01*
Y802417D01*
X147600Y802500D01*
X147767Y802417D01*
Y802250D01*
X147600Y802167D01*
G01X151950Y798083D02*
X152367Y797750D01*
X152950Y797500D01*
X153450D01*
X153950Y797667D01*
X154283Y797917D01*
X154450Y798250D01*
X154367Y798750D01*
X154033Y799000D01*
X152533Y799500D01*
X152200Y800083D01*
X152367Y800500D01*
X152700Y800750D01*
X153200Y800833D01*
X153700Y800750D01*
X154200Y800500D01*
G01X162983Y797500D02*
Y800833D01*
G01Y800000D02*
X163317Y800417D01*
X163817Y800750D01*
X164483Y800833D01*
X165067Y800750D01*
X165567Y800417D01*
X165817Y799833D01*
Y797500D01*
G01X170000D02*
X169500Y797583D01*
X169000Y797917D01*
X168667Y798500D01*
X168500Y799167D01*
X168667Y799833D01*
X169000Y800417D01*
X169500Y800750D01*
X170000Y800833D01*
X170500Y800750D01*
X171000Y800417D01*
X171333Y799833D01*
X171417Y799167D01*
X171333Y798500D01*
X171000Y797917D01*
X170500Y797583D01*
X170000Y797500D01*
G01X175600Y802500D02*
Y797500D01*
G01X174433Y800833D02*
X176767D01*
G01X185550Y798083D02*
X185967Y797750D01*
X186550Y797500D01*
X187050D01*
X187550Y797667D01*
X187883Y797917D01*
X188050Y798250D01*
X187967Y798750D01*
X187633Y799000D01*
X186133Y799500D01*
X185800Y800083D01*
X185967Y800500D01*
X186300Y800750D01*
X186800Y800833D01*
X187300Y800750D01*
X187800Y800500D01*
G01X190900Y795833D02*
Y800833D01*
G01Y800083D02*
X191317Y800500D01*
X191733Y800750D01*
X192400Y800833D01*
X192983Y800750D01*
X193567Y800333D01*
X193817Y799750D01*
X193900Y799167D01*
X193817Y798583D01*
X193567Y798000D01*
X193067Y797667D01*
X192400Y797500D01*
X191817Y797583D01*
X191233Y797833D01*
X190900Y798167D01*
G01X196750Y799750D02*
X199417D01*
X199167Y800333D01*
X198750Y800667D01*
X198167Y800833D01*
X197583Y800750D01*
X197083Y800500D01*
X196750Y799917D01*
X196583Y799417D01*
Y798917D01*
X196750Y798417D01*
X197167Y797917D01*
X197667Y797583D01*
X198250Y797500D01*
X198833Y797667D01*
X199417Y798167D01*
G01X204933Y800417D02*
X204350Y800750D01*
X203850Y800833D01*
X203183Y800667D01*
X202683Y800333D01*
X202350Y799750D01*
X202267Y799167D01*
X202350Y798583D01*
X202683Y798083D01*
X203183Y797667D01*
X203850Y797500D01*
X204433Y797667D01*
X204933Y798000D01*
G01X209200Y800833D02*
Y797500D01*
G01Y802167D02*
X209033Y802250D01*
Y802417D01*
X209200Y802500D01*
X209367Y802417D01*
Y802250D01*
X209200Y802167D01*
G01X214300Y797500D02*
Y801750D01*
X214467Y802167D01*
X214800Y802417D01*
X215300Y802500D01*
X215800Y802333D01*
X216050Y801917D01*
G01X215050Y800500D02*
X213383D01*
G01X220400Y800833D02*
Y797500D01*
G01Y802167D02*
X220233Y802250D01*
Y802417D01*
X220400Y802500D01*
X220567Y802417D01*
Y802250D01*
X220400Y802167D01*
G01X224750Y799750D02*
X227417D01*
X227167Y800333D01*
X226750Y800667D01*
X226167Y800833D01*
X225583Y800750D01*
X225083Y800500D01*
X224750Y799917D01*
X224583Y799417D01*
Y798917D01*
X224750Y798417D01*
X225167Y797917D01*
X225667Y797583D01*
X226250Y797500D01*
X226833Y797667D01*
X227417Y798167D01*
G01X233100Y802500D02*
Y797500D01*
G01Y798250D02*
X232767Y797833D01*
X232267Y797583D01*
X231683Y797500D01*
X231017Y797667D01*
X230517Y798083D01*
X230183Y798583D01*
X230100Y799167D01*
X230183Y799750D01*
X230517Y800250D01*
X231017Y800667D01*
X231683Y800833D01*
X232267Y800750D01*
X232683Y800583D01*
X233100Y800250D01*
G01X242800Y800833D02*
Y797500D01*
G01Y802167D02*
X242633Y802250D01*
Y802417D01*
X242800Y802500D01*
X242967Y802417D01*
Y802250D01*
X242800Y802167D01*
G01X246983Y797500D02*
Y800833D01*
G01Y800000D02*
X247317Y800417D01*
X247817Y800750D01*
X248483Y800833D01*
X249067Y800750D01*
X249567Y800417D01*
X249817Y799833D01*
Y797500D01*
G01X259600Y802500D02*
Y797500D01*
G01X258433Y800833D02*
X260767D01*
G01X263783Y797500D02*
Y802500D01*
G01Y800083D02*
X264200Y800500D01*
X264617Y800750D01*
X265283Y800833D01*
X265783Y800750D01*
X266367Y800417D01*
X266617Y799917D01*
Y797500D01*
G01X269550Y799750D02*
X272217D01*
X271967Y800333D01*
X271550Y800667D01*
X270967Y800833D01*
X270383Y800750D01*
X269883Y800500D01*
X269550Y799917D01*
X269383Y799417D01*
Y798917D01*
X269550Y798417D01*
X269967Y797917D01*
X270467Y797583D01*
X271050Y797500D01*
X271633Y797667D01*
X272217Y798167D01*
G01X282000Y802500D02*
Y797500D01*
G01X280833Y800833D02*
X283167D01*
G01X289100Y797500D02*
Y800833D01*
G01Y800250D02*
X288767Y800583D01*
X288267Y800750D01*
X287683Y800833D01*
X287100Y800667D01*
X286600Y800333D01*
X286267Y799833D01*
X286100Y799167D01*
X286267Y798500D01*
X286600Y798000D01*
X287100Y797667D01*
X287683Y797500D01*
X288267Y797583D01*
X288767Y797833D01*
X289100Y798167D01*
G01X291700Y797500D02*
Y802500D01*
G01Y800000D02*
X292117Y800500D01*
X292617Y800750D01*
X293117Y800833D01*
X293867Y800667D01*
X294367Y800333D01*
X294700Y799750D01*
Y799083D01*
X294533Y798417D01*
X294200Y797917D01*
X293617Y797583D01*
X293117Y797500D01*
X292617Y797583D01*
X292117Y797833D01*
X291700Y798250D01*
G01X298800Y797500D02*
Y802500D01*
G01X303150Y799750D02*
X305817D01*
X305567Y800333D01*
X305150Y800667D01*
X304567Y800833D01*
X303983Y800750D01*
X303483Y800500D01*
X303150Y799917D01*
X302983Y799417D01*
Y798917D01*
X303150Y798417D01*
X303567Y797917D01*
X304067Y797583D01*
X304650Y797500D01*
X305233Y797667D01*
X305817Y798167D01*
G01X310000Y797333D02*
X309833Y797417D01*
Y797583D01*
X310000Y797667D01*
X310167Y797583D01*
Y797417D01*
X310000Y797333D01*
G01Y799583D02*
X309833Y799667D01*
Y799833D01*
X310000Y799917D01*
X310167Y799833D01*
Y799667D01*
X310000Y799583D01*
G01X57833Y806500D02*
Y811500D01*
X59833D01*
X60500Y811250D01*
X61000Y810667D01*
X61167Y810000D01*
X61000Y809333D01*
X60583Y808833D01*
X59833Y808583D01*
X57833D01*
G01X65100Y806500D02*
Y811500D01*
G01X69450Y808750D02*
X72117D01*
X71867Y809333D01*
X71450Y809667D01*
X70867Y809833D01*
X70283Y809750D01*
X69783Y809500D01*
X69450Y808917D01*
X69283Y808417D01*
Y807917D01*
X69450Y807417D01*
X69867Y806917D01*
X70367Y806583D01*
X70950Y806500D01*
X71533Y806667D01*
X72117Y807167D01*
G01X77800Y806500D02*
Y809833D01*
G01Y809250D02*
X77467Y809583D01*
X76967Y809750D01*
X76383Y809833D01*
X75800Y809667D01*
X75300Y809333D01*
X74967Y808833D01*
X74800Y808167D01*
X74967Y807500D01*
X75300Y807000D01*
X75800Y806667D01*
X76383Y806500D01*
X76967Y806583D01*
X77467Y806833D01*
X77800Y807167D01*
G01X80650Y807083D02*
X81067Y806750D01*
X81650Y806500D01*
X82150D01*
X82650Y806667D01*
X82983Y806917D01*
X83150Y807250D01*
X83067Y807750D01*
X82733Y808000D01*
X81233Y808500D01*
X80900Y809083D01*
X81067Y809500D01*
X81400Y809750D01*
X81900Y809833D01*
X82400Y809750D01*
X82900Y809500D01*
G01X86250Y808750D02*
X88917D01*
X88667Y809333D01*
X88250Y809667D01*
X87667Y809833D01*
X87083Y809750D01*
X86583Y809500D01*
X86250Y808917D01*
X86083Y808417D01*
Y807917D01*
X86250Y807417D01*
X86667Y806917D01*
X87167Y806583D01*
X87750Y806500D01*
X88333Y806667D01*
X88917Y807167D01*
G01X98200Y806500D02*
Y810750D01*
X98367Y811167D01*
X98700Y811417D01*
X99200Y811500D01*
X99700Y811333D01*
X99950Y810917D01*
G01X98950Y809500D02*
X97283D01*
G01X104300Y806500D02*
X103800Y806583D01*
X103300Y806917D01*
X102967Y807500D01*
X102800Y808167D01*
X102967Y808833D01*
X103300Y809417D01*
X103800Y809750D01*
X104300Y809833D01*
X104800Y809750D01*
X105300Y809417D01*
X105633Y808833D01*
X105717Y808167D01*
X105633Y807500D01*
X105300Y806917D01*
X104800Y806583D01*
X104300Y806500D01*
G01X109900D02*
Y811500D01*
G01X115500Y806500D02*
Y811500D01*
G01X121100Y806500D02*
X120600Y806583D01*
X120100Y806917D01*
X119767Y807500D01*
X119600Y808167D01*
X119767Y808833D01*
X120100Y809417D01*
X120600Y809750D01*
X121100Y809833D01*
X121600Y809750D01*
X122100Y809417D01*
X122433Y808833D01*
X122517Y808167D01*
X122433Y807500D01*
X122100Y806917D01*
X121600Y806583D01*
X121100Y806500D01*
G01X124617Y809833D02*
X125617Y806500D01*
X126700Y809833D01*
X127783Y806500D01*
X128783Y809833D01*
G01X137900Y811500D02*
Y806500D01*
G01X136733Y809833D02*
X139067D01*
G01X142083Y806500D02*
Y811500D01*
G01Y809083D02*
X142500Y809500D01*
X142917Y809750D01*
X143583Y809833D01*
X144083Y809750D01*
X144667Y809417D01*
X144917Y808917D01*
Y806500D01*
G01X147850Y808750D02*
X150517D01*
X150267Y809333D01*
X149850Y809667D01*
X149267Y809833D01*
X148683Y809750D01*
X148183Y809500D01*
X147850Y808917D01*
X147683Y808417D01*
Y807917D01*
X147850Y807417D01*
X148267Y806917D01*
X148767Y806583D01*
X149350Y806500D01*
X149933Y806667D01*
X150517Y807167D01*
G01X159050Y807083D02*
X159467Y806750D01*
X160050Y806500D01*
X160550D01*
X161050Y806667D01*
X161383Y806917D01*
X161550Y807250D01*
X161467Y807750D01*
X161133Y808000D01*
X159633Y808500D01*
X159300Y809083D01*
X159467Y809500D01*
X159800Y809750D01*
X160300Y809833D01*
X160800Y809750D01*
X161300Y809500D01*
G01X164400Y804833D02*
Y809833D01*
G01Y809083D02*
X164817Y809500D01*
X165233Y809750D01*
X165900Y809833D01*
X166483Y809750D01*
X167067Y809333D01*
X167317Y808750D01*
X167400Y808167D01*
X167317Y807583D01*
X167067Y807000D01*
X166567Y806667D01*
X165900Y806500D01*
X165317Y806583D01*
X164733Y806833D01*
X164400Y807167D01*
G01X170250Y808750D02*
X172917D01*
X172667Y809333D01*
X172250Y809667D01*
X171667Y809833D01*
X171083Y809750D01*
X170583Y809500D01*
X170250Y808917D01*
X170083Y808417D01*
Y807917D01*
X170250Y807417D01*
X170667Y806917D01*
X171167Y806583D01*
X171750Y806500D01*
X172333Y806667D01*
X172917Y807167D01*
G01X178433Y809417D02*
X177850Y809750D01*
X177350Y809833D01*
X176683Y809667D01*
X176183Y809333D01*
X175850Y808750D01*
X175767Y808167D01*
X175850Y807583D01*
X176183Y807083D01*
X176683Y806667D01*
X177350Y806500D01*
X177933Y806667D01*
X178433Y807000D01*
G01X182700Y809833D02*
Y806500D01*
G01Y811167D02*
X182533Y811250D01*
Y811417D01*
X182700Y811500D01*
X182867Y811417D01*
Y811250D01*
X182700Y811167D01*
G01X187800Y806500D02*
Y810750D01*
X187967Y811167D01*
X188300Y811417D01*
X188800Y811500D01*
X189300Y811333D01*
X189550Y810917D01*
G01X188550Y809500D02*
X186883D01*
G01X193900Y809833D02*
Y806500D01*
G01Y811167D02*
X193733Y811250D01*
Y811417D01*
X193900Y811500D01*
X194067Y811417D01*
Y811250D01*
X193900Y811167D01*
G01X200833Y809417D02*
X200250Y809750D01*
X199750Y809833D01*
X199083Y809667D01*
X198583Y809333D01*
X198250Y808750D01*
X198167Y808167D01*
X198250Y807583D01*
X198583Y807083D01*
X199083Y806667D01*
X199750Y806500D01*
X200333Y806667D01*
X200833Y807000D01*
G01X206600Y806500D02*
Y809833D01*
G01Y809250D02*
X206267Y809583D01*
X205767Y809750D01*
X205183Y809833D01*
X204600Y809667D01*
X204100Y809333D01*
X203767Y808833D01*
X203600Y808167D01*
X203767Y807500D01*
X204100Y807000D01*
X204600Y806667D01*
X205183Y806500D01*
X205767Y806583D01*
X206267Y806833D01*
X206600Y807167D01*
G01X210700Y811500D02*
Y806500D01*
G01X209533Y809833D02*
X211867D01*
G01X216300D02*
Y806500D01*
G01Y811167D02*
X216133Y811250D01*
Y811417D01*
X216300Y811500D01*
X216467Y811417D01*
Y811250D01*
X216300Y811167D01*
G01X221900Y806500D02*
X221400Y806583D01*
X220900Y806917D01*
X220567Y807500D01*
X220400Y808167D01*
X220567Y808833D01*
X220900Y809417D01*
X221400Y809750D01*
X221900Y809833D01*
X222400Y809750D01*
X222900Y809417D01*
X223233Y808833D01*
X223317Y808167D01*
X223233Y807500D01*
X222900Y806917D01*
X222400Y806583D01*
X221900Y806500D01*
G01X226083D02*
Y809833D01*
G01Y809000D02*
X226417Y809417D01*
X226917Y809750D01*
X227583Y809833D01*
X228167Y809750D01*
X228667Y809417D01*
X228917Y808833D01*
Y806500D01*
G01X240200Y811500D02*
Y806500D01*
G01Y807250D02*
X239867Y806833D01*
X239367Y806583D01*
X238783Y806500D01*
X238117Y806667D01*
X237617Y807083D01*
X237283Y807583D01*
X237200Y808167D01*
X237283Y808750D01*
X237617Y809250D01*
X238117Y809667D01*
X238783Y809833D01*
X239367Y809750D01*
X239783Y809583D01*
X240200Y809250D01*
G01X244300Y806500D02*
X243800Y806583D01*
X243300Y806917D01*
X242967Y807500D01*
X242800Y808167D01*
X242967Y808833D01*
X243300Y809417D01*
X243800Y809750D01*
X244300Y809833D01*
X244800Y809750D01*
X245300Y809417D01*
X245633Y808833D01*
X245717Y808167D01*
X245633Y807500D01*
X245300Y806917D01*
X244800Y806583D01*
X244300Y806500D01*
G01X251233Y809417D02*
X250650Y809750D01*
X250150Y809833D01*
X249483Y809667D01*
X248983Y809333D01*
X248650Y808750D01*
X248567Y808167D01*
X248650Y807583D01*
X248983Y807083D01*
X249483Y806667D01*
X250150Y806500D01*
X250733Y806667D01*
X251233Y807000D01*
G01X254083Y809833D02*
Y807500D01*
X254417Y806917D01*
X254917Y806583D01*
X255500Y806500D01*
X256083Y806583D01*
X256583Y806917D01*
X256917Y807500D01*
G01Y806500D02*
Y809833D01*
G01X258600Y806500D02*
Y809833D01*
G01Y808917D02*
X258850Y809333D01*
X259267Y809667D01*
X259850Y809833D01*
X260433Y809667D01*
X260850Y809333D01*
X261100Y808917D01*
Y806500D01*
G01Y808917D02*
X261350Y809333D01*
X261767Y809667D01*
X262350Y809833D01*
X262933Y809667D01*
X263350Y809333D01*
X263600Y808833D01*
Y806500D01*
G01X265450Y808750D02*
X268117D01*
X267867Y809333D01*
X267450Y809667D01*
X266867Y809833D01*
X266283Y809750D01*
X265783Y809500D01*
X265450Y808917D01*
X265283Y808417D01*
Y807917D01*
X265450Y807417D01*
X265867Y806917D01*
X266367Y806583D01*
X266950Y806500D01*
X267533Y806667D01*
X268117Y807167D01*
G01X270883Y806500D02*
Y809833D01*
G01Y809000D02*
X271217Y809417D01*
X271717Y809750D01*
X272383Y809833D01*
X272967Y809750D01*
X273467Y809417D01*
X273717Y808833D01*
Y806500D01*
G01X277900Y811500D02*
Y806500D01*
G01X276733Y809833D02*
X279067D01*
G01X282250Y807083D02*
X282667Y806750D01*
X283250Y806500D01*
X283750D01*
X284250Y806667D01*
X284583Y806917D01*
X284750Y807250D01*
X284667Y807750D01*
X284333Y808000D01*
X282833Y808500D01*
X282500Y809083D01*
X282667Y809500D01*
X283000Y809750D01*
X283500Y809833D01*
X284000Y809750D01*
X284500Y809500D01*
G01X294700Y809833D02*
Y806500D01*
G01Y811167D02*
X294533Y811250D01*
Y811417D01*
X294700Y811500D01*
X294867Y811417D01*
Y811250D01*
X294700Y811167D01*
G01X298883Y806500D02*
Y809833D01*
G01Y809000D02*
X299217Y809417D01*
X299717Y809750D01*
X300383Y809833D01*
X300967Y809750D01*
X301467Y809417D01*
X301717Y808833D01*
Y806500D01*
G01X312833Y809417D02*
X312250Y809750D01*
X311750Y809833D01*
X311083Y809667D01*
X310583Y809333D01*
X310250Y808750D01*
X310167Y808167D01*
X310250Y807583D01*
X310583Y807083D01*
X311083Y806667D01*
X311750Y806500D01*
X312333Y806667D01*
X312833Y807000D01*
G01X317100Y806500D02*
Y811500D01*
G01X324200Y806500D02*
Y809833D01*
G01Y809250D02*
X323867Y809583D01*
X323367Y809750D01*
X322783Y809833D01*
X322200Y809667D01*
X321700Y809333D01*
X321367Y808833D01*
X321200Y808167D01*
X321367Y807500D01*
X321700Y807000D01*
X322200Y806667D01*
X322783Y806500D01*
X323367Y806583D01*
X323867Y806833D01*
X324200Y807167D01*
G01X327050Y807083D02*
X327467Y806750D01*
X328050Y806500D01*
X328550D01*
X329050Y806667D01*
X329383Y806917D01*
X329550Y807250D01*
X329467Y807750D01*
X329133Y808000D01*
X327633Y808500D01*
X327300Y809083D01*
X327467Y809500D01*
X327800Y809750D01*
X328300Y809833D01*
X328800Y809750D01*
X329300Y809500D01*
G01X332650Y807083D02*
X333067Y806750D01*
X333650Y806500D01*
X334150D01*
X334650Y806667D01*
X334983Y806917D01*
X335150Y807250D01*
X335067Y807750D01*
X334733Y808000D01*
X333233Y808500D01*
X332900Y809083D01*
X333067Y809500D01*
X333400Y809750D01*
X333900Y809833D01*
X334400Y809750D01*
X334900Y809500D01*
G01X343517Y810667D02*
X344017Y811167D01*
X344600Y811417D01*
X345267Y811500D01*
X346100Y811333D01*
X346683Y810917D01*
X346850Y810417D01*
X346767Y809917D01*
X346433Y809500D01*
X344767Y808667D01*
X344017Y808083D01*
X343517Y807250D01*
X343350Y806500D01*
X346850D01*
G01X357800D02*
Y809833D01*
G01Y809250D02*
X357467Y809583D01*
X356967Y809750D01*
X356383Y809833D01*
X355800Y809667D01*
X355300Y809333D01*
X354967Y808833D01*
X354800Y808167D01*
X354967Y807500D01*
X355300Y807000D01*
X355800Y806667D01*
X356383Y806500D01*
X356967Y806583D01*
X357467Y806833D01*
X357800Y807167D01*
G01X360483Y806500D02*
Y809833D01*
G01Y809000D02*
X360817Y809417D01*
X361317Y809750D01*
X361983Y809833D01*
X362567Y809750D01*
X363067Y809417D01*
X363317Y808833D01*
Y806500D01*
G01X369000Y811500D02*
Y806500D01*
G01Y807250D02*
X368667Y806833D01*
X368167Y806583D01*
X367583Y806500D01*
X366917Y806667D01*
X366417Y807083D01*
X366083Y807583D01*
X366000Y808167D01*
X366083Y808750D01*
X366417Y809250D01*
X366917Y809667D01*
X367583Y809833D01*
X368167Y809750D01*
X368583Y809583D01*
X369000Y809250D01*
G01X378700Y811500D02*
Y806500D01*
G01X377533Y809833D02*
X379867D01*
G01X382883Y806500D02*
Y811500D01*
G01Y809083D02*
X383300Y809500D01*
X383717Y809750D01*
X384383Y809833D01*
X384883Y809750D01*
X385467Y809417D01*
X385717Y808917D01*
Y806500D01*
G01X388650Y808750D02*
X391317D01*
X391067Y809333D01*
X390650Y809667D01*
X390067Y809833D01*
X389483Y809750D01*
X388983Y809500D01*
X388650Y808917D01*
X388483Y808417D01*
Y807917D01*
X388650Y807417D01*
X389067Y806917D01*
X389567Y806583D01*
X390150Y806500D01*
X390733Y806667D01*
X391317Y807167D01*
G01X401100Y806500D02*
Y811500D01*
G01X408200Y806500D02*
Y809833D01*
G01Y809250D02*
X407867Y809583D01*
X407367Y809750D01*
X406783Y809833D01*
X406200Y809667D01*
X405700Y809333D01*
X405367Y808833D01*
X405200Y808167D01*
X405367Y807500D01*
X405700Y807000D01*
X406200Y806667D01*
X406783Y806500D01*
X407367Y806583D01*
X407867Y806833D01*
X408200Y807167D01*
G01X412300Y811500D02*
Y806500D01*
G01X411133Y809833D02*
X413467D01*
G01X416650Y808750D02*
X419317D01*
X419067Y809333D01*
X418650Y809667D01*
X418067Y809833D01*
X417483Y809750D01*
X416983Y809500D01*
X416650Y808917D01*
X416483Y808417D01*
Y807917D01*
X416650Y807417D01*
X417067Y806917D01*
X417567Y806583D01*
X418150Y806500D01*
X418733Y806667D01*
X419317Y807167D01*
G01X422250Y807083D02*
X422667Y806750D01*
X423250Y806500D01*
X423750D01*
X424250Y806667D01*
X424583Y806917D01*
X424750Y807250D01*
X424667Y807750D01*
X424333Y808000D01*
X422833Y808500D01*
X422500Y809083D01*
X422667Y809500D01*
X423000Y809750D01*
X423500Y809833D01*
X424000Y809750D01*
X424500Y809500D01*
G01X429100Y811500D02*
Y806500D01*
G01X427933Y809833D02*
X430267D01*
G01X438800D02*
X440300Y806500D01*
X441800Y809833D01*
G01X444650Y808750D02*
X447317D01*
X447067Y809333D01*
X446650Y809667D01*
X446067Y809833D01*
X445483Y809750D01*
X444983Y809500D01*
X444650Y808917D01*
X444483Y808417D01*
Y807917D01*
X444650Y807417D01*
X445067Y806917D01*
X445567Y806583D01*
X446150Y806500D01*
X446733Y806667D01*
X447317Y807167D01*
G01X450333Y806500D02*
Y809833D01*
G01Y809167D02*
X450750Y809500D01*
X451167Y809750D01*
X451750Y809833D01*
X452167Y809750D01*
X452667Y809500D01*
G01X455850Y807083D02*
X456267Y806750D01*
X456850Y806500D01*
X457350D01*
X457850Y806667D01*
X458183Y806917D01*
X458350Y807250D01*
X458267Y807750D01*
X457933Y808000D01*
X456433Y808500D01*
X456100Y809083D01*
X456267Y809500D01*
X456600Y809750D01*
X457100Y809833D01*
X457600Y809750D01*
X458100Y809500D01*
G01X462700Y809833D02*
Y806500D01*
G01Y811167D02*
X462533Y811250D01*
Y811417D01*
X462700Y811500D01*
X462867Y811417D01*
Y811250D01*
X462700Y811167D01*
G01X468300Y806500D02*
X467800Y806583D01*
X467300Y806917D01*
X466967Y807500D01*
X466800Y808167D01*
X466967Y808833D01*
X467300Y809417D01*
X467800Y809750D01*
X468300Y809833D01*
X468800Y809750D01*
X469300Y809417D01*
X469633Y808833D01*
X469717Y808167D01*
X469633Y807500D01*
X469300Y806917D01*
X468800Y806583D01*
X468300Y806500D01*
G01X472483D02*
Y809833D01*
G01Y809000D02*
X472817Y809417D01*
X473317Y809750D01*
X473983Y809833D01*
X474567Y809750D01*
X475067Y809417D01*
X475317Y808833D01*
Y806500D01*
G01X485100Y809833D02*
Y806500D01*
G01Y811167D02*
X484933Y811250D01*
Y811417D01*
X485100Y811500D01*
X485267Y811417D01*
Y811250D01*
X485100Y811167D01*
G01X489450Y807083D02*
X489867Y806750D01*
X490450Y806500D01*
X490950D01*
X491450Y806667D01*
X491783Y806917D01*
X491950Y807250D01*
X491867Y807750D01*
X491533Y808000D01*
X490033Y808500D01*
X489700Y809083D01*
X489867Y809500D01*
X490200Y809750D01*
X490700Y809833D01*
X491200Y809750D01*
X491700Y809500D01*
G01X500733Y806500D02*
Y809833D01*
G01Y809167D02*
X501150Y809500D01*
X501567Y809750D01*
X502150Y809833D01*
X502567Y809750D01*
X503067Y809500D01*
G01X506250Y808750D02*
X508917D01*
X508667Y809333D01*
X508250Y809667D01*
X507667Y809833D01*
X507083Y809750D01*
X506583Y809500D01*
X506250Y808917D01*
X506083Y808417D01*
Y807917D01*
X506250Y807417D01*
X506667Y806917D01*
X507167Y806583D01*
X507750Y806500D01*
X508333Y806667D01*
X508917Y807167D01*
G01X514600Y804833D02*
Y809833D01*
G01Y809083D02*
X514183Y809500D01*
X513683Y809750D01*
X513100Y809833D01*
X512600Y809750D01*
X512017Y809333D01*
X511683Y808750D01*
X511600Y808167D01*
X511683Y807583D01*
X512017Y807000D01*
X512600Y806583D01*
X513100Y806500D01*
X513683Y806583D01*
X514183Y806833D01*
X514600Y807250D01*
G01X517283Y809833D02*
Y807500D01*
X517617Y806917D01*
X518117Y806583D01*
X518700Y806500D01*
X519283Y806583D01*
X519783Y806917D01*
X520117Y807500D01*
G01Y806500D02*
Y809833D01*
G01X524300D02*
Y806500D01*
G01Y811167D02*
X524133Y811250D01*
Y811417D01*
X524300Y811500D01*
X524467Y811417D01*
Y811250D01*
X524300Y811167D01*
G01X528733Y806500D02*
Y809833D01*
G01Y809167D02*
X529150Y809500D01*
X529567Y809750D01*
X530150Y809833D01*
X530567Y809750D01*
X531067Y809500D01*
G01X534250Y808750D02*
X536917D01*
X536667Y809333D01*
X536250Y809667D01*
X535667Y809833D01*
X535083Y809750D01*
X534583Y809500D01*
X534250Y808917D01*
X534083Y808417D01*
Y807917D01*
X534250Y807417D01*
X534667Y806917D01*
X535167Y806583D01*
X535750Y806500D01*
X536333Y806667D01*
X536917Y807167D01*
G01X542600Y811500D02*
Y806500D01*
G01Y807250D02*
X542267Y806833D01*
X541767Y806583D01*
X541183Y806500D01*
X540517Y806667D01*
X540017Y807083D01*
X539683Y807583D01*
X539600Y808167D01*
X539683Y808750D01*
X540017Y809250D01*
X540517Y809667D01*
X541183Y809833D01*
X541767Y809750D01*
X542183Y809583D01*
X542600Y809250D01*
G01X546533Y805583D02*
X546867Y806667D01*
G01X112333Y-60000D02*
Y-65000D01*
X115667D01*
G01X119600D02*
X119100Y-64917D01*
X118600Y-64583D01*
X118267Y-64000D01*
X118100Y-63333D01*
X118267Y-62667D01*
X118600Y-62083D01*
X119100Y-61750D01*
X119600Y-61667D01*
X120100Y-61750D01*
X120600Y-62083D01*
X120933Y-62667D01*
X121017Y-63333D01*
X120933Y-64000D01*
X120600Y-64583D01*
X120100Y-64917D01*
X119600Y-65000D01*
G01X124033Y-66250D02*
X124617Y-66583D01*
X125283Y-66667D01*
X125867Y-66583D01*
X126367Y-66167D01*
X126700Y-65583D01*
Y-61667D01*
G01Y-62333D02*
X126367Y-62000D01*
X125867Y-61750D01*
X125283Y-61667D01*
X124617Y-61833D01*
X124200Y-62167D01*
X123867Y-62750D01*
X123700Y-63333D01*
X123783Y-63833D01*
X124117Y-64417D01*
X124617Y-64833D01*
X125283Y-65000D01*
X125783Y-64917D01*
X126367Y-64583D01*
X126700Y-64250D01*
G01X130800Y-65000D02*
X130300Y-64917D01*
X129800Y-64583D01*
X129467Y-64000D01*
X129300Y-63333D01*
X129467Y-62667D01*
X129800Y-62083D01*
X130300Y-61750D01*
X130800Y-61667D01*
X131300Y-61750D01*
X131800Y-62083D01*
X132133Y-62667D01*
X132217Y-63333D01*
X132133Y-64000D01*
X131800Y-64583D01*
X131300Y-64917D01*
X130800Y-65000D01*
G01X114000Y-36000D02*
Y-41000D01*
G01X112833Y-37667D02*
X115167D01*
G01X118183Y-41000D02*
Y-36000D01*
G01Y-38417D02*
X118600Y-38000D01*
X119017Y-37750D01*
X119683Y-37667D01*
X120183Y-37750D01*
X120767Y-38083D01*
X121017Y-38583D01*
Y-41000D01*
G01X125200Y-37667D02*
Y-41000D01*
G01Y-36333D02*
X125033Y-36250D01*
Y-36083D01*
X125200Y-36000D01*
X125367Y-36083D01*
Y-36250D01*
X125200Y-36333D01*
G01X132133Y-38083D02*
X131550Y-37750D01*
X131050Y-37667D01*
X130383Y-37833D01*
X129883Y-38167D01*
X129550Y-38750D01*
X129467Y-39333D01*
X129550Y-39917D01*
X129883Y-40417D01*
X130383Y-40833D01*
X131050Y-41000D01*
X131633Y-40833D01*
X132133Y-40500D01*
G01X134983Y-41000D02*
Y-36000D01*
G01X137650Y-37667D02*
X134983Y-39583D01*
G01X136067Y-38833D02*
X137817Y-41000D01*
G01X140583D02*
Y-37667D01*
G01Y-38500D02*
X140917Y-38083D01*
X141417Y-37750D01*
X142083Y-37667D01*
X142667Y-37750D01*
X143167Y-38083D01*
X143417Y-38667D01*
Y-41000D01*
G01X146350Y-38750D02*
X149017D01*
X148767Y-38167D01*
X148350Y-37833D01*
X147767Y-37667D01*
X147183Y-37750D01*
X146683Y-38000D01*
X146350Y-38583D01*
X146183Y-39083D01*
Y-39583D01*
X146350Y-40083D01*
X146767Y-40583D01*
X147267Y-40917D01*
X147850Y-41000D01*
X148433Y-40833D01*
X149017Y-40333D01*
G01X151950Y-40417D02*
X152367Y-40750D01*
X152950Y-41000D01*
X153450D01*
X153950Y-40833D01*
X154283Y-40583D01*
X154450Y-40250D01*
X154367Y-39750D01*
X154033Y-39500D01*
X152533Y-39000D01*
X152200Y-38417D01*
X152367Y-38000D01*
X152700Y-37750D01*
X153200Y-37667D01*
X153700Y-37750D01*
X154200Y-38000D01*
G01X157550Y-40417D02*
X157967Y-40750D01*
X158550Y-41000D01*
X159050D01*
X159550Y-40833D01*
X159883Y-40583D01*
X160050Y-40250D01*
X159967Y-39750D01*
X159633Y-39500D01*
X158133Y-39000D01*
X157800Y-38417D01*
X157967Y-38000D01*
X158300Y-37750D01*
X158800Y-37667D01*
X159300Y-37750D01*
X159800Y-38000D01*
G01X103500Y679000D02*
Y-69500D01*
G01Y-54500D02*
X694500D01*
G01X112483Y24700D02*
Y29700D01*
X114650Y25533D01*
X116817Y29700D01*
Y24700D01*
G01X121750D02*
Y28033D01*
G01Y27450D02*
X121417Y27783D01*
X120917Y27950D01*
X120333Y28033D01*
X119750Y27867D01*
X119250Y27533D01*
X118917Y27033D01*
X118750Y26367D01*
X118917Y25700D01*
X119250Y25200D01*
X119750Y24867D01*
X120333Y24700D01*
X120917Y24783D01*
X121417Y25033D01*
X121750Y25367D01*
G01X124683Y24700D02*
Y28033D01*
G01Y27367D02*
X125100Y27700D01*
X125517Y27950D01*
X126100Y28033D01*
X126517Y27950D01*
X127017Y27700D01*
G01X130033Y24700D02*
Y29700D01*
G01X132700Y28033D02*
X130033Y26117D01*
G01X131117Y26867D02*
X132867Y24700D01*
G01X137467Y23033D02*
X138300Y23867D01*
X138717Y24700D01*
Y28033D01*
X138300Y28867D01*
X137467Y29700D01*
G01X114000Y-15000D02*
Y-20000D01*
G01X112833Y-16667D02*
X115167D01*
G01X118183Y-20000D02*
Y-15000D01*
G01Y-17417D02*
X118600Y-17000D01*
X119017Y-16750D01*
X119683Y-16667D01*
X120183Y-16750D01*
X120767Y-17083D01*
X121017Y-17583D01*
Y-20000D01*
G01X125200Y-16667D02*
Y-20000D01*
G01Y-15333D02*
X125033Y-15250D01*
Y-15083D01*
X125200Y-15000D01*
X125367Y-15083D01*
Y-15250D01*
X125200Y-15333D01*
G01X132133Y-17083D02*
X131550Y-16750D01*
X131050Y-16667D01*
X130383Y-16833D01*
X129883Y-17167D01*
X129550Y-17750D01*
X129467Y-18333D01*
X129550Y-18917D01*
X129883Y-19417D01*
X130383Y-19833D01*
X131050Y-20000D01*
X131633Y-19833D01*
X132133Y-19500D01*
G01X134983Y-20000D02*
Y-15000D01*
G01X137650Y-16667D02*
X134983Y-18583D01*
G01X136067Y-17833D02*
X137817Y-20000D01*
G01X140583D02*
Y-16667D01*
G01Y-17500D02*
X140917Y-17083D01*
X141417Y-16750D01*
X142083Y-16667D01*
X142667Y-16750D01*
X143167Y-17083D01*
X143417Y-17667D01*
Y-20000D01*
G01X146350Y-17750D02*
X149017D01*
X148767Y-17167D01*
X148350Y-16833D01*
X147767Y-16667D01*
X147183Y-16750D01*
X146683Y-17000D01*
X146350Y-17583D01*
X146183Y-18083D01*
Y-18583D01*
X146350Y-19083D01*
X146767Y-19583D01*
X147267Y-19917D01*
X147850Y-20000D01*
X148433Y-19833D01*
X149017Y-19333D01*
G01X151950Y-19417D02*
X152367Y-19750D01*
X152950Y-20000D01*
X153450D01*
X153950Y-19833D01*
X154283Y-19583D01*
X154450Y-19250D01*
X154367Y-18750D01*
X154033Y-18500D01*
X152533Y-18000D01*
X152200Y-17417D01*
X152367Y-17000D01*
X152700Y-16750D01*
X153200Y-16667D01*
X153700Y-16750D01*
X154200Y-17000D01*
G01X157550Y-19417D02*
X157967Y-19750D01*
X158550Y-20000D01*
X159050D01*
X159550Y-19833D01*
X159883Y-19583D01*
X160050Y-19250D01*
X159967Y-18750D01*
X159633Y-18500D01*
X158133Y-18000D01*
X157800Y-17417D01*
X157967Y-17000D01*
X158300Y-16750D01*
X158800Y-16667D01*
X159300Y-16750D01*
X159800Y-17000D01*
G01X119183Y-2167D02*
X118350Y-1333D01*
X117933Y-500D01*
Y2833D01*
X118350Y3667D01*
X119183Y4500D01*
G01X123450Y167D02*
X124117Y-250D01*
X124867Y-500D01*
X125533D01*
X126200Y-250D01*
X126700Y167D01*
X126950Y750D01*
X126783Y1333D01*
X126367Y1833D01*
X125617Y2167D01*
X124617Y2333D01*
X124033Y2667D01*
X123783Y3250D01*
X123950Y3833D01*
X124367Y4250D01*
X124950Y4500D01*
X125533D01*
X126117Y4333D01*
X126617Y3917D01*
G01X128633Y-500D02*
Y4500D01*
X130800Y333D01*
X132967Y4500D01*
Y-500D01*
G01X134567D02*
Y4500D01*
X136233D01*
X136900Y4250D01*
X137400Y3917D01*
X137817Y3417D01*
X138150Y2833D01*
X138233Y2000D01*
X138150Y1167D01*
X137817Y583D01*
X137400Y83D01*
X136900Y-250D01*
X136233Y-500D01*
X134567D01*
G01X142417Y-2167D02*
X143250Y-1333D01*
X143667Y-500D01*
Y2833D01*
X143250Y3667D01*
X142417Y4500D01*
G01X112250Y12167D02*
X112917Y11750D01*
X113667Y11500D01*
X114333D01*
X115000Y11750D01*
X115500Y12167D01*
X115750Y12750D01*
X115583Y13333D01*
X115167Y13833D01*
X114417Y14167D01*
X113417Y14333D01*
X112833Y14667D01*
X112583Y15250D01*
X112750Y15833D01*
X113167Y16250D01*
X113750Y16500D01*
X114333D01*
X114917Y16333D01*
X115417Y15917D01*
G01X119600Y11500D02*
X119100Y11583D01*
X118600Y11917D01*
X118267Y12500D01*
X118100Y13167D01*
X118267Y13833D01*
X118600Y14417D01*
X119100Y14750D01*
X119600Y14833D01*
X120100Y14750D01*
X120600Y14417D01*
X120933Y13833D01*
X121017Y13167D01*
X120933Y12500D01*
X120600Y11917D01*
X120100Y11583D01*
X119600Y11500D01*
G01X125200D02*
Y16500D01*
G01X132300D02*
Y11500D01*
G01Y12250D02*
X131967Y11833D01*
X131467Y11583D01*
X130883Y11500D01*
X130217Y11667D01*
X129717Y12083D01*
X129383Y12583D01*
X129300Y13167D01*
X129383Y13750D01*
X129717Y14250D01*
X130217Y14667D01*
X130883Y14833D01*
X131467Y14750D01*
X131883Y14583D01*
X132300Y14250D01*
G01X135150Y13750D02*
X137817D01*
X137567Y14333D01*
X137150Y14667D01*
X136567Y14833D01*
X135983Y14750D01*
X135483Y14500D01*
X135150Y13917D01*
X134983Y13417D01*
Y12917D01*
X135150Y12417D01*
X135567Y11917D01*
X136067Y11583D01*
X136650Y11500D01*
X137233Y11667D01*
X137817Y12167D01*
G01X140833Y11500D02*
Y14833D01*
G01Y14167D02*
X141250Y14500D01*
X141667Y14750D01*
X142250Y14833D01*
X142667Y14750D01*
X143167Y14500D01*
G01X150700Y11500D02*
Y14833D01*
G01Y13917D02*
X150950Y14333D01*
X151367Y14667D01*
X151950Y14833D01*
X152533Y14667D01*
X152950Y14333D01*
X153200Y13917D01*
Y11500D01*
G01Y13917D02*
X153450Y14333D01*
X153867Y14667D01*
X154450Y14833D01*
X155033Y14667D01*
X155450Y14333D01*
X155700Y13833D01*
Y11500D01*
G01X160300D02*
Y14833D01*
G01Y14250D02*
X159967Y14583D01*
X159467Y14750D01*
X158883Y14833D01*
X158300Y14667D01*
X157800Y14333D01*
X157467Y13833D01*
X157300Y13167D01*
X157467Y12500D01*
X157800Y12000D01*
X158300Y11667D01*
X158883Y11500D01*
X159467Y11583D01*
X159967Y11833D01*
X160300Y12167D01*
G01X163150Y12083D02*
X163567Y11750D01*
X164150Y11500D01*
X164650D01*
X165150Y11667D01*
X165483Y11917D01*
X165650Y12250D01*
X165567Y12750D01*
X165233Y13000D01*
X163733Y13500D01*
X163400Y14083D01*
X163567Y14500D01*
X163900Y14750D01*
X164400Y14833D01*
X164900Y14750D01*
X165400Y14500D01*
G01X168583Y11500D02*
Y16500D01*
G01X171250Y14833D02*
X168583Y12917D01*
G01X169667Y13667D02*
X171417Y11500D01*
G01X182700Y16500D02*
Y11500D01*
G01Y12250D02*
X182367Y11833D01*
X181867Y11583D01*
X181283Y11500D01*
X180617Y11667D01*
X180117Y12083D01*
X179783Y12583D01*
X179700Y13167D01*
X179783Y13750D01*
X180117Y14250D01*
X180617Y14667D01*
X181283Y14833D01*
X181867Y14750D01*
X182283Y14583D01*
X182700Y14250D01*
G01X185550Y13750D02*
X188217D01*
X187967Y14333D01*
X187550Y14667D01*
X186967Y14833D01*
X186383Y14750D01*
X185883Y14500D01*
X185550Y13917D01*
X185383Y13417D01*
Y12917D01*
X185550Y12417D01*
X185967Y11917D01*
X186467Y11583D01*
X187050Y11500D01*
X187633Y11667D01*
X188217Y12167D01*
G01X191900Y11500D02*
Y15750D01*
X192067Y16167D01*
X192400Y16417D01*
X192900Y16500D01*
X193400Y16333D01*
X193650Y15917D01*
G01X192650Y14500D02*
X190983D01*
G01X198000Y14833D02*
Y11500D01*
G01Y16167D02*
X197833Y16250D01*
Y16417D01*
X198000Y16500D01*
X198167Y16417D01*
Y16250D01*
X198000Y16167D01*
G01X202183Y11500D02*
Y14833D01*
G01Y14000D02*
X202517Y14417D01*
X203017Y14750D01*
X203683Y14833D01*
X204267Y14750D01*
X204767Y14417D01*
X205017Y13833D01*
Y11500D01*
G01X207950Y13750D02*
X210617D01*
X210367Y14333D01*
X209950Y14667D01*
X209367Y14833D01*
X208783Y14750D01*
X208283Y14500D01*
X207950Y13917D01*
X207783Y13417D01*
Y12917D01*
X207950Y12417D01*
X208367Y11917D01*
X208867Y11583D01*
X209450Y11500D01*
X210033Y11667D01*
X210617Y12167D01*
G01X218900Y9833D02*
Y14833D01*
G01Y14083D02*
X219317Y14500D01*
X219733Y14750D01*
X220400Y14833D01*
X220983Y14750D01*
X221567Y14333D01*
X221817Y13750D01*
X221900Y13167D01*
X221817Y12583D01*
X221567Y12000D01*
X221067Y11667D01*
X220400Y11500D01*
X219817Y11583D01*
X219233Y11833D01*
X218900Y12167D01*
G01X227500Y11500D02*
Y14833D01*
G01Y14250D02*
X227167Y14583D01*
X226667Y14750D01*
X226083Y14833D01*
X225500Y14667D01*
X225000Y14333D01*
X224667Y13833D01*
X224500Y13167D01*
X224667Y12500D01*
X225000Y12000D01*
X225500Y11667D01*
X226083Y11500D01*
X226667Y11583D01*
X227167Y11833D01*
X227500Y12167D01*
G01X233100Y16500D02*
Y11500D01*
G01Y12250D02*
X232767Y11833D01*
X232267Y11583D01*
X231683Y11500D01*
X231017Y11667D01*
X230517Y12083D01*
X230183Y12583D01*
X230100Y13167D01*
X230183Y13750D01*
X230517Y14250D01*
X231017Y14667D01*
X231683Y14833D01*
X232267Y14750D01*
X232683Y14583D01*
X233100Y14250D01*
G01X103500Y-9500D02*
X694500D01*
G01X113070Y36130D02*
X114737D01*
Y34630D01*
X114237Y34130D01*
X113653Y33797D01*
X112820Y33630D01*
X111987Y33797D01*
X111403Y34130D01*
X110903Y34630D01*
X110570Y35213D01*
X110403Y35880D01*
Y36463D01*
X110570Y36963D01*
X110903Y37547D01*
X111403Y38047D01*
X111903Y38380D01*
X112570Y38630D01*
X113153D01*
X113820Y38463D01*
X114320Y38130D01*
G01X118170Y33630D02*
X117670Y33713D01*
X117170Y34047D01*
X116837Y34630D01*
X116670Y35297D01*
X116837Y35963D01*
X117170Y36547D01*
X117670Y36880D01*
X118170Y36963D01*
X118670Y36880D01*
X119170Y36547D01*
X119503Y35963D01*
X119587Y35297D01*
X119503Y34630D01*
X119170Y34047D01*
X118670Y33713D01*
X118170Y33630D01*
G01X123770D02*
Y38630D01*
G01X130870D02*
Y33630D01*
G01Y34380D02*
X130537Y33963D01*
X130037Y33713D01*
X129453Y33630D01*
X128787Y33797D01*
X128287Y34213D01*
X127953Y34713D01*
X127870Y35297D01*
X127953Y35880D01*
X128287Y36380D01*
X128787Y36797D01*
X129453Y36963D01*
X130037Y36880D01*
X130453Y36713D01*
X130870Y36380D01*
G01X133720Y35880D02*
X136387D01*
X136137Y36463D01*
X135720Y36797D01*
X135137Y36963D01*
X134553Y36880D01*
X134053Y36630D01*
X133720Y36047D01*
X133553Y35547D01*
Y35047D01*
X133720Y34547D01*
X134137Y34047D01*
X134637Y33713D01*
X135220Y33630D01*
X135803Y33797D01*
X136387Y34297D01*
G01X139153Y33630D02*
Y36963D01*
G01Y36130D02*
X139487Y36547D01*
X139987Y36880D01*
X140653Y36963D01*
X141237Y36880D01*
X141737Y36547D01*
X141987Y35963D01*
Y33630D01*
G01X151270D02*
Y37880D01*
X151437Y38297D01*
X151770Y38547D01*
X152270Y38630D01*
X152770Y38463D01*
X153020Y38047D01*
G01X152020Y36630D02*
X150353D01*
G01X157370Y36963D02*
Y33630D01*
G01Y38297D02*
X157203Y38380D01*
Y38547D01*
X157370Y38630D01*
X157537Y38547D01*
Y38380D01*
X157370Y38297D01*
G01X161553Y33630D02*
Y36963D01*
G01Y36130D02*
X161887Y36547D01*
X162387Y36880D01*
X163053Y36963D01*
X163637Y36880D01*
X164137Y36547D01*
X164387Y35963D01*
Y33630D01*
G01X167403Y32380D02*
X167987Y32047D01*
X168653Y31963D01*
X169237Y32047D01*
X169737Y32463D01*
X170070Y33047D01*
Y36963D01*
G01Y36297D02*
X169737Y36630D01*
X169237Y36880D01*
X168653Y36963D01*
X167987Y36797D01*
X167570Y36463D01*
X167237Y35880D01*
X167070Y35297D01*
X167153Y34797D01*
X167487Y34213D01*
X167987Y33797D01*
X168653Y33630D01*
X169153Y33713D01*
X169737Y34047D01*
X170070Y34380D01*
G01X172920Y35880D02*
X175587D01*
X175337Y36463D01*
X174920Y36797D01*
X174337Y36963D01*
X173753Y36880D01*
X173253Y36630D01*
X172920Y36047D01*
X172753Y35547D01*
Y35047D01*
X172920Y34547D01*
X173337Y34047D01*
X173837Y33713D01*
X174420Y33630D01*
X175003Y33797D01*
X175587Y34297D01*
G01X178603Y33630D02*
Y36963D01*
G01Y36297D02*
X179020Y36630D01*
X179437Y36880D01*
X180020Y36963D01*
X180437Y36880D01*
X180937Y36630D01*
G01X189303Y33630D02*
Y38630D01*
X191303D01*
X191970Y38380D01*
X192470Y37797D01*
X192637Y37130D01*
X192470Y36463D01*
X192053Y35963D01*
X191303Y35713D01*
X189303D01*
G01X194487Y33630D02*
X196570Y38630D01*
X198653Y33630D01*
G01X197903Y35380D02*
X195237D01*
G01X200337Y33630D02*
Y38630D01*
X202003D01*
X202670Y38380D01*
X203170Y38047D01*
X203587Y37547D01*
X203920Y36963D01*
X204003Y36130D01*
X203920Y35297D01*
X203587Y34713D01*
X203170Y34213D01*
X202670Y33880D01*
X202003Y33630D01*
X200337D01*
G01X211870Y33463D02*
X214870Y38630D01*
G01X217387Y33630D02*
Y38630D01*
X220553D01*
G01X219387Y36213D02*
X217387D01*
G01X224570Y36963D02*
Y33630D01*
G01Y38297D02*
X224403Y38380D01*
Y38547D01*
X224570Y38630D01*
X224737Y38547D01*
Y38380D01*
X224570Y38297D01*
G01X231670Y38630D02*
Y33630D01*
G01Y34380D02*
X231337Y33963D01*
X230837Y33713D01*
X230253Y33630D01*
X229587Y33797D01*
X229087Y34213D01*
X228753Y34713D01*
X228670Y35297D01*
X228753Y35880D01*
X229087Y36380D01*
X229587Y36797D01*
X230253Y36963D01*
X230837Y36880D01*
X231253Y36713D01*
X231670Y36380D01*
G01X234353Y36963D02*
Y34630D01*
X234687Y34047D01*
X235187Y33713D01*
X235770Y33630D01*
X236353Y33713D01*
X236853Y34047D01*
X237187Y34630D01*
G01Y33630D02*
Y36963D01*
G01X242703Y36547D02*
X242120Y36880D01*
X241620Y36963D01*
X240953Y36797D01*
X240453Y36463D01*
X240120Y35880D01*
X240037Y35297D01*
X240120Y34713D01*
X240453Y34213D01*
X240953Y33797D01*
X241620Y33630D01*
X242203Y33797D01*
X242703Y34130D01*
G01X246970Y36963D02*
Y33630D01*
G01Y38297D02*
X246803Y38380D01*
Y38547D01*
X246970Y38630D01*
X247137Y38547D01*
Y38380D01*
X246970Y38297D01*
G01X254070Y33630D02*
Y36963D01*
G01Y36380D02*
X253737Y36713D01*
X253237Y36880D01*
X252653Y36963D01*
X252070Y36797D01*
X251570Y36463D01*
X251237Y35963D01*
X251070Y35297D01*
X251237Y34630D01*
X251570Y34130D01*
X252070Y33797D01*
X252653Y33630D01*
X253237Y33713D01*
X253737Y33963D01*
X254070Y34297D01*
G01X258170Y33630D02*
Y38630D01*
G01X112743Y42673D02*
X111910Y43507D01*
X111493Y44340D01*
Y47673D01*
X111910Y48507D01*
X112743Y49340D01*
G01X116260Y44340D02*
Y47673D01*
G01Y46757D02*
X116510Y47173D01*
X116927Y47507D01*
X117510Y47673D01*
X118093Y47507D01*
X118510Y47173D01*
X118760Y46757D01*
Y44340D01*
G01Y46757D02*
X119010Y47173D01*
X119427Y47507D01*
X120010Y47673D01*
X120593Y47507D01*
X121010Y47173D01*
X121260Y46673D01*
Y44340D01*
G01X123110Y46590D02*
X125777D01*
X125527Y47173D01*
X125110Y47507D01*
X124527Y47673D01*
X123943Y47590D01*
X123443Y47340D01*
X123110Y46757D01*
X122943Y46257D01*
Y45757D01*
X123110Y45257D01*
X123527Y44757D01*
X124027Y44423D01*
X124610Y44340D01*
X125193Y44507D01*
X125777Y45007D01*
G01X131460Y44340D02*
Y47673D01*
G01Y47090D02*
X131127Y47423D01*
X130627Y47590D01*
X130043Y47673D01*
X129460Y47507D01*
X128960Y47173D01*
X128627Y46673D01*
X128460Y46007D01*
X128627Y45340D01*
X128960Y44840D01*
X129460Y44507D01*
X130043Y44340D01*
X130627Y44423D01*
X131127Y44673D01*
X131460Y45007D01*
G01X134310Y44923D02*
X134727Y44590D01*
X135310Y44340D01*
X135810D01*
X136310Y44507D01*
X136643Y44757D01*
X136810Y45090D01*
X136727Y45590D01*
X136393Y45840D01*
X134893Y46340D01*
X134560Y46923D01*
X134727Y47340D01*
X135060Y47590D01*
X135560Y47673D01*
X136060Y47590D01*
X136560Y47340D01*
G01X139743Y47673D02*
Y45340D01*
X140077Y44757D01*
X140577Y44423D01*
X141160Y44340D01*
X141743Y44423D01*
X142243Y44757D01*
X142577Y45340D01*
G01Y44340D02*
Y47673D01*
G01X145593Y44340D02*
Y47673D01*
G01Y47007D02*
X146010Y47340D01*
X146427Y47590D01*
X147010Y47673D01*
X147427Y47590D01*
X147927Y47340D01*
G01X151110Y46590D02*
X153777D01*
X153527Y47173D01*
X153110Y47507D01*
X152527Y47673D01*
X151943Y47590D01*
X151443Y47340D01*
X151110Y46757D01*
X150943Y46257D01*
Y45757D01*
X151110Y45257D01*
X151527Y44757D01*
X152027Y44423D01*
X152610Y44340D01*
X153193Y44507D01*
X153777Y45007D01*
G01X163560Y49340D02*
Y44340D01*
G01X162393Y47673D02*
X164727D01*
G01X169160Y44340D02*
X168660Y44423D01*
X168160Y44757D01*
X167827Y45340D01*
X167660Y46007D01*
X167827Y46673D01*
X168160Y47257D01*
X168660Y47590D01*
X169160Y47673D01*
X169660Y47590D01*
X170160Y47257D01*
X170493Y46673D01*
X170577Y46007D01*
X170493Y45340D01*
X170160Y44757D01*
X169660Y44423D01*
X169160Y44340D01*
G01X173260Y42673D02*
Y47673D01*
G01Y46923D02*
X173677Y47340D01*
X174093Y47590D01*
X174760Y47673D01*
X175343Y47590D01*
X175927Y47173D01*
X176177Y46590D01*
X176260Y46007D01*
X176177Y45423D01*
X175927Y44840D01*
X175427Y44507D01*
X174760Y44340D01*
X174177Y44423D01*
X173593Y44673D01*
X173260Y45007D01*
G01X184710Y44923D02*
X185127Y44590D01*
X185710Y44340D01*
X186210D01*
X186710Y44507D01*
X187043Y44757D01*
X187210Y45090D01*
X187127Y45590D01*
X186793Y45840D01*
X185293Y46340D01*
X184960Y46923D01*
X185127Y47340D01*
X185460Y47590D01*
X185960Y47673D01*
X186460Y47590D01*
X186960Y47340D01*
G01X191560Y47673D02*
Y44340D01*
G01Y49007D02*
X191393Y49090D01*
Y49257D01*
X191560Y49340D01*
X191727Y49257D01*
Y49090D01*
X191560Y49007D01*
G01X195910Y47673D02*
X198410D01*
X195910Y44340D01*
X198410D01*
G01X201510Y46590D02*
X204177D01*
X203927Y47173D01*
X203510Y47507D01*
X202927Y47673D01*
X202343Y47590D01*
X201843Y47340D01*
X201510Y46757D01*
X201343Y46257D01*
Y45757D01*
X201510Y45257D01*
X201927Y44757D01*
X202427Y44423D01*
X203010Y44340D01*
X203593Y44507D01*
X204177Y45007D01*
G01X213960Y44340D02*
X213460Y44423D01*
X212960Y44757D01*
X212627Y45340D01*
X212460Y46007D01*
X212627Y46673D01*
X212960Y47257D01*
X213460Y47590D01*
X213960Y47673D01*
X214460Y47590D01*
X214960Y47257D01*
X215293Y46673D01*
X215377Y46007D01*
X215293Y45340D01*
X214960Y44757D01*
X214460Y44423D01*
X213960Y44340D01*
G01X219060D02*
Y48590D01*
X219227Y49007D01*
X219560Y49257D01*
X220060Y49340D01*
X220560Y49173D01*
X220810Y48757D01*
G01X219810Y47340D02*
X218143D01*
G01X229093Y44340D02*
Y49340D01*
X231093D01*
X231760Y49090D01*
X232260Y48507D01*
X232427Y47840D01*
X232260Y47173D01*
X231843Y46673D01*
X231093Y46423D01*
X229093D01*
G01X234277Y44340D02*
X236360Y49340D01*
X238443Y44340D01*
G01X237693Y46090D02*
X235027D01*
G01X240127Y44340D02*
Y49340D01*
X241793D01*
X242460Y49090D01*
X242960Y48757D01*
X243377Y48257D01*
X243710Y47673D01*
X243793Y46840D01*
X243710Y46007D01*
X243377Y45423D01*
X242960Y44923D01*
X242460Y44590D01*
X241793Y44340D01*
X240127D01*
G01X251660Y44173D02*
X254660Y49340D01*
G01X112333Y51500D02*
Y56500D01*
X114333D01*
X115000Y56250D01*
X115500Y55667D01*
X115667Y55000D01*
X115500Y54333D01*
X115083Y53833D01*
X114333Y53583D01*
X112333D01*
G01X117517Y51500D02*
X119600Y56500D01*
X121683Y51500D01*
G01X120933Y53250D02*
X118267D01*
G01X123367Y51500D02*
Y56500D01*
X125033D01*
X125700Y56250D01*
X126200Y55917D01*
X126617Y55417D01*
X126950Y54833D01*
X127033Y54000D01*
X126950Y53167D01*
X126617Y52583D01*
X126200Y52083D01*
X125700Y51750D01*
X125033Y51500D01*
X123367D01*
G01X135150Y52083D02*
X135567Y51750D01*
X136150Y51500D01*
X136650D01*
X137150Y51667D01*
X137483Y51917D01*
X137650Y52250D01*
X137567Y52750D01*
X137233Y53000D01*
X135733Y53500D01*
X135400Y54083D01*
X135567Y54500D01*
X135900Y54750D01*
X136400Y54833D01*
X136900Y54750D01*
X137400Y54500D01*
G01X142000Y54833D02*
Y51500D01*
G01Y56167D02*
X141833Y56250D01*
Y56417D01*
X142000Y56500D01*
X142167Y56417D01*
Y56250D01*
X142000Y56167D01*
G01X146350Y54833D02*
X148850D01*
X146350Y51500D01*
X148850D01*
G01X151950Y53750D02*
X154617D01*
X154367Y54333D01*
X153950Y54667D01*
X153367Y54833D01*
X152783Y54750D01*
X152283Y54500D01*
X151950Y53917D01*
X151783Y53417D01*
Y52917D01*
X151950Y52417D01*
X152367Y51917D01*
X152867Y51583D01*
X153450Y51500D01*
X154033Y51667D01*
X154617Y52167D01*
G01X103500Y60500D02*
X694500D01*
G01X114000Y85000D02*
Y80000D01*
G01X112083Y85000D02*
X115917D01*
G01X118433Y80000D02*
Y83333D01*
G01Y82667D02*
X118850Y83000D01*
X119267Y83250D01*
X119850Y83333D01*
X120267Y83250D01*
X120767Y83000D01*
G01X126700Y80000D02*
Y83333D01*
G01Y82750D02*
X126367Y83083D01*
X125867Y83250D01*
X125283Y83333D01*
X124700Y83167D01*
X124200Y82833D01*
X123867Y82333D01*
X123700Y81667D01*
X123867Y81000D01*
X124200Y80500D01*
X124700Y80167D01*
X125283Y80000D01*
X125867Y80083D01*
X126367Y80333D01*
X126700Y80667D01*
G01X132133Y82917D02*
X131550Y83250D01*
X131050Y83333D01*
X130383Y83167D01*
X129883Y82833D01*
X129550Y82250D01*
X129467Y81667D01*
X129550Y81083D01*
X129883Y80583D01*
X130383Y80167D01*
X131050Y80000D01*
X131633Y80167D01*
X132133Y80500D01*
G01X135150Y82250D02*
X137817D01*
X137567Y82833D01*
X137150Y83167D01*
X136567Y83333D01*
X135983Y83250D01*
X135483Y83000D01*
X135150Y82417D01*
X134983Y81917D01*
Y81417D01*
X135150Y80917D01*
X135567Y80417D01*
X136067Y80083D01*
X136650Y80000D01*
X137233Y80167D01*
X137817Y80667D01*
G01X145517Y83333D02*
X146517Y80000D01*
X147600Y83333D01*
X148683Y80000D01*
X149683Y83333D01*
G01X153200D02*
Y80000D01*
G01Y84667D02*
X153033Y84750D01*
Y84917D01*
X153200Y85000D01*
X153367Y84917D01*
Y84750D01*
X153200Y84667D01*
G01X160300Y85000D02*
Y80000D01*
G01Y80750D02*
X159967Y80333D01*
X159467Y80083D01*
X158883Y80000D01*
X158217Y80167D01*
X157717Y80583D01*
X157383Y81083D01*
X157300Y81667D01*
X157383Y82250D01*
X157717Y82750D01*
X158217Y83167D01*
X158883Y83333D01*
X159467Y83250D01*
X159883Y83083D01*
X160300Y82750D01*
G01X164400Y85000D02*
Y80000D01*
G01X163233Y83333D02*
X165567D01*
G01X168583Y80000D02*
Y85000D01*
G01Y82583D02*
X169000Y83000D01*
X169417Y83250D01*
X170083Y83333D01*
X170583Y83250D01*
X171167Y82917D01*
X171417Y82417D01*
Y80000D01*
G01X112333Y111500D02*
Y116500D01*
X114417D01*
X115083Y116250D01*
X115500Y115917D01*
X115667Y115250D01*
X115500Y114583D01*
X115000Y114167D01*
X114417Y113917D01*
X112333D01*
G01X114417D02*
X115667Y111500D01*
G01X118350Y113750D02*
X121017D01*
X120767Y114333D01*
X120350Y114667D01*
X119767Y114833D01*
X119183Y114750D01*
X118683Y114500D01*
X118350Y113917D01*
X118183Y113417D01*
Y112917D01*
X118350Y112417D01*
X118767Y111917D01*
X119267Y111583D01*
X119850Y111500D01*
X120433Y111667D01*
X121017Y112167D01*
G01X125200Y111500D02*
Y116500D01*
G01X132300Y111500D02*
Y114833D01*
G01Y114250D02*
X131967Y114583D01*
X131467Y114750D01*
X130883Y114833D01*
X130300Y114667D01*
X129800Y114333D01*
X129467Y113833D01*
X129300Y113167D01*
X129467Y112500D01*
X129800Y112000D01*
X130300Y111667D01*
X130883Y111500D01*
X131467Y111583D01*
X131967Y111833D01*
X132300Y112167D01*
G01X136400Y116500D02*
Y111500D01*
G01X135233Y114833D02*
X137567D01*
G01X142000D02*
Y111500D01*
G01Y116167D02*
X141833Y116250D01*
Y116417D01*
X142000Y116500D01*
X142167Y116417D01*
Y116250D01*
X142000Y116167D01*
G01X146100Y114833D02*
X147600Y111500D01*
X149100Y114833D01*
G01X151950Y113750D02*
X154617D01*
X154367Y114333D01*
X153950Y114667D01*
X153367Y114833D01*
X152783Y114750D01*
X152283Y114500D01*
X151950Y113917D01*
X151783Y113417D01*
Y112917D01*
X151950Y112417D01*
X152367Y111917D01*
X152867Y111583D01*
X153450Y111500D01*
X154033Y111667D01*
X154617Y112167D01*
G01X162900Y109833D02*
Y114833D01*
G01Y114083D02*
X163317Y114500D01*
X163733Y114750D01*
X164400Y114833D01*
X164983Y114750D01*
X165567Y114333D01*
X165817Y113750D01*
X165900Y113167D01*
X165817Y112583D01*
X165567Y112000D01*
X165067Y111667D01*
X164400Y111500D01*
X163817Y111583D01*
X163233Y111833D01*
X162900Y112167D01*
G01X170000Y111500D02*
X169500Y111583D01*
X169000Y111917D01*
X168667Y112500D01*
X168500Y113167D01*
X168667Y113833D01*
X169000Y114417D01*
X169500Y114750D01*
X170000Y114833D01*
X170500Y114750D01*
X171000Y114417D01*
X171333Y113833D01*
X171417Y113167D01*
X171333Y112500D01*
X171000Y111917D01*
X170500Y111583D01*
X170000Y111500D01*
G01X174350Y112083D02*
X174767Y111750D01*
X175350Y111500D01*
X175850D01*
X176350Y111667D01*
X176683Y111917D01*
X176850Y112250D01*
X176767Y112750D01*
X176433Y113000D01*
X174933Y113500D01*
X174600Y114083D01*
X174767Y114500D01*
X175100Y114750D01*
X175600Y114833D01*
X176100Y114750D01*
X176600Y114500D01*
G01X181200Y114833D02*
Y111500D01*
G01Y116167D02*
X181033Y116250D01*
Y116417D01*
X181200Y116500D01*
X181367Y116417D01*
Y116250D01*
X181200Y116167D01*
G01X186800Y116500D02*
Y111500D01*
G01X185633Y114833D02*
X187967D01*
G01X192400D02*
Y111500D01*
G01Y116167D02*
X192233Y116250D01*
Y116417D01*
X192400Y116500D01*
X192567Y116417D01*
Y116250D01*
X192400Y116167D01*
G01X198000Y111500D02*
X197500Y111583D01*
X197000Y111917D01*
X196667Y112500D01*
X196500Y113167D01*
X196667Y113833D01*
X197000Y114417D01*
X197500Y114750D01*
X198000Y114833D01*
X198500Y114750D01*
X199000Y114417D01*
X199333Y113833D01*
X199417Y113167D01*
X199333Y112500D01*
X199000Y111917D01*
X198500Y111583D01*
X198000Y111500D01*
G01X202183D02*
Y114833D01*
G01Y114000D02*
X202517Y114417D01*
X203017Y114750D01*
X203683Y114833D01*
X204267Y114750D01*
X204767Y114417D01*
X205017Y113833D01*
Y111500D01*
G01X114000Y143500D02*
Y138500D01*
G01X112833Y141833D02*
X115167D01*
G01X118183Y138500D02*
Y143500D01*
G01Y141083D02*
X118600Y141500D01*
X119017Y141750D01*
X119683Y141833D01*
X120183Y141750D01*
X120767Y141417D01*
X121017Y140917D01*
Y138500D01*
G01X125200Y141833D02*
Y138500D01*
G01Y143167D02*
X125033Y143250D01*
Y143417D01*
X125200Y143500D01*
X125367Y143417D01*
Y143250D01*
X125200Y143167D01*
G01X132133Y141417D02*
X131550Y141750D01*
X131050Y141833D01*
X130383Y141667D01*
X129883Y141333D01*
X129550Y140750D01*
X129467Y140167D01*
X129550Y139583D01*
X129883Y139083D01*
X130383Y138667D01*
X131050Y138500D01*
X131633Y138667D01*
X132133Y139000D01*
G01X134983Y138500D02*
Y143500D01*
G01X137650Y141833D02*
X134983Y139917D01*
G01X136067Y140667D02*
X137817Y138500D01*
G01X140583D02*
Y141833D01*
G01Y141000D02*
X140917Y141417D01*
X141417Y141750D01*
X142083Y141833D01*
X142667Y141750D01*
X143167Y141417D01*
X143417Y140833D01*
Y138500D01*
G01X146350Y140750D02*
X149017D01*
X148767Y141333D01*
X148350Y141667D01*
X147767Y141833D01*
X147183Y141750D01*
X146683Y141500D01*
X146350Y140917D01*
X146183Y140417D01*
Y139917D01*
X146350Y139417D01*
X146767Y138917D01*
X147267Y138583D01*
X147850Y138500D01*
X148433Y138667D01*
X149017Y139167D01*
G01X151950Y139083D02*
X152367Y138750D01*
X152950Y138500D01*
X153450D01*
X153950Y138667D01*
X154283Y138917D01*
X154450Y139250D01*
X154367Y139750D01*
X154033Y140000D01*
X152533Y140500D01*
X152200Y141083D01*
X152367Y141500D01*
X152700Y141750D01*
X153200Y141833D01*
X153700Y141750D01*
X154200Y141500D01*
G01X157550Y139083D02*
X157967Y138750D01*
X158550Y138500D01*
X159050D01*
X159550Y138667D01*
X159883Y138917D01*
X160050Y139250D01*
X159967Y139750D01*
X159633Y140000D01*
X158133Y140500D01*
X157800Y141083D01*
X157967Y141500D01*
X158300Y141750D01*
X158800Y141833D01*
X159300Y141750D01*
X159800Y141500D01*
G01X171500Y138500D02*
Y141833D01*
G01Y141250D02*
X171167Y141583D01*
X170667Y141750D01*
X170083Y141833D01*
X169500Y141667D01*
X169000Y141333D01*
X168667Y140833D01*
X168500Y140167D01*
X168667Y139500D01*
X169000Y139000D01*
X169500Y138667D01*
X170083Y138500D01*
X170667Y138583D01*
X171167Y138833D01*
X171500Y139167D01*
G01X175100Y138500D02*
Y142750D01*
X175267Y143167D01*
X175600Y143417D01*
X176100Y143500D01*
X176600Y143333D01*
X176850Y142917D01*
G01X175850Y141500D02*
X174183D01*
G01X181200Y143500D02*
Y138500D01*
G01X180033Y141833D02*
X182367D01*
G01X185550Y140750D02*
X188217D01*
X187967Y141333D01*
X187550Y141667D01*
X186967Y141833D01*
X186383Y141750D01*
X185883Y141500D01*
X185550Y140917D01*
X185383Y140417D01*
Y139917D01*
X185550Y139417D01*
X185967Y138917D01*
X186467Y138583D01*
X187050Y138500D01*
X187633Y138667D01*
X188217Y139167D01*
G01X191233Y138500D02*
Y141833D01*
G01Y141167D02*
X191650Y141500D01*
X192067Y141750D01*
X192650Y141833D01*
X193067Y141750D01*
X193567Y141500D01*
G01X202100Y136833D02*
Y141833D01*
G01Y141083D02*
X202517Y141500D01*
X202933Y141750D01*
X203600Y141833D01*
X204183Y141750D01*
X204767Y141333D01*
X205017Y140750D01*
X205100Y140167D01*
X205017Y139583D01*
X204767Y139000D01*
X204267Y138667D01*
X203600Y138500D01*
X203017Y138583D01*
X202433Y138833D01*
X202100Y139167D01*
G01X209200Y138500D02*
Y143500D01*
G01X216300Y138500D02*
Y141833D01*
G01Y141250D02*
X215967Y141583D01*
X215467Y141750D01*
X214883Y141833D01*
X214300Y141667D01*
X213800Y141333D01*
X213467Y140833D01*
X213300Y140167D01*
X213467Y139500D01*
X213800Y139000D01*
X214300Y138667D01*
X214883Y138500D01*
X215467Y138583D01*
X215967Y138833D01*
X216300Y139167D01*
G01X220400Y143500D02*
Y138500D01*
G01X219233Y141833D02*
X221567D01*
G01X226000D02*
Y138500D01*
G01Y143167D02*
X225833Y143250D01*
Y143417D01*
X226000Y143500D01*
X226167Y143417D01*
Y143250D01*
X226000Y143167D01*
G01X230183Y138500D02*
Y141833D01*
G01Y141000D02*
X230517Y141417D01*
X231017Y141750D01*
X231683Y141833D01*
X232267Y141750D01*
X232767Y141417D01*
X233017Y140833D01*
Y138500D01*
G01X236033Y137250D02*
X236617Y136917D01*
X237283Y136833D01*
X237867Y136917D01*
X238367Y137333D01*
X238700Y137917D01*
Y141833D01*
G01Y141167D02*
X238367Y141500D01*
X237867Y141750D01*
X237283Y141833D01*
X236617Y141667D01*
X236200Y141333D01*
X235867Y140750D01*
X235700Y140167D01*
X235783Y139667D01*
X236117Y139083D01*
X236617Y138667D01*
X237283Y138500D01*
X237783Y138583D01*
X238367Y138917D01*
X238700Y139250D01*
G01X115667Y148500D02*
X112333D01*
Y153500D01*
X115667D01*
G01X114333Y151083D02*
X112333D01*
G01X118350Y151833D02*
X120850Y148500D01*
G01Y151833D02*
X118350Y148500D01*
G01X125200Y153500D02*
Y148500D01*
G01X124033Y151833D02*
X126367D01*
G01X129550Y150750D02*
X132217D01*
X131967Y151333D01*
X131550Y151667D01*
X130967Y151833D01*
X130383Y151750D01*
X129883Y151500D01*
X129550Y150917D01*
X129383Y150417D01*
Y149917D01*
X129550Y149417D01*
X129967Y148917D01*
X130467Y148583D01*
X131050Y148500D01*
X131633Y148667D01*
X132217Y149167D01*
G01X135233Y148500D02*
Y151833D01*
G01Y151167D02*
X135650Y151500D01*
X136067Y151750D01*
X136650Y151833D01*
X137067Y151750D01*
X137567Y151500D01*
G01X140583Y148500D02*
Y151833D01*
G01Y151000D02*
X140917Y151417D01*
X141417Y151750D01*
X142083Y151833D01*
X142667Y151750D01*
X143167Y151417D01*
X143417Y150833D01*
Y148500D01*
G01X149100D02*
Y151833D01*
G01Y151250D02*
X148767Y151583D01*
X148267Y151750D01*
X147683Y151833D01*
X147100Y151667D01*
X146600Y151333D01*
X146267Y150833D01*
X146100Y150167D01*
X146267Y149500D01*
X146600Y149000D01*
X147100Y148667D01*
X147683Y148500D01*
X148267Y148583D01*
X148767Y148833D01*
X149100Y149167D01*
G01X153200Y148500D02*
Y153500D01*
G01X165733Y151417D02*
X165150Y151750D01*
X164650Y151833D01*
X163983Y151667D01*
X163483Y151333D01*
X163150Y150750D01*
X163067Y150167D01*
X163150Y149583D01*
X163483Y149083D01*
X163983Y148667D01*
X164650Y148500D01*
X165233Y148667D01*
X165733Y149000D01*
G01X170000Y148500D02*
X169500Y148583D01*
X169000Y148917D01*
X168667Y149500D01*
X168500Y150167D01*
X168667Y150833D01*
X169000Y151417D01*
X169500Y151750D01*
X170000Y151833D01*
X170500Y151750D01*
X171000Y151417D01*
X171333Y150833D01*
X171417Y150167D01*
X171333Y149500D01*
X171000Y148917D01*
X170500Y148583D01*
X170000Y148500D01*
G01X174183D02*
Y151833D01*
G01Y151000D02*
X174517Y151417D01*
X175017Y151750D01*
X175683Y151833D01*
X176267Y151750D01*
X176767Y151417D01*
X177017Y150833D01*
Y148500D01*
G01X182700Y153500D02*
Y148500D01*
G01Y149250D02*
X182367Y148833D01*
X181867Y148583D01*
X181283Y148500D01*
X180617Y148667D01*
X180117Y149083D01*
X179783Y149583D01*
X179700Y150167D01*
X179783Y150750D01*
X180117Y151250D01*
X180617Y151667D01*
X181283Y151833D01*
X181867Y151750D01*
X182283Y151583D01*
X182700Y151250D01*
G01X185383Y151833D02*
Y149500D01*
X185717Y148917D01*
X186217Y148583D01*
X186800Y148500D01*
X187383Y148583D01*
X187883Y148917D01*
X188217Y149500D01*
G01Y148500D02*
Y151833D01*
G01X193733Y151417D02*
X193150Y151750D01*
X192650Y151833D01*
X191983Y151667D01*
X191483Y151333D01*
X191150Y150750D01*
X191067Y150167D01*
X191150Y149583D01*
X191483Y149083D01*
X191983Y148667D01*
X192650Y148500D01*
X193233Y148667D01*
X193733Y149000D01*
G01X198000Y153500D02*
Y148500D01*
G01X196833Y151833D02*
X199167D01*
G01X203600Y148500D02*
X203100Y148583D01*
X202600Y148917D01*
X202267Y149500D01*
X202100Y150167D01*
X202267Y150833D01*
X202600Y151417D01*
X203100Y151750D01*
X203600Y151833D01*
X204100Y151750D01*
X204600Y151417D01*
X204933Y150833D01*
X205017Y150167D01*
X204933Y149500D01*
X204600Y148917D01*
X204100Y148583D01*
X203600Y148500D01*
G01X208033D02*
Y151833D01*
G01Y151167D02*
X208450Y151500D01*
X208867Y151750D01*
X209450Y151833D01*
X209867Y151750D01*
X210367Y151500D01*
G01X112333Y356500D02*
Y351500D01*
X115667D01*
G01X121100D02*
Y354833D01*
G01Y354250D02*
X120767Y354583D01*
X120267Y354750D01*
X119683Y354833D01*
X119100Y354667D01*
X118600Y354333D01*
X118267Y353833D01*
X118100Y353167D01*
X118267Y352500D01*
X118600Y352000D01*
X119100Y351667D01*
X119683Y351500D01*
X120267Y351583D01*
X120767Y351833D01*
X121100Y352167D01*
G01X123950Y352083D02*
X124367Y351750D01*
X124950Y351500D01*
X125450D01*
X125950Y351667D01*
X126283Y351917D01*
X126450Y352250D01*
X126367Y352750D01*
X126033Y353000D01*
X124533Y353500D01*
X124200Y354083D01*
X124367Y354500D01*
X124700Y354750D01*
X125200Y354833D01*
X125700Y354750D01*
X126200Y354500D01*
G01X129550Y353750D02*
X132217D01*
X131967Y354333D01*
X131550Y354667D01*
X130967Y354833D01*
X130383Y354750D01*
X129883Y354500D01*
X129550Y353917D01*
X129383Y353417D01*
Y352917D01*
X129550Y352417D01*
X129967Y351917D01*
X130467Y351583D01*
X131050Y351500D01*
X131633Y351667D01*
X132217Y352167D01*
G01X135233Y351500D02*
Y354833D01*
G01Y354167D02*
X135650Y354500D01*
X136067Y354750D01*
X136650Y354833D01*
X137067Y354750D01*
X137567Y354500D01*
G01X146100Y354833D02*
X147600Y351500D01*
X149100Y354833D01*
G01X153200D02*
Y351500D01*
G01Y356167D02*
X153033Y356250D01*
Y356417D01*
X153200Y356500D01*
X153367Y356417D01*
Y356250D01*
X153200Y356167D01*
G01X160300Y351500D02*
Y354833D01*
G01Y354250D02*
X159967Y354583D01*
X159467Y354750D01*
X158883Y354833D01*
X158300Y354667D01*
X157800Y354333D01*
X157467Y353833D01*
X157300Y353167D01*
X157467Y352500D01*
X157800Y352000D01*
X158300Y351667D01*
X158883Y351500D01*
X159467Y351583D01*
X159967Y351833D01*
X160300Y352167D01*
G01X168167Y351333D02*
X171833Y355000D01*
G01X170000Y355667D02*
Y350667D01*
G01X171833Y351333D02*
X168167Y355000D01*
G01X167500Y353167D02*
X172500D01*
G01X175183Y349833D02*
X174350Y350667D01*
X173933Y351500D01*
Y354833D01*
X174350Y355667D01*
X175183Y356500D01*
G01X179367Y352250D02*
X179867Y351833D01*
X180450Y351583D01*
X181200Y351500D01*
X181950Y351667D01*
X182533Y352000D01*
X182950Y352583D01*
X183033Y353250D01*
X182867Y353917D01*
X182450Y354333D01*
X181867Y354667D01*
X181283Y354750D01*
X180700Y354667D01*
X179950Y354333D01*
X180200Y356500D01*
X182450D01*
G01X186800Y351333D02*
X186633Y351417D01*
Y351583D01*
X186800Y351667D01*
X186967Y351583D01*
Y351417D01*
X186800Y351333D01*
G01X192400Y351500D02*
Y356500D01*
X191400Y355500D01*
G01Y351500D02*
X193400D01*
G01X198417Y349833D02*
X199250Y350667D01*
X199667Y351500D01*
Y354833D01*
X199250Y355667D01*
X198417Y356500D01*
G01X112333Y406500D02*
Y411500D01*
X114333D01*
X115000Y411250D01*
X115500Y410667D01*
X115667Y410000D01*
X115500Y409333D01*
X115083Y408833D01*
X114333Y408583D01*
X112333D01*
G01X119600Y411500D02*
Y406500D01*
G01X117683Y411500D02*
X121517D01*
G01X123450Y406500D02*
Y411500D01*
G01X126950D02*
Y406500D01*
G01Y409000D02*
X123450D01*
G01X135233Y406500D02*
Y409833D01*
G01Y409167D02*
X135650Y409500D01*
X136067Y409750D01*
X136650Y409833D01*
X137067Y409750D01*
X137567Y409500D01*
G01X140750Y408750D02*
X143417D01*
X143167Y409333D01*
X142750Y409667D01*
X142167Y409833D01*
X141583Y409750D01*
X141083Y409500D01*
X140750Y408917D01*
X140583Y408417D01*
Y407917D01*
X140750Y407417D01*
X141167Y406917D01*
X141667Y406583D01*
X142250Y406500D01*
X142833Y406667D01*
X143417Y407167D01*
G01X146433Y405250D02*
X147017Y404917D01*
X147683Y404833D01*
X148267Y404917D01*
X148767Y405333D01*
X149100Y405917D01*
Y409833D01*
G01Y409167D02*
X148767Y409500D01*
X148267Y409750D01*
X147683Y409833D01*
X147017Y409667D01*
X146600Y409333D01*
X146267Y408750D01*
X146100Y408167D01*
X146183Y407667D01*
X146517Y407083D01*
X147017Y406667D01*
X147683Y406500D01*
X148183Y406583D01*
X148767Y406917D01*
X149100Y407250D01*
G01X153200Y409833D02*
Y406500D01*
G01Y411167D02*
X153033Y411250D01*
Y411417D01*
X153200Y411500D01*
X153367Y411417D01*
Y411250D01*
X153200Y411167D01*
G01X157550Y407083D02*
X157967Y406750D01*
X158550Y406500D01*
X159050D01*
X159550Y406667D01*
X159883Y406917D01*
X160050Y407250D01*
X159967Y407750D01*
X159633Y408000D01*
X158133Y408500D01*
X157800Y409083D01*
X157967Y409500D01*
X158300Y409750D01*
X158800Y409833D01*
X159300Y409750D01*
X159800Y409500D01*
G01X164400Y411500D02*
Y406500D01*
G01X163233Y409833D02*
X165567D01*
G01X168833Y406500D02*
Y409833D01*
G01Y409167D02*
X169250Y409500D01*
X169667Y409750D01*
X170250Y409833D01*
X170667Y409750D01*
X171167Y409500D01*
G01X177100Y406500D02*
Y409833D01*
G01Y409250D02*
X176767Y409583D01*
X176267Y409750D01*
X175683Y409833D01*
X175100Y409667D01*
X174600Y409333D01*
X174267Y408833D01*
X174100Y408167D01*
X174267Y407500D01*
X174600Y407000D01*
X175100Y406667D01*
X175683Y406500D01*
X176267Y406583D01*
X176767Y406833D01*
X177100Y407167D01*
G01X181200Y411500D02*
Y406500D01*
G01X180033Y409833D02*
X182367D01*
G01X186800D02*
Y406500D01*
G01Y411167D02*
X186633Y411250D01*
Y411417D01*
X186800Y411500D01*
X186967Y411417D01*
Y411250D01*
X186800Y411167D01*
G01X192400Y406500D02*
X191900Y406583D01*
X191400Y406917D01*
X191067Y407500D01*
X190900Y408167D01*
X191067Y408833D01*
X191400Y409417D01*
X191900Y409750D01*
X192400Y409833D01*
X192900Y409750D01*
X193400Y409417D01*
X193733Y408833D01*
X193817Y408167D01*
X193733Y407500D01*
X193400Y406917D01*
X192900Y406583D01*
X192400Y406500D01*
G01X196583D02*
Y409833D01*
G01Y409000D02*
X196917Y409417D01*
X197417Y409750D01*
X198083Y409833D01*
X198667Y409750D01*
X199167Y409417D01*
X199417Y408833D01*
Y406500D01*
G01X105000Y364500D02*
X694500D01*
G01X112167Y433000D02*
Y438000D01*
X113833D01*
X114500Y437750D01*
X115000Y437417D01*
X115417Y436917D01*
X115750Y436333D01*
X115833Y435500D01*
X115750Y434667D01*
X115417Y434083D01*
X115000Y433583D01*
X114500Y433250D01*
X113833Y433000D01*
X112167D01*
G01X118350Y435250D02*
X121017D01*
X120767Y435833D01*
X120350Y436167D01*
X119767Y436333D01*
X119183Y436250D01*
X118683Y436000D01*
X118350Y435417D01*
X118183Y434917D01*
Y434417D01*
X118350Y433917D01*
X118767Y433417D01*
X119267Y433083D01*
X119850Y433000D01*
X120433Y433167D01*
X121017Y433667D01*
G01X123700Y431333D02*
Y436333D01*
G01Y435583D02*
X124117Y436000D01*
X124533Y436250D01*
X125200Y436333D01*
X125783Y436250D01*
X126367Y435833D01*
X126617Y435250D01*
X126700Y434667D01*
X126617Y434083D01*
X126367Y433500D01*
X125867Y433167D01*
X125200Y433000D01*
X124617Y433083D01*
X124033Y433333D01*
X123700Y433667D01*
G01X130800Y438000D02*
Y433000D01*
G01X129633Y436333D02*
X131967D01*
G01X134983Y433000D02*
Y438000D01*
G01Y435583D02*
X135400Y436000D01*
X135817Y436250D01*
X136483Y436333D01*
X136983Y436250D01*
X137567Y435917D01*
X137817Y435417D01*
Y433000D01*
G01X148933Y435917D02*
X148350Y436250D01*
X147850Y436333D01*
X147183Y436167D01*
X146683Y435833D01*
X146350Y435250D01*
X146267Y434667D01*
X146350Y434083D01*
X146683Y433583D01*
X147183Y433167D01*
X147850Y433000D01*
X148433Y433167D01*
X148933Y433500D01*
G01X153200Y433000D02*
X152700Y433083D01*
X152200Y433417D01*
X151867Y434000D01*
X151700Y434667D01*
X151867Y435333D01*
X152200Y435917D01*
X152700Y436250D01*
X153200Y436333D01*
X153700Y436250D01*
X154200Y435917D01*
X154533Y435333D01*
X154617Y434667D01*
X154533Y434000D01*
X154200Y433417D01*
X153700Y433083D01*
X153200Y433000D01*
G01X157383D02*
Y436333D01*
G01Y435500D02*
X157717Y435917D01*
X158217Y436250D01*
X158883Y436333D01*
X159467Y436250D01*
X159967Y435917D01*
X160217Y435333D01*
Y433000D01*
G01X164400Y438000D02*
Y433000D01*
G01X163233Y436333D02*
X165567D01*
G01X168833Y433000D02*
Y436333D01*
G01Y435667D02*
X169250Y436000D01*
X169667Y436250D01*
X170250Y436333D01*
X170667Y436250D01*
X171167Y436000D01*
G01X175600Y433000D02*
X175100Y433083D01*
X174600Y433417D01*
X174267Y434000D01*
X174100Y434667D01*
X174267Y435333D01*
X174600Y435917D01*
X175100Y436250D01*
X175600Y436333D01*
X176100Y436250D01*
X176600Y435917D01*
X176933Y435333D01*
X177017Y434667D01*
X176933Y434000D01*
X176600Y433417D01*
X176100Y433083D01*
X175600Y433000D01*
G01X181200D02*
Y438000D01*
G01X190983Y433000D02*
Y438000D01*
G01Y435583D02*
X191400Y436000D01*
X191817Y436250D01*
X192483Y436333D01*
X192983Y436250D01*
X193567Y435917D01*
X193817Y435417D01*
Y433000D01*
G01X198000D02*
X197500Y433083D01*
X197000Y433417D01*
X196667Y434000D01*
X196500Y434667D01*
X196667Y435333D01*
X197000Y435917D01*
X197500Y436250D01*
X198000Y436333D01*
X198500Y436250D01*
X199000Y435917D01*
X199333Y435333D01*
X199417Y434667D01*
X199333Y434000D01*
X199000Y433417D01*
X198500Y433083D01*
X198000Y433000D01*
G01X203600D02*
Y438000D01*
G01X207950Y435250D02*
X210617D01*
X210367Y435833D01*
X209950Y436167D01*
X209367Y436333D01*
X208783Y436250D01*
X208283Y436000D01*
X207950Y435417D01*
X207783Y434917D01*
Y434417D01*
X207950Y433917D01*
X208367Y433417D01*
X208867Y433083D01*
X209450Y433000D01*
X210033Y433167D01*
X210617Y433667D01*
G01X112333Y455000D02*
Y460000D01*
X114417D01*
X115083Y459750D01*
X115500Y459417D01*
X115667Y458750D01*
X115500Y458083D01*
X115000Y457667D01*
X114417Y457417D01*
X112333D01*
G01X114417D02*
X115667Y455000D01*
G01X119600D02*
X119100Y455083D01*
X118600Y455417D01*
X118267Y456000D01*
X118100Y456667D01*
X118267Y457333D01*
X118600Y457917D01*
X119100Y458250D01*
X119600Y458333D01*
X120100Y458250D01*
X120600Y457917D01*
X120933Y457333D01*
X121017Y456667D01*
X120933Y456000D01*
X120600Y455417D01*
X120100Y455083D01*
X119600Y455000D01*
G01X123783Y458333D02*
Y456000D01*
X124117Y455417D01*
X124617Y455083D01*
X125200Y455000D01*
X125783Y455083D01*
X126283Y455417D01*
X126617Y456000D01*
G01Y455000D02*
Y458333D01*
G01X129633Y453750D02*
X130217Y453417D01*
X130883Y453333D01*
X131467Y453417D01*
X131967Y453833D01*
X132300Y454417D01*
Y458333D01*
G01Y457667D02*
X131967Y458000D01*
X131467Y458250D01*
X130883Y458333D01*
X130217Y458167D01*
X129800Y457833D01*
X129467Y457250D01*
X129300Y456667D01*
X129383Y456167D01*
X129717Y455583D01*
X130217Y455167D01*
X130883Y455000D01*
X131383Y455083D01*
X131967Y455417D01*
X132300Y455750D01*
G01X134983Y455000D02*
Y460000D01*
G01Y457583D02*
X135400Y458000D01*
X135817Y458250D01*
X136483Y458333D01*
X136983Y458250D01*
X137567Y457917D01*
X137817Y457417D01*
Y455000D01*
G01X140583D02*
Y458333D01*
G01Y457500D02*
X140917Y457917D01*
X141417Y458250D01*
X142083Y458333D01*
X142667Y458250D01*
X143167Y457917D01*
X143417Y457333D01*
Y455000D01*
G01X146350Y457250D02*
X149017D01*
X148767Y457833D01*
X148350Y458167D01*
X147767Y458333D01*
X147183Y458250D01*
X146683Y458000D01*
X146350Y457417D01*
X146183Y456917D01*
Y456417D01*
X146350Y455917D01*
X146767Y455417D01*
X147267Y455083D01*
X147850Y455000D01*
X148433Y455167D01*
X149017Y455667D01*
G01X151950Y455583D02*
X152367Y455250D01*
X152950Y455000D01*
X153450D01*
X153950Y455167D01*
X154283Y455417D01*
X154450Y455750D01*
X154367Y456250D01*
X154033Y456500D01*
X152533Y457000D01*
X152200Y457583D01*
X152367Y458000D01*
X152700Y458250D01*
X153200Y458333D01*
X153700Y458250D01*
X154200Y458000D01*
G01X157550Y455583D02*
X157967Y455250D01*
X158550Y455000D01*
X159050D01*
X159550Y455167D01*
X159883Y455417D01*
X160050Y455750D01*
X159967Y456250D01*
X159633Y456500D01*
X158133Y457000D01*
X157800Y457583D01*
X157967Y458000D01*
X158300Y458250D01*
X158800Y458333D01*
X159300Y458250D01*
X159800Y458000D01*
G01X103500Y449000D02*
X694500D01*
G01X103500Y424000D02*
X694500D01*
G01X104000Y464000D02*
X694500D01*
G01X112250Y513500D02*
Y518500D01*
G01X115750D02*
Y513500D01*
G01Y516000D02*
X112250D01*
G01X119600Y513500D02*
X119100Y513583D01*
X118600Y513917D01*
X118267Y514500D01*
X118100Y515167D01*
X118267Y515833D01*
X118600Y516417D01*
X119100Y516750D01*
X119600Y516833D01*
X120100Y516750D01*
X120600Y516417D01*
X120933Y515833D01*
X121017Y515167D01*
X120933Y514500D01*
X120600Y513917D01*
X120100Y513583D01*
X119600Y513500D01*
G01X125200D02*
Y518500D01*
G01X129550Y515750D02*
X132217D01*
X131967Y516333D01*
X131550Y516667D01*
X130967Y516833D01*
X130383Y516750D01*
X129883Y516500D01*
X129550Y515917D01*
X129383Y515417D01*
Y514917D01*
X129550Y514417D01*
X129967Y513917D01*
X130467Y513583D01*
X131050Y513500D01*
X131633Y513667D01*
X132217Y514167D01*
G01X140750Y514083D02*
X141167Y513750D01*
X141750Y513500D01*
X142250D01*
X142750Y513667D01*
X143083Y513917D01*
X143250Y514250D01*
X143167Y514750D01*
X142833Y515000D01*
X141333Y515500D01*
X141000Y516083D01*
X141167Y516500D01*
X141500Y516750D01*
X142000Y516833D01*
X142500Y516750D01*
X143000Y516500D01*
G01X147600Y516833D02*
Y513500D01*
G01Y518167D02*
X147433Y518250D01*
Y518417D01*
X147600Y518500D01*
X147767Y518417D01*
Y518250D01*
X147600Y518167D01*
G01X151950Y516833D02*
X154450D01*
X151950Y513500D01*
X154450D01*
G01X157550Y515750D02*
X160217D01*
X159967Y516333D01*
X159550Y516667D01*
X158967Y516833D01*
X158383Y516750D01*
X157883Y516500D01*
X157550Y515917D01*
X157383Y515417D01*
Y514917D01*
X157550Y514417D01*
X157967Y513917D01*
X158467Y513583D01*
X159050Y513500D01*
X159633Y513667D01*
X160217Y514167D01*
G01X112250Y588500D02*
Y593500D01*
G01X115750D02*
Y588500D01*
G01Y591000D02*
X112250D01*
G01X119600Y588500D02*
X119100Y588583D01*
X118600Y588917D01*
X118267Y589500D01*
X118100Y590167D01*
X118267Y590833D01*
X118600Y591417D01*
X119100Y591750D01*
X119600Y591833D01*
X120100Y591750D01*
X120600Y591417D01*
X120933Y590833D01*
X121017Y590167D01*
X120933Y589500D01*
X120600Y588917D01*
X120100Y588583D01*
X119600Y588500D01*
G01X125200D02*
Y593500D01*
G01X129550Y590750D02*
X132217D01*
X131967Y591333D01*
X131550Y591667D01*
X130967Y591833D01*
X130383Y591750D01*
X129883Y591500D01*
X129550Y590917D01*
X129383Y590417D01*
Y589917D01*
X129550Y589417D01*
X129967Y588917D01*
X130467Y588583D01*
X131050Y588500D01*
X131633Y588667D01*
X132217Y589167D01*
G01X140500Y586833D02*
Y591833D01*
G01Y591083D02*
X140917Y591500D01*
X141333Y591750D01*
X142000Y591833D01*
X142583Y591750D01*
X143167Y591333D01*
X143417Y590750D01*
X143500Y590167D01*
X143417Y589583D01*
X143167Y589000D01*
X142667Y588667D01*
X142000Y588500D01*
X141417Y588583D01*
X140833Y588833D01*
X140500Y589167D01*
G01X147600Y588500D02*
X147100Y588583D01*
X146600Y588917D01*
X146267Y589500D01*
X146100Y590167D01*
X146267Y590833D01*
X146600Y591417D01*
X147100Y591750D01*
X147600Y591833D01*
X148100Y591750D01*
X148600Y591417D01*
X148933Y590833D01*
X149017Y590167D01*
X148933Y589500D01*
X148600Y588917D01*
X148100Y588583D01*
X147600Y588500D01*
G01X151950Y589083D02*
X152367Y588750D01*
X152950Y588500D01*
X153450D01*
X153950Y588667D01*
X154283Y588917D01*
X154450Y589250D01*
X154367Y589750D01*
X154033Y590000D01*
X152533Y590500D01*
X152200Y591083D01*
X152367Y591500D01*
X152700Y591750D01*
X153200Y591833D01*
X153700Y591750D01*
X154200Y591500D01*
G01X158800Y591833D02*
Y588500D01*
G01Y593167D02*
X158633Y593250D01*
Y593417D01*
X158800Y593500D01*
X158967Y593417D01*
Y593250D01*
X158800Y593167D01*
G01X164400Y593500D02*
Y588500D01*
G01X163233Y591833D02*
X165567D01*
G01X170000D02*
Y588500D01*
G01Y593167D02*
X169833Y593250D01*
Y593417D01*
X170000Y593500D01*
X170167Y593417D01*
Y593250D01*
X170000Y593167D01*
G01X175600Y588500D02*
X175100Y588583D01*
X174600Y588917D01*
X174267Y589500D01*
X174100Y590167D01*
X174267Y590833D01*
X174600Y591417D01*
X175100Y591750D01*
X175600Y591833D01*
X176100Y591750D01*
X176600Y591417D01*
X176933Y590833D01*
X177017Y590167D01*
X176933Y589500D01*
X176600Y588917D01*
X176100Y588583D01*
X175600Y588500D01*
G01X179783D02*
Y591833D01*
G01Y591000D02*
X180117Y591417D01*
X180617Y591750D01*
X181283Y591833D01*
X181867Y591750D01*
X182367Y591417D01*
X182617Y590833D01*
Y588500D01*
G01X192400Y593500D02*
Y588500D01*
G01X191233Y591833D02*
X193567D01*
G01X198000Y588500D02*
X197500Y588583D01*
X197000Y588917D01*
X196667Y589500D01*
X196500Y590167D01*
X196667Y590833D01*
X197000Y591417D01*
X197500Y591750D01*
X198000Y591833D01*
X198500Y591750D01*
X199000Y591417D01*
X199333Y590833D01*
X199417Y590167D01*
X199333Y589500D01*
X199000Y588917D01*
X198500Y588583D01*
X198000Y588500D01*
G01X203600D02*
Y593500D01*
G01X207950Y590750D02*
X210617D01*
X210367Y591333D01*
X209950Y591667D01*
X209367Y591833D01*
X208783Y591750D01*
X208283Y591500D01*
X207950Y590917D01*
X207783Y590417D01*
Y589917D01*
X207950Y589417D01*
X208367Y588917D01*
X208867Y588583D01*
X209450Y588500D01*
X210033Y588667D01*
X210617Y589167D01*
G01X213633Y588500D02*
Y591833D01*
G01Y591167D02*
X214050Y591500D01*
X214467Y591750D01*
X215050Y591833D01*
X215467Y591750D01*
X215967Y591500D01*
G01X221900Y588500D02*
Y591833D01*
G01Y591250D02*
X221567Y591583D01*
X221067Y591750D01*
X220483Y591833D01*
X219900Y591667D01*
X219400Y591333D01*
X219067Y590833D01*
X218900Y590167D01*
X219067Y589500D01*
X219400Y589000D01*
X219900Y588667D01*
X220483Y588500D01*
X221067Y588583D01*
X221567Y588833D01*
X221900Y589167D01*
G01X224583Y588500D02*
Y591833D01*
G01Y591000D02*
X224917Y591417D01*
X225417Y591750D01*
X226083Y591833D01*
X226667Y591750D01*
X227167Y591417D01*
X227417Y590833D01*
Y588500D01*
G01X232933Y591417D02*
X232350Y591750D01*
X231850Y591833D01*
X231183Y591667D01*
X230683Y591333D01*
X230350Y590750D01*
X230267Y590167D01*
X230350Y589583D01*
X230683Y589083D01*
X231183Y588667D01*
X231850Y588500D01*
X232433Y588667D01*
X232933Y589000D01*
G01X235950Y590750D02*
X238617D01*
X238367Y591333D01*
X237950Y591667D01*
X237367Y591833D01*
X236783Y591750D01*
X236283Y591500D01*
X235950Y590917D01*
X235783Y590417D01*
Y589917D01*
X235950Y589417D01*
X236367Y588917D01*
X236867Y588583D01*
X237450Y588500D01*
X238033Y588667D01*
X238617Y589167D01*
G01X103500Y584000D02*
X694500D01*
G01X111917Y610000D02*
X114000Y605000D01*
X116083Y610000D01*
G01X119600Y608333D02*
Y605000D01*
G01Y609667D02*
X119433Y609750D01*
Y609917D01*
X119600Y610000D01*
X119767Y609917D01*
Y609750D01*
X119600Y609667D01*
G01X126700Y605000D02*
Y608333D01*
G01Y607750D02*
X126367Y608083D01*
X125867Y608250D01*
X125283Y608333D01*
X124700Y608167D01*
X124200Y607833D01*
X123867Y607333D01*
X123700Y606667D01*
X123867Y606000D01*
X124200Y605500D01*
X124700Y605167D01*
X125283Y605000D01*
X125867Y605083D01*
X126367Y605333D01*
X126700Y605667D01*
G01X134983Y605000D02*
Y610000D01*
G01Y607583D02*
X135400Y608000D01*
X135817Y608250D01*
X136483Y608333D01*
X136983Y608250D01*
X137567Y607917D01*
X137817Y607417D01*
Y605000D01*
G01X142000D02*
X141500Y605083D01*
X141000Y605417D01*
X140667Y606000D01*
X140500Y606667D01*
X140667Y607333D01*
X141000Y607917D01*
X141500Y608250D01*
X142000Y608333D01*
X142500Y608250D01*
X143000Y607917D01*
X143333Y607333D01*
X143417Y606667D01*
X143333Y606000D01*
X143000Y605417D01*
X142500Y605083D01*
X142000Y605000D01*
G01X147600D02*
Y610000D01*
G01X151950Y607250D02*
X154617D01*
X154367Y607833D01*
X153950Y608167D01*
X153367Y608333D01*
X152783Y608250D01*
X152283Y608000D01*
X151950Y607417D01*
X151783Y606917D01*
Y606417D01*
X151950Y605917D01*
X152367Y605417D01*
X152867Y605083D01*
X153450Y605000D01*
X154033Y605167D01*
X154617Y605667D01*
G01X164400Y610000D02*
Y605000D01*
G01X163233Y608333D02*
X165567D01*
G01X168583Y605000D02*
Y610000D01*
G01Y607583D02*
X169000Y608000D01*
X169417Y608250D01*
X170083Y608333D01*
X170583Y608250D01*
X171167Y607917D01*
X171417Y607417D01*
Y605000D01*
G01X174350Y607250D02*
X177017D01*
X176767Y607833D01*
X176350Y608167D01*
X175767Y608333D01*
X175183Y608250D01*
X174683Y608000D01*
X174350Y607417D01*
X174183Y606917D01*
Y606417D01*
X174350Y605917D01*
X174767Y605417D01*
X175267Y605083D01*
X175850Y605000D01*
X176433Y605167D01*
X177017Y605667D01*
G01X180033Y605000D02*
Y608333D01*
G01Y607667D02*
X180450Y608000D01*
X180867Y608250D01*
X181450Y608333D01*
X181867Y608250D01*
X182367Y608000D01*
G01X184300Y605000D02*
Y608333D01*
G01Y607417D02*
X184550Y607833D01*
X184967Y608167D01*
X185550Y608333D01*
X186133Y608167D01*
X186550Y607833D01*
X186800Y607417D01*
Y605000D01*
G01Y607417D02*
X187050Y607833D01*
X187467Y608167D01*
X188050Y608333D01*
X188633Y608167D01*
X189050Y607833D01*
X189300Y607333D01*
Y605000D01*
G01X193900D02*
Y608333D01*
G01Y607750D02*
X193567Y608083D01*
X193067Y608250D01*
X192483Y608333D01*
X191900Y608167D01*
X191400Y607833D01*
X191067Y607333D01*
X190900Y606667D01*
X191067Y606000D01*
X191400Y605500D01*
X191900Y605167D01*
X192483Y605000D01*
X193067Y605083D01*
X193567Y605333D01*
X193900Y605667D01*
G01X198000Y605000D02*
Y610000D01*
G01X207700Y603333D02*
Y608333D01*
G01Y607583D02*
X208117Y608000D01*
X208533Y608250D01*
X209200Y608333D01*
X209783Y608250D01*
X210367Y607833D01*
X210617Y607250D01*
X210700Y606667D01*
X210617Y606083D01*
X210367Y605500D01*
X209867Y605167D01*
X209200Y605000D01*
X208617Y605083D01*
X208033Y605333D01*
X207700Y605667D01*
G01X216300Y605000D02*
Y608333D01*
G01Y607750D02*
X215967Y608083D01*
X215467Y608250D01*
X214883Y608333D01*
X214300Y608167D01*
X213800Y607833D01*
X213467Y607333D01*
X213300Y606667D01*
X213467Y606000D01*
X213800Y605500D01*
X214300Y605167D01*
X214883Y605000D01*
X215467Y605083D01*
X215967Y605333D01*
X216300Y605667D01*
G01X221900Y610000D02*
Y605000D01*
G01Y605750D02*
X221567Y605333D01*
X221067Y605083D01*
X220483Y605000D01*
X219817Y605167D01*
X219317Y605583D01*
X218983Y606083D01*
X218900Y606667D01*
X218983Y607250D01*
X219317Y607750D01*
X219817Y608167D01*
X220483Y608333D01*
X221067Y608250D01*
X221483Y608083D01*
X221900Y607750D01*
G01X111917Y620000D02*
X114000Y625000D01*
X116083Y620000D01*
G01X115333Y621750D02*
X112667D01*
G01X118183Y620000D02*
Y623333D01*
G01Y622500D02*
X118517Y622917D01*
X119017Y623250D01*
X119683Y623333D01*
X120267Y623250D01*
X120767Y622917D01*
X121017Y622333D01*
Y620000D01*
G01X125200Y625000D02*
Y620000D01*
G01X124033Y623333D02*
X126367D01*
G01X130800D02*
Y620000D01*
G01Y624667D02*
X130633Y624750D01*
Y624917D01*
X130800Y625000D01*
X130967Y624917D01*
Y624750D01*
X130800Y624667D01*
G01X135317Y621667D02*
X137483D01*
G01X146100Y618333D02*
Y623333D01*
G01Y622583D02*
X146517Y623000D01*
X146933Y623250D01*
X147600Y623333D01*
X148183Y623250D01*
X148767Y622833D01*
X149017Y622250D01*
X149100Y621667D01*
X149017Y621083D01*
X148767Y620500D01*
X148267Y620167D01*
X147600Y620000D01*
X147017Y620083D01*
X146433Y620333D01*
X146100Y620667D01*
G01X154700Y620000D02*
Y623333D01*
G01Y622750D02*
X154367Y623083D01*
X153867Y623250D01*
X153283Y623333D01*
X152700Y623167D01*
X152200Y622833D01*
X151867Y622333D01*
X151700Y621667D01*
X151867Y621000D01*
X152200Y620500D01*
X152700Y620167D01*
X153283Y620000D01*
X153867Y620083D01*
X154367Y620333D01*
X154700Y620667D01*
G01X160300Y625000D02*
Y620000D01*
G01Y620750D02*
X159967Y620333D01*
X159467Y620083D01*
X158883Y620000D01*
X158217Y620167D01*
X157717Y620583D01*
X157383Y621083D01*
X157300Y621667D01*
X157383Y622250D01*
X157717Y622750D01*
X158217Y623167D01*
X158883Y623333D01*
X159467Y623250D01*
X159883Y623083D01*
X160300Y622750D01*
G01X111843Y639590D02*
Y644590D01*
X115677Y639590D01*
Y644590D01*
G01X119360Y639590D02*
X118860Y639673D01*
X118360Y640007D01*
X118027Y640590D01*
X117860Y641257D01*
X118027Y641923D01*
X118360Y642507D01*
X118860Y642840D01*
X119360Y642923D01*
X119860Y642840D01*
X120360Y642507D01*
X120693Y641923D01*
X120777Y641257D01*
X120693Y640590D01*
X120360Y640007D01*
X119860Y639673D01*
X119360Y639590D01*
G01X123543D02*
Y642923D01*
G01Y642090D02*
X123877Y642507D01*
X124377Y642840D01*
X125043Y642923D01*
X125627Y642840D01*
X126127Y642507D01*
X126377Y641923D01*
Y639590D01*
G01X129477Y641257D02*
X131643D01*
G01X135660Y639590D02*
Y643840D01*
X135827Y644257D01*
X136160Y644507D01*
X136660Y644590D01*
X137160Y644423D01*
X137410Y644007D01*
G01X136410Y642590D02*
X134743D01*
G01X140343Y642923D02*
Y640590D01*
X140677Y640007D01*
X141177Y639673D01*
X141760Y639590D01*
X142343Y639673D01*
X142843Y640007D01*
X143177Y640590D01*
G01Y639590D02*
Y642923D01*
G01X145943Y639590D02*
Y642923D01*
G01Y642090D02*
X146277Y642507D01*
X146777Y642840D01*
X147443Y642923D01*
X148027Y642840D01*
X148527Y642507D01*
X148777Y641923D01*
Y639590D01*
G01X154293Y642507D02*
X153710Y642840D01*
X153210Y642923D01*
X152543Y642757D01*
X152043Y642423D01*
X151710Y641840D01*
X151627Y641257D01*
X151710Y640673D01*
X152043Y640173D01*
X152543Y639757D01*
X153210Y639590D01*
X153793Y639757D01*
X154293Y640090D01*
G01X158560Y644590D02*
Y639590D01*
G01X157393Y642923D02*
X159727D01*
G01X164160D02*
Y639590D01*
G01Y644257D02*
X163993Y644340D01*
Y644507D01*
X164160Y644590D01*
X164327Y644507D01*
Y644340D01*
X164160Y644257D01*
G01X169760Y639590D02*
X169260Y639673D01*
X168760Y640007D01*
X168427Y640590D01*
X168260Y641257D01*
X168427Y641923D01*
X168760Y642507D01*
X169260Y642840D01*
X169760Y642923D01*
X170260Y642840D01*
X170760Y642507D01*
X171093Y641923D01*
X171177Y641257D01*
X171093Y640590D01*
X170760Y640007D01*
X170260Y639673D01*
X169760Y639590D01*
G01X173943D02*
Y642923D01*
G01Y642090D02*
X174277Y642507D01*
X174777Y642840D01*
X175443Y642923D01*
X176027Y642840D01*
X176527Y642507D01*
X176777Y641923D01*
Y639590D01*
G01X182460D02*
Y642923D01*
G01Y642340D02*
X182127Y642673D01*
X181627Y642840D01*
X181043Y642923D01*
X180460Y642757D01*
X179960Y642423D01*
X179627Y641923D01*
X179460Y641257D01*
X179627Y640590D01*
X179960Y640090D01*
X180460Y639757D01*
X181043Y639590D01*
X181627Y639673D01*
X182127Y639923D01*
X182460Y640257D01*
G01X186560Y639590D02*
Y644590D01*
G01X196260Y637923D02*
Y642923D01*
G01Y642173D02*
X196677Y642590D01*
X197093Y642840D01*
X197760Y642923D01*
X198343Y642840D01*
X198927Y642423D01*
X199177Y641840D01*
X199260Y641257D01*
X199177Y640673D01*
X198927Y640090D01*
X198427Y639757D01*
X197760Y639590D01*
X197177Y639673D01*
X196593Y639923D01*
X196260Y640257D01*
G01X204860Y639590D02*
Y642923D01*
G01Y642340D02*
X204527Y642673D01*
X204027Y642840D01*
X203443Y642923D01*
X202860Y642757D01*
X202360Y642423D01*
X202027Y641923D01*
X201860Y641257D01*
X202027Y640590D01*
X202360Y640090D01*
X202860Y639757D01*
X203443Y639590D01*
X204027Y639673D01*
X204527Y639923D01*
X204860Y640257D01*
G01X210460Y644590D02*
Y639590D01*
G01Y640340D02*
X210127Y639923D01*
X209627Y639673D01*
X209043Y639590D01*
X208377Y639757D01*
X207877Y640173D01*
X207543Y640673D01*
X207460Y641257D01*
X207543Y641840D01*
X207877Y642340D01*
X208377Y642757D01*
X209043Y642923D01*
X209627Y642840D01*
X210043Y642673D01*
X210460Y642340D01*
G01X103500Y614000D02*
X694500D01*
G01X103500Y629000D02*
X694500D01*
G01X160333Y668083D02*
X159833Y668333D01*
X159250Y668500D01*
X158583D01*
X157833Y668250D01*
X157250Y667833D01*
X156833Y667333D01*
X156500Y666500D01*
X156417Y665750D01*
X156583Y665000D01*
X156833Y664500D01*
X157333Y664000D01*
X157917Y663667D01*
X158500Y663500D01*
X159083D01*
X159667Y663667D01*
X160167Y663917D01*
X160583Y664250D01*
G01X164100Y663500D02*
Y668500D01*
G01X171200Y663500D02*
Y666833D01*
G01Y666250D02*
X170867Y666583D01*
X170367Y666750D01*
X169783Y666833D01*
X169200Y666667D01*
X168700Y666333D01*
X168367Y665833D01*
X168200Y665167D01*
X168367Y664500D01*
X168700Y664000D01*
X169200Y663667D01*
X169783Y663500D01*
X170367Y663583D01*
X170867Y663833D01*
X171200Y664167D01*
G01X174050Y664083D02*
X174467Y663750D01*
X175050Y663500D01*
X175550D01*
X176050Y663667D01*
X176383Y663917D01*
X176550Y664250D01*
X176467Y664750D01*
X176133Y665000D01*
X174633Y665500D01*
X174300Y666083D01*
X174467Y666500D01*
X174800Y666750D01*
X175300Y666833D01*
X175800Y666750D01*
X176300Y666500D01*
G01X179650Y664083D02*
X180067Y663750D01*
X180650Y663500D01*
X181150D01*
X181650Y663667D01*
X181983Y663917D01*
X182150Y664250D01*
X182067Y664750D01*
X181733Y665000D01*
X180233Y665500D01*
X179900Y666083D01*
X180067Y666500D01*
X180400Y666750D01*
X180900Y666833D01*
X181400Y666750D01*
X181900Y666500D01*
G01X186500Y666833D02*
Y663500D01*
G01Y668167D02*
X186333Y668250D01*
Y668417D01*
X186500Y668500D01*
X186667Y668417D01*
Y668250D01*
X186500Y668167D01*
G01X191600Y663500D02*
Y667750D01*
X191767Y668167D01*
X192100Y668417D01*
X192600Y668500D01*
X193100Y668333D01*
X193350Y667917D01*
G01X192350Y666500D02*
X190683D01*
G01X195950Y662000D02*
X196450Y661833D01*
X197117Y662000D01*
X197533Y662333D01*
X197867Y662750D01*
X198367Y664083D01*
X199450Y666833D01*
G01X196783D02*
X198367Y664083D01*
G01X274000Y-63500D02*
Y-60167D01*
G01Y-60750D02*
X273667Y-60417D01*
X273167Y-60250D01*
X272583Y-60167D01*
X272000Y-60333D01*
X271500Y-60667D01*
X271167Y-61167D01*
X271000Y-61833D01*
X271167Y-62500D01*
X271500Y-63000D01*
X272000Y-63333D01*
X272583Y-63500D01*
X273167Y-63417D01*
X273667Y-63167D01*
X274000Y-62833D01*
G01X279600Y-58500D02*
Y-63500D01*
G01Y-62750D02*
X279267Y-63167D01*
X278767Y-63417D01*
X278183Y-63500D01*
X277517Y-63333D01*
X277017Y-62917D01*
X276683Y-62417D01*
X276600Y-61833D01*
X276683Y-61250D01*
X277017Y-60750D01*
X277517Y-60333D01*
X278183Y-60167D01*
X278767Y-60250D01*
X279183Y-60417D01*
X279600Y-60750D01*
G01X285200Y-58500D02*
Y-63500D01*
G01Y-62750D02*
X284867Y-63167D01*
X284367Y-63417D01*
X283783Y-63500D01*
X283117Y-63333D01*
X282617Y-62917D01*
X282283Y-62417D01*
X282200Y-61833D01*
X282283Y-61250D01*
X282617Y-60750D01*
X283117Y-60333D01*
X283783Y-60167D01*
X284367Y-60250D01*
X284783Y-60417D01*
X285200Y-60750D01*
G01X293650Y-62917D02*
X294067Y-63250D01*
X294650Y-63500D01*
X295150D01*
X295650Y-63333D01*
X295983Y-63083D01*
X296150Y-62750D01*
X296067Y-62250D01*
X295733Y-62000D01*
X294233Y-61500D01*
X293900Y-60917D01*
X294067Y-60500D01*
X294400Y-60250D01*
X294900Y-60167D01*
X295400Y-60250D01*
X295900Y-60500D01*
G01X299083Y-60167D02*
Y-62500D01*
X299417Y-63083D01*
X299917Y-63417D01*
X300500Y-63500D01*
X301083Y-63417D01*
X301583Y-63083D01*
X301917Y-62500D01*
G01Y-63500D02*
Y-60167D01*
G01X304600Y-65167D02*
Y-60167D01*
G01Y-60917D02*
X305017Y-60500D01*
X305433Y-60250D01*
X306100Y-60167D01*
X306683Y-60250D01*
X307267Y-60667D01*
X307517Y-61250D01*
X307600Y-61833D01*
X307517Y-62417D01*
X307267Y-63000D01*
X306767Y-63333D01*
X306100Y-63500D01*
X305517Y-63417D01*
X304933Y-63167D01*
X304600Y-62833D01*
G01X310200Y-65167D02*
Y-60167D01*
G01Y-60917D02*
X310617Y-60500D01*
X311033Y-60250D01*
X311700Y-60167D01*
X312283Y-60250D01*
X312867Y-60667D01*
X313117Y-61250D01*
X313200Y-61833D01*
X313117Y-62417D01*
X312867Y-63000D01*
X312367Y-63333D01*
X311700Y-63500D01*
X311117Y-63417D01*
X310533Y-63167D01*
X310200Y-62833D01*
G01X317300Y-63500D02*
Y-58500D01*
G01X322900Y-60167D02*
Y-63500D01*
G01Y-58833D02*
X322733Y-58750D01*
Y-58583D01*
X322900Y-58500D01*
X323067Y-58583D01*
Y-58750D01*
X322900Y-58833D01*
G01X327250Y-61250D02*
X329917D01*
X329667Y-60667D01*
X329250Y-60333D01*
X328667Y-60167D01*
X328083Y-60250D01*
X327583Y-60500D01*
X327250Y-61083D01*
X327083Y-61583D01*
Y-62083D01*
X327250Y-62583D01*
X327667Y-63083D01*
X328167Y-63417D01*
X328750Y-63500D01*
X329333Y-63333D01*
X329917Y-62833D01*
G01X332933Y-63500D02*
Y-60167D01*
G01Y-60833D02*
X333350Y-60500D01*
X333767Y-60250D01*
X334350Y-60167D01*
X334767Y-60250D01*
X335267Y-60500D01*
G01X339700Y-60167D02*
X340533Y-59125D01*
Y-58500D01*
X339908D01*
Y-59125D01*
X340533D01*
G01X344050Y-62917D02*
X344467Y-63250D01*
X345050Y-63500D01*
X345550D01*
X346050Y-63333D01*
X346383Y-63083D01*
X346550Y-62750D01*
X346467Y-62250D01*
X346133Y-62000D01*
X344633Y-61500D01*
X344300Y-60917D01*
X344467Y-60500D01*
X344800Y-60250D01*
X345300Y-60167D01*
X345800Y-60250D01*
X346300Y-60500D01*
G01X354833Y-58500D02*
Y-63500D01*
X358167D01*
G01X362100D02*
X361600Y-63417D01*
X361100Y-63083D01*
X360767Y-62500D01*
X360600Y-61833D01*
X360767Y-61167D01*
X361100Y-60583D01*
X361600Y-60250D01*
X362100Y-60167D01*
X362600Y-60250D01*
X363100Y-60583D01*
X363433Y-61167D01*
X363517Y-61833D01*
X363433Y-62500D01*
X363100Y-63083D01*
X362600Y-63417D01*
X362100Y-63500D01*
G01X366533Y-64750D02*
X367117Y-65083D01*
X367783Y-65167D01*
X368367Y-65083D01*
X368867Y-64667D01*
X369200Y-64083D01*
Y-60167D01*
G01Y-60833D02*
X368867Y-60500D01*
X368367Y-60250D01*
X367783Y-60167D01*
X367117Y-60333D01*
X366700Y-60667D01*
X366367Y-61250D01*
X366200Y-61833D01*
X366283Y-62333D01*
X366617Y-62917D01*
X367117Y-63333D01*
X367783Y-63500D01*
X368283Y-63417D01*
X368867Y-63083D01*
X369200Y-62750D01*
G01X373300Y-63500D02*
X372800Y-63417D01*
X372300Y-63083D01*
X371967Y-62500D01*
X371800Y-61833D01*
X371967Y-61167D01*
X372300Y-60583D01*
X372800Y-60250D01*
X373300Y-60167D01*
X373800Y-60250D01*
X374300Y-60583D01*
X374633Y-61167D01*
X374717Y-61833D01*
X374633Y-62500D01*
X374300Y-63083D01*
X373800Y-63417D01*
X373300Y-63500D01*
G01X386000D02*
Y-60167D01*
G01Y-60750D02*
X385667Y-60417D01*
X385167Y-60250D01*
X384583Y-60167D01*
X384000Y-60333D01*
X383500Y-60667D01*
X383167Y-61167D01*
X383000Y-61833D01*
X383167Y-62500D01*
X383500Y-63000D01*
X384000Y-63333D01*
X384583Y-63500D01*
X385167Y-63417D01*
X385667Y-63167D01*
X386000Y-62833D01*
G01X388683Y-63500D02*
Y-60167D01*
G01Y-61000D02*
X389017Y-60583D01*
X389517Y-60250D01*
X390183Y-60167D01*
X390767Y-60250D01*
X391267Y-60583D01*
X391517Y-61167D01*
Y-63500D01*
G01X397200Y-58500D02*
Y-63500D01*
G01Y-62750D02*
X396867Y-63167D01*
X396367Y-63417D01*
X395783Y-63500D01*
X395117Y-63333D01*
X394617Y-62917D01*
X394283Y-62417D01*
X394200Y-61833D01*
X394283Y-61250D01*
X394617Y-60750D01*
X395117Y-60333D01*
X395783Y-60167D01*
X396367Y-60250D01*
X396783Y-60417D01*
X397200Y-60750D01*
G01X405067Y-58500D02*
Y-62083D01*
X405400Y-62833D01*
X406067Y-63333D01*
X406900Y-63500D01*
X407733Y-63333D01*
X408400Y-62833D01*
X408733Y-62083D01*
Y-58500D01*
G01X410833D02*
Y-63500D01*
X414167D01*
G01X423200D02*
Y-59250D01*
X423367Y-58833D01*
X423700Y-58583D01*
X424200Y-58500D01*
X424700Y-58667D01*
X424950Y-59083D01*
G01X423950Y-60500D02*
X422283D01*
G01X429300Y-60167D02*
Y-63500D01*
G01Y-58833D02*
X429133Y-58750D01*
Y-58583D01*
X429300Y-58500D01*
X429467Y-58583D01*
Y-58750D01*
X429300Y-58833D01*
G01X434900Y-63500D02*
Y-58500D01*
G01X439250Y-61250D02*
X441917D01*
X441667Y-60667D01*
X441250Y-60333D01*
X440667Y-60167D01*
X440083Y-60250D01*
X439583Y-60500D01*
X439250Y-61083D01*
X439083Y-61583D01*
Y-62083D01*
X439250Y-62583D01*
X439667Y-63083D01*
X440167Y-63417D01*
X440750Y-63500D01*
X441333Y-63333D01*
X441917Y-62833D01*
G01X449783Y-63500D02*
Y-58500D01*
X453617Y-63500D01*
Y-58500D01*
G01X455883Y-60167D02*
Y-62500D01*
X456217Y-63083D01*
X456717Y-63417D01*
X457300Y-63500D01*
X457883Y-63417D01*
X458383Y-63083D01*
X458717Y-62500D01*
G01Y-63500D02*
Y-60167D01*
G01X460400Y-63500D02*
Y-60167D01*
G01Y-61083D02*
X460650Y-60667D01*
X461067Y-60333D01*
X461650Y-60167D01*
X462233Y-60333D01*
X462650Y-60667D01*
X462900Y-61083D01*
Y-63500D01*
G01Y-61083D02*
X463150Y-60667D01*
X463567Y-60333D01*
X464150Y-60167D01*
X464733Y-60333D01*
X465150Y-60667D01*
X465400Y-61167D01*
Y-63500D01*
G01X467000D02*
Y-58500D01*
G01Y-61000D02*
X467417Y-60500D01*
X467917Y-60250D01*
X468417Y-60167D01*
X469167Y-60333D01*
X469667Y-60667D01*
X470000Y-61250D01*
Y-61917D01*
X469833Y-62583D01*
X469500Y-63083D01*
X468917Y-63417D01*
X468417Y-63500D01*
X467917Y-63417D01*
X467417Y-63167D01*
X467000Y-62750D01*
G01X472850Y-61250D02*
X475517D01*
X475267Y-60667D01*
X474850Y-60333D01*
X474267Y-60167D01*
X473683Y-60250D01*
X473183Y-60500D01*
X472850Y-61083D01*
X472683Y-61583D01*
Y-62083D01*
X472850Y-62583D01*
X473267Y-63083D01*
X473767Y-63417D01*
X474350Y-63500D01*
X474933Y-63333D01*
X475517Y-62833D01*
G01X478533Y-63500D02*
Y-60167D01*
G01Y-60833D02*
X478950Y-60500D01*
X479367Y-60250D01*
X479950Y-60167D01*
X480367Y-60250D01*
X480867Y-60500D01*
G01X490900Y-60167D02*
Y-63500D01*
G01Y-58833D02*
X490733Y-58750D01*
Y-58583D01*
X490900Y-58500D01*
X491067Y-58583D01*
Y-58750D01*
X490900Y-58833D01*
G01X495083Y-63500D02*
Y-60167D01*
G01Y-61000D02*
X495417Y-60583D01*
X495917Y-60250D01*
X496583Y-60167D01*
X497167Y-60250D01*
X497667Y-60583D01*
X497917Y-61167D01*
Y-63500D01*
G01X506450Y-62917D02*
X506867Y-63250D01*
X507450Y-63500D01*
X507950D01*
X508450Y-63333D01*
X508783Y-63083D01*
X508950Y-62750D01*
X508867Y-62250D01*
X508533Y-62000D01*
X507033Y-61500D01*
X506700Y-60917D01*
X506867Y-60500D01*
X507200Y-60250D01*
X507700Y-60167D01*
X508200Y-60250D01*
X508700Y-60500D01*
G01X513300Y-60167D02*
Y-63500D01*
G01Y-58833D02*
X513133Y-58750D01*
Y-58583D01*
X513300Y-58500D01*
X513467Y-58583D01*
Y-58750D01*
X513300Y-58833D01*
G01X518900Y-63500D02*
Y-58500D01*
G01X523083Y-63500D02*
Y-58500D01*
G01X525750Y-60167D02*
X523083Y-62083D01*
G01X524167Y-61333D02*
X525917Y-63500D01*
G01X528850Y-62917D02*
X529267Y-63250D01*
X529850Y-63500D01*
X530350D01*
X530850Y-63333D01*
X531183Y-63083D01*
X531350Y-62750D01*
X531267Y-62250D01*
X530933Y-62000D01*
X529433Y-61500D01*
X529100Y-60917D01*
X529267Y-60500D01*
X529600Y-60250D01*
X530100Y-60167D01*
X530600Y-60250D01*
X531100Y-60500D01*
G01X537033Y-60583D02*
X536450Y-60250D01*
X535950Y-60167D01*
X535283Y-60333D01*
X534783Y-60667D01*
X534450Y-61250D01*
X534367Y-61833D01*
X534450Y-62417D01*
X534783Y-62917D01*
X535283Y-63333D01*
X535950Y-63500D01*
X536533Y-63333D01*
X537033Y-63000D01*
G01X540133Y-63500D02*
Y-60167D01*
G01Y-60833D02*
X540550Y-60500D01*
X540967Y-60250D01*
X541550Y-60167D01*
X541967Y-60250D01*
X542467Y-60500D01*
G01X545650Y-61250D02*
X548317D01*
X548067Y-60667D01*
X547650Y-60333D01*
X547067Y-60167D01*
X546483Y-60250D01*
X545983Y-60500D01*
X545650Y-61083D01*
X545483Y-61583D01*
Y-62083D01*
X545650Y-62583D01*
X546067Y-63083D01*
X546567Y-63417D01*
X547150Y-63500D01*
X547733Y-63333D01*
X548317Y-62833D01*
G01X551250Y-61250D02*
X553917D01*
X553667Y-60667D01*
X553250Y-60333D01*
X552667Y-60167D01*
X552083Y-60250D01*
X551583Y-60500D01*
X551250Y-61083D01*
X551083Y-61583D01*
Y-62083D01*
X551250Y-62583D01*
X551667Y-63083D01*
X552167Y-63417D01*
X552750Y-63500D01*
X553333Y-63333D01*
X553917Y-62833D01*
G01X556683Y-63500D02*
Y-60167D01*
G01Y-61000D02*
X557017Y-60583D01*
X557517Y-60250D01*
X558183Y-60167D01*
X558767Y-60250D01*
X559267Y-60583D01*
X559517Y-61167D01*
Y-63500D01*
G01X270750Y-47833D02*
X271417Y-48250D01*
X272167Y-48500D01*
X272833D01*
X273500Y-48250D01*
X274000Y-47833D01*
X274250Y-47250D01*
X274083Y-46667D01*
X273667Y-46167D01*
X272917Y-45833D01*
X271917Y-45667D01*
X271333Y-45333D01*
X271083Y-44750D01*
X271250Y-44167D01*
X271667Y-43750D01*
X272250Y-43500D01*
X272833D01*
X273417Y-43667D01*
X273917Y-44083D01*
G01X278100Y-48500D02*
X277600Y-48417D01*
X277100Y-48083D01*
X276767Y-47500D01*
X276600Y-46833D01*
X276767Y-46167D01*
X277100Y-45583D01*
X277600Y-45250D01*
X278100Y-45167D01*
X278600Y-45250D01*
X279100Y-45583D01*
X279433Y-46167D01*
X279517Y-46833D01*
X279433Y-47500D01*
X279100Y-48083D01*
X278600Y-48417D01*
X278100Y-48500D01*
G01X283700D02*
Y-43500D01*
G01X290800D02*
Y-48500D01*
G01Y-47750D02*
X290467Y-48167D01*
X289967Y-48417D01*
X289383Y-48500D01*
X288717Y-48333D01*
X288217Y-47917D01*
X287883Y-47417D01*
X287800Y-46833D01*
X287883Y-46250D01*
X288217Y-45750D01*
X288717Y-45333D01*
X289383Y-45167D01*
X289967Y-45250D01*
X290383Y-45417D01*
X290800Y-45750D01*
G01X293650Y-46250D02*
X296317D01*
X296067Y-45667D01*
X295650Y-45333D01*
X295067Y-45167D01*
X294483Y-45250D01*
X293983Y-45500D01*
X293650Y-46083D01*
X293483Y-46583D01*
Y-47083D01*
X293650Y-47583D01*
X294067Y-48083D01*
X294567Y-48417D01*
X295150Y-48500D01*
X295733Y-48333D01*
X296317Y-47833D01*
G01X299333Y-48500D02*
Y-45167D01*
G01Y-45833D02*
X299750Y-45500D01*
X300167Y-45250D01*
X300750Y-45167D01*
X301167Y-45250D01*
X301667Y-45500D01*
G01X309200Y-48500D02*
Y-45167D01*
G01Y-46083D02*
X309450Y-45667D01*
X309867Y-45333D01*
X310450Y-45167D01*
X311033Y-45333D01*
X311450Y-45667D01*
X311700Y-46083D01*
Y-48500D01*
G01Y-46083D02*
X311950Y-45667D01*
X312367Y-45333D01*
X312950Y-45167D01*
X313533Y-45333D01*
X313950Y-45667D01*
X314200Y-46167D01*
Y-48500D01*
G01X318800D02*
Y-45167D01*
G01Y-45750D02*
X318467Y-45417D01*
X317967Y-45250D01*
X317383Y-45167D01*
X316800Y-45333D01*
X316300Y-45667D01*
X315967Y-46167D01*
X315800Y-46833D01*
X315967Y-47500D01*
X316300Y-48000D01*
X316800Y-48333D01*
X317383Y-48500D01*
X317967Y-48417D01*
X318467Y-48167D01*
X318800Y-47833D01*
G01X321650Y-47917D02*
X322067Y-48250D01*
X322650Y-48500D01*
X323150D01*
X323650Y-48333D01*
X323983Y-48083D01*
X324150Y-47750D01*
X324067Y-47250D01*
X323733Y-47000D01*
X322233Y-46500D01*
X321900Y-45917D01*
X322067Y-45500D01*
X322400Y-45250D01*
X322900Y-45167D01*
X323400Y-45250D01*
X323900Y-45500D01*
G01X327083Y-48500D02*
Y-43500D01*
G01X329750Y-45167D02*
X327083Y-47083D01*
G01X328167Y-46333D02*
X329917Y-48500D01*
G01X339700Y-43500D02*
Y-48500D01*
G01X338533Y-45167D02*
X340867D01*
G01X343883Y-48500D02*
Y-43500D01*
G01Y-45917D02*
X344300Y-45500D01*
X344717Y-45250D01*
X345383Y-45167D01*
X345883Y-45250D01*
X346467Y-45583D01*
X346717Y-46083D01*
Y-48500D01*
G01X350900Y-45167D02*
Y-48500D01*
G01Y-43833D02*
X350733Y-43750D01*
Y-43583D01*
X350900Y-43500D01*
X351067Y-43583D01*
Y-43750D01*
X350900Y-43833D01*
G01X357833Y-45583D02*
X357250Y-45250D01*
X356750Y-45167D01*
X356083Y-45333D01*
X355583Y-45667D01*
X355250Y-46250D01*
X355167Y-46833D01*
X355250Y-47417D01*
X355583Y-47917D01*
X356083Y-48333D01*
X356750Y-48500D01*
X357333Y-48333D01*
X357833Y-48000D01*
G01X360683Y-48500D02*
Y-43500D01*
G01X363350Y-45167D02*
X360683Y-47083D01*
G01X361767Y-46333D02*
X363517Y-48500D01*
G01X366283D02*
Y-45167D01*
G01Y-46000D02*
X366617Y-45583D01*
X367117Y-45250D01*
X367783Y-45167D01*
X368367Y-45250D01*
X368867Y-45583D01*
X369117Y-46167D01*
Y-48500D01*
G01X372050Y-46250D02*
X374717D01*
X374467Y-45667D01*
X374050Y-45333D01*
X373467Y-45167D01*
X372883Y-45250D01*
X372383Y-45500D01*
X372050Y-46083D01*
X371883Y-46583D01*
Y-47083D01*
X372050Y-47583D01*
X372467Y-48083D01*
X372967Y-48417D01*
X373550Y-48500D01*
X374133Y-48333D01*
X374717Y-47833D01*
G01X377650Y-47917D02*
X378067Y-48250D01*
X378650Y-48500D01*
X379150D01*
X379650Y-48333D01*
X379983Y-48083D01*
X380150Y-47750D01*
X380067Y-47250D01*
X379733Y-47000D01*
X378233Y-46500D01*
X377900Y-45917D01*
X378067Y-45500D01*
X378400Y-45250D01*
X378900Y-45167D01*
X379400Y-45250D01*
X379900Y-45500D01*
G01X383250Y-47917D02*
X383667Y-48250D01*
X384250Y-48500D01*
X384750D01*
X385250Y-48333D01*
X385583Y-48083D01*
X385750Y-47750D01*
X385667Y-47250D01*
X385333Y-47000D01*
X383833Y-46500D01*
X383500Y-45917D01*
X383667Y-45500D01*
X384000Y-45250D01*
X384500Y-45167D01*
X385000Y-45250D01*
X385500Y-45500D01*
G01X394200Y-50167D02*
Y-45167D01*
G01Y-45917D02*
X394617Y-45500D01*
X395033Y-45250D01*
X395700Y-45167D01*
X396283Y-45250D01*
X396867Y-45667D01*
X397117Y-46250D01*
X397200Y-46833D01*
X397117Y-47417D01*
X396867Y-48000D01*
X396367Y-48333D01*
X395700Y-48500D01*
X395117Y-48417D01*
X394533Y-48167D01*
X394200Y-47833D01*
G01X401300Y-48500D02*
Y-43500D01*
G01X405483Y-45167D02*
Y-47500D01*
X405817Y-48083D01*
X406317Y-48417D01*
X406900Y-48500D01*
X407483Y-48417D01*
X407983Y-48083D01*
X408317Y-47500D01*
G01Y-48500D02*
Y-45167D01*
G01X411250Y-47917D02*
X411667Y-48250D01*
X412250Y-48500D01*
X412750D01*
X413250Y-48333D01*
X413583Y-48083D01*
X413750Y-47750D01*
X413667Y-47250D01*
X413333Y-47000D01*
X411833Y-46500D01*
X411500Y-45917D01*
X411667Y-45500D01*
X412000Y-45250D01*
X412500Y-45167D01*
X413000Y-45250D01*
X413500Y-45500D01*
G01X423700Y-48500D02*
Y-43500D01*
G01X428050Y-46250D02*
X430717D01*
X430467Y-45667D01*
X430050Y-45333D01*
X429467Y-45167D01*
X428883Y-45250D01*
X428383Y-45500D01*
X428050Y-46083D01*
X427883Y-46583D01*
Y-47083D01*
X428050Y-47583D01*
X428467Y-48083D01*
X428967Y-48417D01*
X429550Y-48500D01*
X430133Y-48333D01*
X430717Y-47833D01*
G01X433733Y-49750D02*
X434317Y-50083D01*
X434983Y-50167D01*
X435567Y-50083D01*
X436067Y-49667D01*
X436400Y-49083D01*
Y-45167D01*
G01Y-45833D02*
X436067Y-45500D01*
X435567Y-45250D01*
X434983Y-45167D01*
X434317Y-45333D01*
X433900Y-45667D01*
X433567Y-46250D01*
X433400Y-46833D01*
X433483Y-47333D01*
X433817Y-47917D01*
X434317Y-48333D01*
X434983Y-48500D01*
X435483Y-48417D01*
X436067Y-48083D01*
X436400Y-47750D01*
G01X439250Y-46250D02*
X441917D01*
X441667Y-45667D01*
X441250Y-45333D01*
X440667Y-45167D01*
X440083Y-45250D01*
X439583Y-45500D01*
X439250Y-46083D01*
X439083Y-46583D01*
Y-47083D01*
X439250Y-47583D01*
X439667Y-48083D01*
X440167Y-48417D01*
X440750Y-48500D01*
X441333Y-48333D01*
X441917Y-47833D01*
G01X444683Y-48500D02*
Y-45167D01*
G01Y-46000D02*
X445017Y-45583D01*
X445517Y-45250D01*
X446183Y-45167D01*
X446767Y-45250D01*
X447267Y-45583D01*
X447517Y-46167D01*
Y-48500D01*
G01X453200Y-43500D02*
Y-48500D01*
G01Y-47750D02*
X452867Y-48167D01*
X452367Y-48417D01*
X451783Y-48500D01*
X451117Y-48333D01*
X450617Y-47917D01*
X450283Y-47417D01*
X450200Y-46833D01*
X450283Y-46250D01*
X450617Y-45750D01*
X451117Y-45333D01*
X451783Y-45167D01*
X452367Y-45250D01*
X452783Y-45417D01*
X453200Y-45750D01*
G01X462900Y-43500D02*
Y-48500D01*
G01X461733Y-45167D02*
X464067D01*
G01X467083Y-48500D02*
Y-43500D01*
G01Y-45917D02*
X467500Y-45500D01*
X467917Y-45250D01*
X468583Y-45167D01*
X469083Y-45250D01*
X469667Y-45583D01*
X469917Y-46083D01*
Y-48500D01*
G01X474100Y-45167D02*
Y-48500D01*
G01Y-43833D02*
X473933Y-43750D01*
Y-43583D01*
X474100Y-43500D01*
X474267Y-43583D01*
Y-43750D01*
X474100Y-43833D01*
G01X481033Y-45583D02*
X480450Y-45250D01*
X479950Y-45167D01*
X479283Y-45333D01*
X478783Y-45667D01*
X478450Y-46250D01*
X478367Y-46833D01*
X478450Y-47417D01*
X478783Y-47917D01*
X479283Y-48333D01*
X479950Y-48500D01*
X480533Y-48333D01*
X481033Y-48000D01*
G01X483883Y-48500D02*
Y-43500D01*
G01X486550Y-45167D02*
X483883Y-47083D01*
G01X484967Y-46333D02*
X486717Y-48500D01*
G01X489483D02*
Y-45167D01*
G01Y-46000D02*
X489817Y-45583D01*
X490317Y-45250D01*
X490983Y-45167D01*
X491567Y-45250D01*
X492067Y-45583D01*
X492317Y-46167D01*
Y-48500D01*
G01X495250Y-46250D02*
X497917D01*
X497667Y-45667D01*
X497250Y-45333D01*
X496667Y-45167D01*
X496083Y-45250D01*
X495583Y-45500D01*
X495250Y-46083D01*
X495083Y-46583D01*
Y-47083D01*
X495250Y-47583D01*
X495667Y-48083D01*
X496167Y-48417D01*
X496750Y-48500D01*
X497333Y-48333D01*
X497917Y-47833D01*
G01X500850Y-47917D02*
X501267Y-48250D01*
X501850Y-48500D01*
X502350D01*
X502850Y-48333D01*
X503183Y-48083D01*
X503350Y-47750D01*
X503267Y-47250D01*
X502933Y-47000D01*
X501433Y-46500D01*
X501100Y-45917D01*
X501267Y-45500D01*
X501600Y-45250D01*
X502100Y-45167D01*
X502600Y-45250D01*
X503100Y-45500D01*
G01X506450Y-47917D02*
X506867Y-48250D01*
X507450Y-48500D01*
X507950D01*
X508450Y-48333D01*
X508783Y-48083D01*
X508950Y-47750D01*
X508867Y-47250D01*
X508533Y-47000D01*
X507033Y-46500D01*
X506700Y-45917D01*
X506867Y-45500D01*
X507200Y-45250D01*
X507700Y-45167D01*
X508200Y-45250D01*
X508700Y-45500D01*
G01X518900Y-48500D02*
X518400Y-48417D01*
X517900Y-48083D01*
X517567Y-47500D01*
X517400Y-46833D01*
X517567Y-46167D01*
X517900Y-45583D01*
X518400Y-45250D01*
X518900Y-45167D01*
X519400Y-45250D01*
X519900Y-45583D01*
X520233Y-46167D01*
X520317Y-46833D01*
X520233Y-47500D01*
X519900Y-48083D01*
X519400Y-48417D01*
X518900Y-48500D01*
G01X523083D02*
Y-45167D01*
G01Y-46000D02*
X523417Y-45583D01*
X523917Y-45250D01*
X524583Y-45167D01*
X525167Y-45250D01*
X525667Y-45583D01*
X525917Y-46167D01*
Y-48500D01*
G01X535700Y-43500D02*
Y-48500D01*
G01X534533Y-45167D02*
X536867D01*
G01X540133Y-48500D02*
Y-45167D01*
G01Y-45833D02*
X540550Y-45500D01*
X540967Y-45250D01*
X541550Y-45167D01*
X541967Y-45250D01*
X542467Y-45500D01*
G01X548400Y-48500D02*
Y-45167D01*
G01Y-45750D02*
X548067Y-45417D01*
X547567Y-45250D01*
X546983Y-45167D01*
X546400Y-45333D01*
X545900Y-45667D01*
X545567Y-46167D01*
X545400Y-46833D01*
X545567Y-47500D01*
X545900Y-48000D01*
X546400Y-48333D01*
X546983Y-48500D01*
X547567Y-48417D01*
X548067Y-48167D01*
X548400Y-47833D01*
G01X553833Y-45583D02*
X553250Y-45250D01*
X552750Y-45167D01*
X552083Y-45333D01*
X551583Y-45667D01*
X551250Y-46250D01*
X551167Y-46833D01*
X551250Y-47417D01*
X551583Y-47917D01*
X552083Y-48333D01*
X552750Y-48500D01*
X553333Y-48333D01*
X553833Y-48000D01*
G01X556850Y-46250D02*
X559517D01*
X559267Y-45667D01*
X558850Y-45333D01*
X558267Y-45167D01*
X557683Y-45250D01*
X557183Y-45500D01*
X556850Y-46083D01*
X556683Y-46583D01*
Y-47083D01*
X556850Y-47583D01*
X557267Y-48083D01*
X557767Y-48417D01*
X558350Y-48500D01*
X558933Y-48333D01*
X559517Y-47833D01*
G01X563700Y-48667D02*
X563533Y-48583D01*
Y-48417D01*
X563700Y-48333D01*
X563867Y-48417D01*
Y-48583D01*
X563700Y-48667D01*
G01X272500Y-33500D02*
Y-28500D01*
G01X276850Y-31250D02*
X279517D01*
X279267Y-30667D01*
X278850Y-30333D01*
X278267Y-30167D01*
X277683Y-30250D01*
X277183Y-30500D01*
X276850Y-31083D01*
X276683Y-31583D01*
Y-32083D01*
X276850Y-32583D01*
X277267Y-33083D01*
X277767Y-33417D01*
X278350Y-33500D01*
X278933Y-33333D01*
X279517Y-32833D01*
G01X282533Y-34750D02*
X283117Y-35083D01*
X283783Y-35167D01*
X284367Y-35083D01*
X284867Y-34667D01*
X285200Y-34083D01*
Y-30167D01*
G01Y-30833D02*
X284867Y-30500D01*
X284367Y-30250D01*
X283783Y-30167D01*
X283117Y-30333D01*
X282700Y-30667D01*
X282367Y-31250D01*
X282200Y-31833D01*
X282283Y-32333D01*
X282617Y-32917D01*
X283117Y-33333D01*
X283783Y-33500D01*
X284283Y-33417D01*
X284867Y-33083D01*
X285200Y-32750D01*
G01X288050Y-31250D02*
X290717D01*
X290467Y-30667D01*
X290050Y-30333D01*
X289467Y-30167D01*
X288883Y-30250D01*
X288383Y-30500D01*
X288050Y-31083D01*
X287883Y-31583D01*
Y-32083D01*
X288050Y-32583D01*
X288467Y-33083D01*
X288967Y-33417D01*
X289550Y-33500D01*
X290133Y-33333D01*
X290717Y-32833D01*
G01X293483Y-33500D02*
Y-30167D01*
G01Y-31000D02*
X293817Y-30583D01*
X294317Y-30250D01*
X294983Y-30167D01*
X295567Y-30250D01*
X296067Y-30583D01*
X296317Y-31167D01*
Y-33500D01*
G01X302000Y-28500D02*
Y-33500D01*
G01Y-32750D02*
X301667Y-33167D01*
X301167Y-33417D01*
X300583Y-33500D01*
X299917Y-33333D01*
X299417Y-32917D01*
X299083Y-32417D01*
X299000Y-31833D01*
X299083Y-31250D01*
X299417Y-30750D01*
X299917Y-30333D01*
X300583Y-30167D01*
X301167Y-30250D01*
X301583Y-30417D01*
X302000Y-30750D01*
G01X311700Y-28500D02*
Y-33500D01*
G01X310533Y-30167D02*
X312867D01*
G01X315883Y-33500D02*
Y-28500D01*
G01Y-30917D02*
X316300Y-30500D01*
X316717Y-30250D01*
X317383Y-30167D01*
X317883Y-30250D01*
X318467Y-30583D01*
X318717Y-31083D01*
Y-33500D01*
G01X322900Y-30167D02*
Y-33500D01*
G01Y-28833D02*
X322733Y-28750D01*
Y-28583D01*
X322900Y-28500D01*
X323067Y-28583D01*
Y-28750D01*
X322900Y-28833D01*
G01X329833Y-30583D02*
X329250Y-30250D01*
X328750Y-30167D01*
X328083Y-30333D01*
X327583Y-30667D01*
X327250Y-31250D01*
X327167Y-31833D01*
X327250Y-32417D01*
X327583Y-32917D01*
X328083Y-33333D01*
X328750Y-33500D01*
X329333Y-33333D01*
X329833Y-33000D01*
G01X332683Y-33500D02*
Y-28500D01*
G01X335350Y-30167D02*
X332683Y-32083D01*
G01X333767Y-31333D02*
X335517Y-33500D01*
G01X338283D02*
Y-30167D01*
G01Y-31000D02*
X338617Y-30583D01*
X339117Y-30250D01*
X339783Y-30167D01*
X340367Y-30250D01*
X340867Y-30583D01*
X341117Y-31167D01*
Y-33500D01*
G01X344050Y-31250D02*
X346717D01*
X346467Y-30667D01*
X346050Y-30333D01*
X345467Y-30167D01*
X344883Y-30250D01*
X344383Y-30500D01*
X344050Y-31083D01*
X343883Y-31583D01*
Y-32083D01*
X344050Y-32583D01*
X344467Y-33083D01*
X344967Y-33417D01*
X345550Y-33500D01*
X346133Y-33333D01*
X346717Y-32833D01*
G01X349650Y-32917D02*
X350067Y-33250D01*
X350650Y-33500D01*
X351150D01*
X351650Y-33333D01*
X351983Y-33083D01*
X352150Y-32750D01*
X352067Y-32250D01*
X351733Y-32000D01*
X350233Y-31500D01*
X349900Y-30917D01*
X350067Y-30500D01*
X350400Y-30250D01*
X350900Y-30167D01*
X351400Y-30250D01*
X351900Y-30500D01*
G01X355250Y-32917D02*
X355667Y-33250D01*
X356250Y-33500D01*
X356750D01*
X357250Y-33333D01*
X357583Y-33083D01*
X357750Y-32750D01*
X357667Y-32250D01*
X357333Y-32000D01*
X355833Y-31500D01*
X355500Y-30917D01*
X355667Y-30500D01*
X356000Y-30250D01*
X356500Y-30167D01*
X357000Y-30250D01*
X357500Y-30500D01*
G01X367700Y-33500D02*
X367200Y-33417D01*
X366700Y-33083D01*
X366367Y-32500D01*
X366200Y-31833D01*
X366367Y-31167D01*
X366700Y-30583D01*
X367200Y-30250D01*
X367700Y-30167D01*
X368200Y-30250D01*
X368700Y-30583D01*
X369033Y-31167D01*
X369117Y-31833D01*
X369033Y-32500D01*
X368700Y-33083D01*
X368200Y-33417D01*
X367700Y-33500D01*
G01X371883D02*
Y-30167D01*
G01Y-31000D02*
X372217Y-30583D01*
X372717Y-30250D01*
X373383Y-30167D01*
X373967Y-30250D01*
X374467Y-30583D01*
X374717Y-31167D01*
Y-33500D01*
G01X385833Y-30583D02*
X385250Y-30250D01*
X384750Y-30167D01*
X384083Y-30333D01*
X383583Y-30667D01*
X383250Y-31250D01*
X383167Y-31833D01*
X383250Y-32417D01*
X383583Y-32917D01*
X384083Y-33333D01*
X384750Y-33500D01*
X385333Y-33333D01*
X385833Y-33000D01*
G01X390100Y-33500D02*
X389600Y-33417D01*
X389100Y-33083D01*
X388767Y-32500D01*
X388600Y-31833D01*
X388767Y-31167D01*
X389100Y-30583D01*
X389600Y-30250D01*
X390100Y-30167D01*
X390600Y-30250D01*
X391100Y-30583D01*
X391433Y-31167D01*
X391517Y-31833D01*
X391433Y-32500D01*
X391100Y-33083D01*
X390600Y-33417D01*
X390100Y-33500D01*
G01X394200Y-35167D02*
Y-30167D01*
G01Y-30917D02*
X394617Y-30500D01*
X395033Y-30250D01*
X395700Y-30167D01*
X396283Y-30250D01*
X396867Y-30667D01*
X397117Y-31250D01*
X397200Y-31833D01*
X397117Y-32417D01*
X396867Y-33000D01*
X396367Y-33333D01*
X395700Y-33500D01*
X395117Y-33417D01*
X394533Y-33167D01*
X394200Y-32833D01*
G01X399800Y-35167D02*
Y-30167D01*
G01Y-30917D02*
X400217Y-30500D01*
X400633Y-30250D01*
X401300Y-30167D01*
X401883Y-30250D01*
X402467Y-30667D01*
X402717Y-31250D01*
X402800Y-31833D01*
X402717Y-32417D01*
X402467Y-33000D01*
X401967Y-33333D01*
X401300Y-33500D01*
X400717Y-33417D01*
X400133Y-33167D01*
X399800Y-32833D01*
G01X405650Y-31250D02*
X408317D01*
X408067Y-30667D01*
X407650Y-30333D01*
X407067Y-30167D01*
X406483Y-30250D01*
X405983Y-30500D01*
X405650Y-31083D01*
X405483Y-31583D01*
Y-32083D01*
X405650Y-32583D01*
X406067Y-33083D01*
X406567Y-33417D01*
X407150Y-33500D01*
X407733Y-33333D01*
X408317Y-32833D01*
G01X411333Y-33500D02*
Y-30167D01*
G01Y-30833D02*
X411750Y-30500D01*
X412167Y-30250D01*
X412750Y-30167D01*
X413167Y-30250D01*
X413667Y-30500D01*
G01X423283Y-35167D02*
X422450Y-34333D01*
X422033Y-33500D01*
Y-30167D01*
X422450Y-29333D01*
X423283Y-28500D01*
G01X427217Y-30167D02*
X428217Y-33500D01*
X429300Y-30167D01*
X430383Y-33500D01*
X431383Y-30167D01*
G01X433483Y-33500D02*
Y-28500D01*
G01Y-30917D02*
X433900Y-30500D01*
X434317Y-30250D01*
X434983Y-30167D01*
X435483Y-30250D01*
X436067Y-30583D01*
X436317Y-31083D01*
Y-33500D01*
G01X440500Y-30167D02*
Y-33500D01*
G01Y-28833D02*
X440333Y-28750D01*
Y-28583D01*
X440500Y-28500D01*
X440667Y-28583D01*
Y-28750D01*
X440500Y-28833D01*
G01X447433Y-30583D02*
X446850Y-30250D01*
X446350Y-30167D01*
X445683Y-30333D01*
X445183Y-30667D01*
X444850Y-31250D01*
X444767Y-31833D01*
X444850Y-32417D01*
X445183Y-32917D01*
X445683Y-33333D01*
X446350Y-33500D01*
X446933Y-33333D01*
X447433Y-33000D01*
G01X450283Y-33500D02*
Y-28500D01*
G01Y-30917D02*
X450700Y-30500D01*
X451117Y-30250D01*
X451783Y-30167D01*
X452283Y-30250D01*
X452867Y-30583D01*
X453117Y-31083D01*
Y-33500D01*
G01X462900Y-30167D02*
Y-33500D01*
G01Y-28833D02*
X462733Y-28750D01*
Y-28583D01*
X462900Y-28500D01*
X463067Y-28583D01*
Y-28750D01*
X462900Y-28833D01*
G01X467250Y-32917D02*
X467667Y-33250D01*
X468250Y-33500D01*
X468750D01*
X469250Y-33333D01*
X469583Y-33083D01*
X469750Y-32750D01*
X469667Y-32250D01*
X469333Y-32000D01*
X467833Y-31500D01*
X467500Y-30917D01*
X467667Y-30500D01*
X468000Y-30250D01*
X468500Y-30167D01*
X469000Y-30250D01*
X469500Y-30500D01*
G01X478200Y-33500D02*
Y-28500D01*
G01Y-31000D02*
X478617Y-30500D01*
X479117Y-30250D01*
X479617Y-30167D01*
X480367Y-30333D01*
X480867Y-30667D01*
X481200Y-31250D01*
Y-31917D01*
X481033Y-32583D01*
X480700Y-33083D01*
X480117Y-33417D01*
X479617Y-33500D01*
X479117Y-33417D01*
X478617Y-33167D01*
X478200Y-32750D01*
G01X484050Y-31250D02*
X486717D01*
X486467Y-30667D01*
X486050Y-30333D01*
X485467Y-30167D01*
X484883Y-30250D01*
X484383Y-30500D01*
X484050Y-31083D01*
X483883Y-31583D01*
Y-32083D01*
X484050Y-32583D01*
X484467Y-33083D01*
X484967Y-33417D01*
X485550Y-33500D01*
X486133Y-33333D01*
X486717Y-32833D01*
G01X490900Y-28500D02*
Y-33500D01*
G01X489733Y-30167D02*
X492067D01*
G01X496500Y-28500D02*
Y-33500D01*
G01X495333Y-30167D02*
X497667D01*
G01X500850Y-31250D02*
X503517D01*
X503267Y-30667D01*
X502850Y-30333D01*
X502267Y-30167D01*
X501683Y-30250D01*
X501183Y-30500D01*
X500850Y-31083D01*
X500683Y-31583D01*
Y-32083D01*
X500850Y-32583D01*
X501267Y-33083D01*
X501767Y-33417D01*
X502350Y-33500D01*
X502933Y-33333D01*
X503517Y-32833D01*
G01X506533Y-33500D02*
Y-30167D01*
G01Y-30833D02*
X506950Y-30500D01*
X507367Y-30250D01*
X507950Y-30167D01*
X508367Y-30250D01*
X508867Y-30500D01*
G01X513717Y-35167D02*
X514550Y-34333D01*
X514967Y-33500D01*
Y-30167D01*
X514550Y-29333D01*
X513717Y-28500D01*
G01X264000Y-39500D02*
X694500D01*
G01X262500Y-69500D02*
Y439000D01*
G01X272500Y0D02*
Y-5000D01*
G01X270583Y0D02*
X274417D01*
G01X276683Y-5000D02*
Y0D01*
G01Y-2417D02*
X277100Y-2000D01*
X277517Y-1750D01*
X278183Y-1667D01*
X278683Y-1750D01*
X279267Y-2083D01*
X279517Y-2583D01*
Y-5000D01*
G01X282450Y-2750D02*
X285117D01*
X284867Y-2167D01*
X284450Y-1833D01*
X283867Y-1667D01*
X283283Y-1750D01*
X282783Y-2000D01*
X282450Y-2583D01*
X282283Y-3083D01*
Y-3583D01*
X282450Y-4083D01*
X282867Y-4583D01*
X283367Y-4917D01*
X283950Y-5000D01*
X284533Y-4833D01*
X285117Y-4333D01*
G01X294900Y-5000D02*
Y0D01*
G01X302000Y-5000D02*
Y-1667D01*
G01Y-2250D02*
X301667Y-1917D01*
X301167Y-1750D01*
X300583Y-1667D01*
X300000Y-1833D01*
X299500Y-2167D01*
X299167Y-2667D01*
X299000Y-3333D01*
X299167Y-4000D01*
X299500Y-4500D01*
X300000Y-4833D01*
X300583Y-5000D01*
X301167Y-4917D01*
X301667Y-4667D01*
X302000Y-4333D01*
G01X304933Y-5000D02*
Y-1667D01*
G01Y-2333D02*
X305350Y-2000D01*
X305767Y-1750D01*
X306350Y-1667D01*
X306767Y-1750D01*
X307267Y-2000D01*
G01X310533Y-6250D02*
X311117Y-6583D01*
X311783Y-6667D01*
X312367Y-6583D01*
X312867Y-6167D01*
X313200Y-5583D01*
Y-1667D01*
G01Y-2333D02*
X312867Y-2000D01*
X312367Y-1750D01*
X311783Y-1667D01*
X311117Y-1833D01*
X310700Y-2167D01*
X310367Y-2750D01*
X310200Y-3333D01*
X310283Y-3833D01*
X310617Y-4417D01*
X311117Y-4833D01*
X311783Y-5000D01*
X312283Y-4917D01*
X312867Y-4583D01*
X313200Y-4250D01*
G01X316050Y-2750D02*
X318717D01*
X318467Y-2167D01*
X318050Y-1833D01*
X317467Y-1667D01*
X316883Y-1750D01*
X316383Y-2000D01*
X316050Y-2583D01*
X315883Y-3083D01*
Y-3583D01*
X316050Y-4083D01*
X316467Y-4583D01*
X316967Y-4917D01*
X317550Y-5000D01*
X318133Y-4833D01*
X318717Y-4333D01*
G01X321650Y-4417D02*
X322067Y-4750D01*
X322650Y-5000D01*
X323150D01*
X323650Y-4833D01*
X323983Y-4583D01*
X324150Y-4250D01*
X324067Y-3750D01*
X323733Y-3500D01*
X322233Y-3000D01*
X321900Y-2417D01*
X322067Y-2000D01*
X322400Y-1750D01*
X322900Y-1667D01*
X323400Y-1750D01*
X323900Y-2000D01*
G01X328500Y0D02*
Y-5000D01*
G01X327333Y-1667D02*
X329667D01*
G01X341200Y0D02*
Y-5000D01*
G01Y-4250D02*
X340867Y-4667D01*
X340367Y-4917D01*
X339783Y-5000D01*
X339117Y-4833D01*
X338617Y-4417D01*
X338283Y-3917D01*
X338200Y-3333D01*
X338283Y-2750D01*
X338617Y-2250D01*
X339117Y-1833D01*
X339783Y-1667D01*
X340367Y-1750D01*
X340783Y-1917D01*
X341200Y-2250D01*
G01X345300Y-1667D02*
Y-5000D01*
G01Y-333D02*
X345133Y-250D01*
Y-83D01*
X345300Y0D01*
X345467Y-83D01*
Y-250D01*
X345300Y-333D01*
G01X348400Y-5000D02*
Y-1667D01*
G01Y-2583D02*
X348650Y-2167D01*
X349067Y-1833D01*
X349650Y-1667D01*
X350233Y-1833D01*
X350650Y-2167D01*
X350900Y-2583D01*
Y-5000D01*
G01Y-2583D02*
X351150Y-2167D01*
X351567Y-1833D01*
X352150Y-1667D01*
X352733Y-1833D01*
X353150Y-2167D01*
X353400Y-2667D01*
Y-5000D01*
G01X355250Y-2750D02*
X357917D01*
X357667Y-2167D01*
X357250Y-1833D01*
X356667Y-1667D01*
X356083Y-1750D01*
X355583Y-2000D01*
X355250Y-2583D01*
X355083Y-3083D01*
Y-3583D01*
X355250Y-4083D01*
X355667Y-4583D01*
X356167Y-4917D01*
X356750Y-5000D01*
X357333Y-4833D01*
X357917Y-4333D01*
G01X360683Y-5000D02*
Y-1667D01*
G01Y-2500D02*
X361017Y-2083D01*
X361517Y-1750D01*
X362183Y-1667D01*
X362767Y-1750D01*
X363267Y-2083D01*
X363517Y-2667D01*
Y-5000D01*
G01X366450Y-4417D02*
X366867Y-4750D01*
X367450Y-5000D01*
X367950D01*
X368450Y-4833D01*
X368783Y-4583D01*
X368950Y-4250D01*
X368867Y-3750D01*
X368533Y-3500D01*
X367033Y-3000D01*
X366700Y-2417D01*
X366867Y-2000D01*
X367200Y-1750D01*
X367700Y-1667D01*
X368200Y-1750D01*
X368700Y-2000D01*
G01X373300Y-1667D02*
Y-5000D01*
G01Y-333D02*
X373133Y-250D01*
Y-83D01*
X373300Y0D01*
X373467Y-83D01*
Y-250D01*
X373300Y-333D01*
G01X378900Y-5000D02*
X378400Y-4917D01*
X377900Y-4583D01*
X377567Y-4000D01*
X377400Y-3333D01*
X377567Y-2667D01*
X377900Y-2083D01*
X378400Y-1750D01*
X378900Y-1667D01*
X379400Y-1750D01*
X379900Y-2083D01*
X380233Y-2667D01*
X380317Y-3333D01*
X380233Y-4000D01*
X379900Y-4583D01*
X379400Y-4917D01*
X378900Y-5000D01*
G01X383083D02*
Y-1667D01*
G01Y-2500D02*
X383417Y-2083D01*
X383917Y-1750D01*
X384583Y-1667D01*
X385167Y-1750D01*
X385667Y-2083D01*
X385917Y-2667D01*
Y-5000D01*
G01X395700D02*
X395200Y-4917D01*
X394700Y-4583D01*
X394367Y-4000D01*
X394200Y-3333D01*
X394367Y-2667D01*
X394700Y-2083D01*
X395200Y-1750D01*
X395700Y-1667D01*
X396200Y-1750D01*
X396700Y-2083D01*
X397033Y-2667D01*
X397117Y-3333D01*
X397033Y-4000D01*
X396700Y-4583D01*
X396200Y-4917D01*
X395700Y-5000D01*
G01X400800D02*
Y-750D01*
X400967Y-333D01*
X401300Y-83D01*
X401800Y0D01*
X402300Y-167D01*
X402550Y-583D01*
G01X401550Y-2000D02*
X399883D01*
G01X411000Y-6667D02*
Y-1667D01*
G01Y-2417D02*
X411417Y-2000D01*
X411833Y-1750D01*
X412500Y-1667D01*
X413083Y-1750D01*
X413667Y-2167D01*
X413917Y-2750D01*
X414000Y-3333D01*
X413917Y-3917D01*
X413667Y-4500D01*
X413167Y-4833D01*
X412500Y-5000D01*
X411917Y-4917D01*
X411333Y-4667D01*
X411000Y-4333D01*
G01X419600Y-5000D02*
Y-1667D01*
G01Y-2250D02*
X419267Y-1917D01*
X418767Y-1750D01*
X418183Y-1667D01*
X417600Y-1833D01*
X417100Y-2167D01*
X416767Y-2667D01*
X416600Y-3333D01*
X416767Y-4000D01*
X417100Y-4500D01*
X417600Y-4833D01*
X418183Y-5000D01*
X418767Y-4917D01*
X419267Y-4667D01*
X419600Y-4333D01*
G01X425200Y0D02*
Y-5000D01*
G01Y-4250D02*
X424867Y-4667D01*
X424367Y-4917D01*
X423783Y-5000D01*
X423117Y-4833D01*
X422617Y-4417D01*
X422283Y-3917D01*
X422200Y-3333D01*
X422283Y-2750D01*
X422617Y-2250D01*
X423117Y-1833D01*
X423783Y-1667D01*
X424367Y-1750D01*
X424783Y-1917D01*
X425200Y-2250D01*
G01X434900Y-5000D02*
X434400Y-4917D01*
X433900Y-4583D01*
X433567Y-4000D01*
X433400Y-3333D01*
X433567Y-2667D01*
X433900Y-2083D01*
X434400Y-1750D01*
X434900Y-1667D01*
X435400Y-1750D01*
X435900Y-2083D01*
X436233Y-2667D01*
X436317Y-3333D01*
X436233Y-4000D01*
X435900Y-4583D01*
X435400Y-4917D01*
X434900Y-5000D01*
G01X439333D02*
Y-1667D01*
G01Y-2333D02*
X439750Y-2000D01*
X440167Y-1750D01*
X440750Y-1667D01*
X441167Y-1750D01*
X441667Y-2000D01*
G01X453200Y0D02*
Y-5000D01*
G01Y-4250D02*
X452867Y-4667D01*
X452367Y-4917D01*
X451783Y-5000D01*
X451117Y-4833D01*
X450617Y-4417D01*
X450283Y-3917D01*
X450200Y-3333D01*
X450283Y-2750D01*
X450617Y-2250D01*
X451117Y-1833D01*
X451783Y-1667D01*
X452367Y-1750D01*
X452783Y-1917D01*
X453200Y-2250D01*
G01X457300Y-1667D02*
Y-5000D01*
G01Y-333D02*
X457133Y-250D01*
Y-83D01*
X457300Y0D01*
X457467Y-83D01*
Y-250D01*
X457300Y-333D01*
G01X464400Y-5000D02*
Y-1667D01*
G01Y-2250D02*
X464067Y-1917D01*
X463567Y-1750D01*
X462983Y-1667D01*
X462400Y-1833D01*
X461900Y-2167D01*
X461567Y-2667D01*
X461400Y-3333D01*
X461567Y-4000D01*
X461900Y-4500D01*
X462400Y-4833D01*
X462983Y-5000D01*
X463567Y-4917D01*
X464067Y-4667D01*
X464400Y-4333D01*
G01X466000Y-5000D02*
Y-1667D01*
G01Y-2583D02*
X466250Y-2167D01*
X466667Y-1833D01*
X467250Y-1667D01*
X467833Y-1833D01*
X468250Y-2167D01*
X468500Y-2583D01*
Y-5000D01*
G01Y-2583D02*
X468750Y-2167D01*
X469167Y-1833D01*
X469750Y-1667D01*
X470333Y-1833D01*
X470750Y-2167D01*
X471000Y-2667D01*
Y-5000D01*
G01X472850Y-2750D02*
X475517D01*
X475267Y-2167D01*
X474850Y-1833D01*
X474267Y-1667D01*
X473683Y-1750D01*
X473183Y-2000D01*
X472850Y-2583D01*
X472683Y-3083D01*
Y-3583D01*
X472850Y-4083D01*
X473267Y-4583D01*
X473767Y-4917D01*
X474350Y-5000D01*
X474933Y-4833D01*
X475517Y-4333D01*
G01X479700Y0D02*
Y-5000D01*
G01X478533Y-1667D02*
X480867D01*
G01X484050Y-2750D02*
X486717D01*
X486467Y-2167D01*
X486050Y-1833D01*
X485467Y-1667D01*
X484883Y-1750D01*
X484383Y-2000D01*
X484050Y-2583D01*
X483883Y-3083D01*
Y-3583D01*
X484050Y-4083D01*
X484467Y-4583D01*
X484967Y-4917D01*
X485550Y-5000D01*
X486133Y-4833D01*
X486717Y-4333D01*
G01X489733Y-5000D02*
Y-1667D01*
G01Y-2333D02*
X490150Y-2000D01*
X490567Y-1750D01*
X491150Y-1667D01*
X491567Y-1750D01*
X492067Y-2000D01*
G01X503767Y-5000D02*
X500433Y-3333D01*
X503767Y-1667D01*
G01X506617Y-4083D02*
X508783D01*
G01Y-2583D02*
X506617D01*
G01X518900Y-5000D02*
Y0D01*
X517900Y-1000D01*
G01Y-5000D02*
X519900D01*
G01X525500D02*
Y0D01*
X522417Y-3583D01*
X526583D01*
G01X533200Y-5000D02*
Y-1667D01*
G01Y-2583D02*
X533450Y-2167D01*
X533867Y-1833D01*
X534450Y-1667D01*
X535033Y-1833D01*
X535450Y-2167D01*
X535700Y-2583D01*
Y-5000D01*
G01Y-2583D02*
X535950Y-2167D01*
X536367Y-1833D01*
X536950Y-1667D01*
X537533Y-1833D01*
X537950Y-2167D01*
X538200Y-2667D01*
Y-5000D01*
G01X541300Y-1667D02*
Y-5000D01*
G01Y-333D02*
X541133Y-250D01*
Y-83D01*
X541300Y0D01*
X541467Y-83D01*
Y-250D01*
X541300Y-333D01*
G01X546900Y-5000D02*
Y0D01*
G01X271250Y-19417D02*
X271667Y-19750D01*
X272250Y-20000D01*
X272750D01*
X273250Y-19833D01*
X273583Y-19583D01*
X273750Y-19250D01*
X273667Y-18750D01*
X273333Y-18500D01*
X271833Y-18000D01*
X271500Y-17417D01*
X271667Y-17000D01*
X272000Y-16750D01*
X272500Y-16667D01*
X273000Y-16750D01*
X273500Y-17000D01*
G01X278100Y-20000D02*
X277600Y-19917D01*
X277100Y-19583D01*
X276767Y-19000D01*
X276600Y-18333D01*
X276767Y-17667D01*
X277100Y-17083D01*
X277600Y-16750D01*
X278100Y-16667D01*
X278600Y-16750D01*
X279100Y-17083D01*
X279433Y-17667D01*
X279517Y-18333D01*
X279433Y-19000D01*
X279100Y-19583D01*
X278600Y-19917D01*
X278100Y-20000D01*
G01X283700D02*
Y-15000D01*
G01X290800D02*
Y-20000D01*
G01Y-19250D02*
X290467Y-19667D01*
X289967Y-19917D01*
X289383Y-20000D01*
X288717Y-19833D01*
X288217Y-19417D01*
X287883Y-18917D01*
X287800Y-18333D01*
X287883Y-17750D01*
X288217Y-17250D01*
X288717Y-16833D01*
X289383Y-16667D01*
X289967Y-16750D01*
X290383Y-16917D01*
X290800Y-17250D01*
G01X293650Y-17750D02*
X296317D01*
X296067Y-17167D01*
X295650Y-16833D01*
X295067Y-16667D01*
X294483Y-16750D01*
X293983Y-17000D01*
X293650Y-17583D01*
X293483Y-18083D01*
Y-18583D01*
X293650Y-19083D01*
X294067Y-19583D01*
X294567Y-19917D01*
X295150Y-20000D01*
X295733Y-19833D01*
X296317Y-19333D01*
G01X299333Y-20000D02*
Y-16667D01*
G01Y-17333D02*
X299750Y-17000D01*
X300167Y-16750D01*
X300750Y-16667D01*
X301167Y-16750D01*
X301667Y-17000D01*
G01X309200Y-20000D02*
Y-16667D01*
G01Y-17583D02*
X309450Y-17167D01*
X309867Y-16833D01*
X310450Y-16667D01*
X311033Y-16833D01*
X311450Y-17167D01*
X311700Y-17583D01*
Y-20000D01*
G01Y-17583D02*
X311950Y-17167D01*
X312367Y-16833D01*
X312950Y-16667D01*
X313533Y-16833D01*
X313950Y-17167D01*
X314200Y-17667D01*
Y-20000D01*
G01X318800D02*
Y-16667D01*
G01Y-17250D02*
X318467Y-16917D01*
X317967Y-16750D01*
X317383Y-16667D01*
X316800Y-16833D01*
X316300Y-17167D01*
X315967Y-17667D01*
X315800Y-18333D01*
X315967Y-19000D01*
X316300Y-19500D01*
X316800Y-19833D01*
X317383Y-20000D01*
X317967Y-19917D01*
X318467Y-19667D01*
X318800Y-19333D01*
G01X321650Y-19417D02*
X322067Y-19750D01*
X322650Y-20000D01*
X323150D01*
X323650Y-19833D01*
X323983Y-19583D01*
X324150Y-19250D01*
X324067Y-18750D01*
X323733Y-18500D01*
X322233Y-18000D01*
X321900Y-17417D01*
X322067Y-17000D01*
X322400Y-16750D01*
X322900Y-16667D01*
X323400Y-16750D01*
X323900Y-17000D01*
G01X327083Y-20000D02*
Y-15000D01*
G01X329750Y-16667D02*
X327083Y-18583D01*
G01X328167Y-17833D02*
X329917Y-20000D01*
G01X339700Y-15000D02*
Y-20000D01*
G01X338533Y-16667D02*
X340867D01*
G01X343883Y-20000D02*
Y-15000D01*
G01Y-17417D02*
X344300Y-17000D01*
X344717Y-16750D01*
X345383Y-16667D01*
X345883Y-16750D01*
X346467Y-17083D01*
X346717Y-17583D01*
Y-20000D01*
G01X350900Y-16667D02*
Y-20000D01*
G01Y-15333D02*
X350733Y-15250D01*
Y-15083D01*
X350900Y-15000D01*
X351067Y-15083D01*
Y-15250D01*
X350900Y-15333D01*
G01X357833Y-17083D02*
X357250Y-16750D01*
X356750Y-16667D01*
X356083Y-16833D01*
X355583Y-17167D01*
X355250Y-17750D01*
X355167Y-18333D01*
X355250Y-18917D01*
X355583Y-19417D01*
X356083Y-19833D01*
X356750Y-20000D01*
X357333Y-19833D01*
X357833Y-19500D01*
G01X360683Y-20000D02*
Y-15000D01*
G01X363350Y-16667D02*
X360683Y-18583D01*
G01X361767Y-17833D02*
X363517Y-20000D01*
G01X366283D02*
Y-16667D01*
G01Y-17500D02*
X366617Y-17083D01*
X367117Y-16750D01*
X367783Y-16667D01*
X368367Y-16750D01*
X368867Y-17083D01*
X369117Y-17667D01*
Y-20000D01*
G01X372050Y-17750D02*
X374717D01*
X374467Y-17167D01*
X374050Y-16833D01*
X373467Y-16667D01*
X372883Y-16750D01*
X372383Y-17000D01*
X372050Y-17583D01*
X371883Y-18083D01*
Y-18583D01*
X372050Y-19083D01*
X372467Y-19583D01*
X372967Y-19917D01*
X373550Y-20000D01*
X374133Y-19833D01*
X374717Y-19333D01*
G01X377650Y-19417D02*
X378067Y-19750D01*
X378650Y-20000D01*
X379150D01*
X379650Y-19833D01*
X379983Y-19583D01*
X380150Y-19250D01*
X380067Y-18750D01*
X379733Y-18500D01*
X378233Y-18000D01*
X377900Y-17417D01*
X378067Y-17000D01*
X378400Y-16750D01*
X378900Y-16667D01*
X379400Y-16750D01*
X379900Y-17000D01*
G01X383250Y-19417D02*
X383667Y-19750D01*
X384250Y-20000D01*
X384750D01*
X385250Y-19833D01*
X385583Y-19583D01*
X385750Y-19250D01*
X385667Y-18750D01*
X385333Y-18500D01*
X383833Y-18000D01*
X383500Y-17417D01*
X383667Y-17000D01*
X384000Y-16750D01*
X384500Y-16667D01*
X385000Y-16750D01*
X385500Y-17000D01*
G01X272500Y15000D02*
Y10000D01*
G01X270583Y15000D02*
X274417D01*
G01X276683Y10000D02*
Y15000D01*
G01Y12583D02*
X277100Y13000D01*
X277517Y13250D01*
X278183Y13333D01*
X278683Y13250D01*
X279267Y12917D01*
X279517Y12417D01*
Y10000D01*
G01X282450Y12250D02*
X285117D01*
X284867Y12833D01*
X284450Y13167D01*
X283867Y13333D01*
X283283Y13250D01*
X282783Y13000D01*
X282450Y12417D01*
X282283Y11917D01*
Y11417D01*
X282450Y10917D01*
X282867Y10417D01*
X283367Y10083D01*
X283950Y10000D01*
X284533Y10167D01*
X285117Y10667D01*
G01X294900Y10000D02*
Y15000D01*
G01X302000Y10000D02*
Y13333D01*
G01Y12750D02*
X301667Y13083D01*
X301167Y13250D01*
X300583Y13333D01*
X300000Y13167D01*
X299500Y12833D01*
X299167Y12333D01*
X299000Y11667D01*
X299167Y11000D01*
X299500Y10500D01*
X300000Y10167D01*
X300583Y10000D01*
X301167Y10083D01*
X301667Y10333D01*
X302000Y10667D01*
G01X304933Y10000D02*
Y13333D01*
G01Y12667D02*
X305350Y13000D01*
X305767Y13250D01*
X306350Y13333D01*
X306767Y13250D01*
X307267Y13000D01*
G01X310533Y8750D02*
X311117Y8417D01*
X311783Y8333D01*
X312367Y8417D01*
X312867Y8833D01*
X313200Y9417D01*
Y13333D01*
G01Y12667D02*
X312867Y13000D01*
X312367Y13250D01*
X311783Y13333D01*
X311117Y13167D01*
X310700Y12833D01*
X310367Y12250D01*
X310200Y11667D01*
X310283Y11167D01*
X310617Y10583D01*
X311117Y10167D01*
X311783Y10000D01*
X312283Y10083D01*
X312867Y10417D01*
X313200Y10750D01*
G01X316050Y12250D02*
X318717D01*
X318467Y12833D01*
X318050Y13167D01*
X317467Y13333D01*
X316883Y13250D01*
X316383Y13000D01*
X316050Y12417D01*
X315883Y11917D01*
Y11417D01*
X316050Y10917D01*
X316467Y10417D01*
X316967Y10083D01*
X317550Y10000D01*
X318133Y10167D01*
X318717Y10667D01*
G01X321650Y10583D02*
X322067Y10250D01*
X322650Y10000D01*
X323150D01*
X323650Y10167D01*
X323983Y10417D01*
X324150Y10750D01*
X324067Y11250D01*
X323733Y11500D01*
X322233Y12000D01*
X321900Y12583D01*
X322067Y13000D01*
X322400Y13250D01*
X322900Y13333D01*
X323400Y13250D01*
X323900Y13000D01*
G01X328500Y15000D02*
Y10000D01*
G01X327333Y13333D02*
X329667D01*
G01X341200Y15000D02*
Y10000D01*
G01Y10750D02*
X340867Y10333D01*
X340367Y10083D01*
X339783Y10000D01*
X339117Y10167D01*
X338617Y10583D01*
X338283Y11083D01*
X338200Y11667D01*
X338283Y12250D01*
X338617Y12750D01*
X339117Y13167D01*
X339783Y13333D01*
X340367Y13250D01*
X340783Y13083D01*
X341200Y12750D01*
G01X345300Y13333D02*
Y10000D01*
G01Y14667D02*
X345133Y14750D01*
Y14917D01*
X345300Y15000D01*
X345467Y14917D01*
Y14750D01*
X345300Y14667D01*
G01X348400Y10000D02*
Y13333D01*
G01Y12417D02*
X348650Y12833D01*
X349067Y13167D01*
X349650Y13333D01*
X350233Y13167D01*
X350650Y12833D01*
X350900Y12417D01*
Y10000D01*
G01Y12417D02*
X351150Y12833D01*
X351567Y13167D01*
X352150Y13333D01*
X352733Y13167D01*
X353150Y12833D01*
X353400Y12333D01*
Y10000D01*
G01X355250Y12250D02*
X357917D01*
X357667Y12833D01*
X357250Y13167D01*
X356667Y13333D01*
X356083Y13250D01*
X355583Y13000D01*
X355250Y12417D01*
X355083Y11917D01*
Y11417D01*
X355250Y10917D01*
X355667Y10417D01*
X356167Y10083D01*
X356750Y10000D01*
X357333Y10167D01*
X357917Y10667D01*
G01X360683Y10000D02*
Y13333D01*
G01Y12500D02*
X361017Y12917D01*
X361517Y13250D01*
X362183Y13333D01*
X362767Y13250D01*
X363267Y12917D01*
X363517Y12333D01*
Y10000D01*
G01X366450Y10583D02*
X366867Y10250D01*
X367450Y10000D01*
X367950D01*
X368450Y10167D01*
X368783Y10417D01*
X368950Y10750D01*
X368867Y11250D01*
X368533Y11500D01*
X367033Y12000D01*
X366700Y12583D01*
X366867Y13000D01*
X367200Y13250D01*
X367700Y13333D01*
X368200Y13250D01*
X368700Y13000D01*
G01X373300Y13333D02*
Y10000D01*
G01Y14667D02*
X373133Y14750D01*
Y14917D01*
X373300Y15000D01*
X373467Y14917D01*
Y14750D01*
X373300Y14667D01*
G01X378900Y10000D02*
X378400Y10083D01*
X377900Y10417D01*
X377567Y11000D01*
X377400Y11667D01*
X377567Y12333D01*
X377900Y12917D01*
X378400Y13250D01*
X378900Y13333D01*
X379400Y13250D01*
X379900Y12917D01*
X380233Y12333D01*
X380317Y11667D01*
X380233Y11000D01*
X379900Y10417D01*
X379400Y10083D01*
X378900Y10000D01*
G01X383083D02*
Y13333D01*
G01Y12500D02*
X383417Y12917D01*
X383917Y13250D01*
X384583Y13333D01*
X385167Y13250D01*
X385667Y12917D01*
X385917Y12333D01*
Y10000D01*
G01X395700D02*
X395200Y10083D01*
X394700Y10417D01*
X394367Y11000D01*
X394200Y11667D01*
X394367Y12333D01*
X394700Y12917D01*
X395200Y13250D01*
X395700Y13333D01*
X396200Y13250D01*
X396700Y12917D01*
X397033Y12333D01*
X397117Y11667D01*
X397033Y11000D01*
X396700Y10417D01*
X396200Y10083D01*
X395700Y10000D01*
G01X400800D02*
Y14250D01*
X400967Y14667D01*
X401300Y14917D01*
X401800Y15000D01*
X402300Y14833D01*
X402550Y14417D01*
G01X401550Y13000D02*
X399883D01*
G01X411000Y8333D02*
Y13333D01*
G01Y12583D02*
X411417Y13000D01*
X411833Y13250D01*
X412500Y13333D01*
X413083Y13250D01*
X413667Y12833D01*
X413917Y12250D01*
X414000Y11667D01*
X413917Y11083D01*
X413667Y10500D01*
X413167Y10167D01*
X412500Y10000D01*
X411917Y10083D01*
X411333Y10333D01*
X411000Y10667D01*
G01X419600Y10000D02*
Y13333D01*
G01Y12750D02*
X419267Y13083D01*
X418767Y13250D01*
X418183Y13333D01*
X417600Y13167D01*
X417100Y12833D01*
X416767Y12333D01*
X416600Y11667D01*
X416767Y11000D01*
X417100Y10500D01*
X417600Y10167D01*
X418183Y10000D01*
X418767Y10083D01*
X419267Y10333D01*
X419600Y10667D01*
G01X425200Y15000D02*
Y10000D01*
G01Y10750D02*
X424867Y10333D01*
X424367Y10083D01*
X423783Y10000D01*
X423117Y10167D01*
X422617Y10583D01*
X422283Y11083D01*
X422200Y11667D01*
X422283Y12250D01*
X422617Y12750D01*
X423117Y13167D01*
X423783Y13333D01*
X424367Y13250D01*
X424783Y13083D01*
X425200Y12750D01*
G01X434900Y10000D02*
X434400Y10083D01*
X433900Y10417D01*
X433567Y11000D01*
X433400Y11667D01*
X433567Y12333D01*
X433900Y12917D01*
X434400Y13250D01*
X434900Y13333D01*
X435400Y13250D01*
X435900Y12917D01*
X436233Y12333D01*
X436317Y11667D01*
X436233Y11000D01*
X435900Y10417D01*
X435400Y10083D01*
X434900Y10000D01*
G01X439333D02*
Y13333D01*
G01Y12667D02*
X439750Y13000D01*
X440167Y13250D01*
X440750Y13333D01*
X441167Y13250D01*
X441667Y13000D01*
G01X453200Y15000D02*
Y10000D01*
G01Y10750D02*
X452867Y10333D01*
X452367Y10083D01*
X451783Y10000D01*
X451117Y10167D01*
X450617Y10583D01*
X450283Y11083D01*
X450200Y11667D01*
X450283Y12250D01*
X450617Y12750D01*
X451117Y13167D01*
X451783Y13333D01*
X452367Y13250D01*
X452783Y13083D01*
X453200Y12750D01*
G01X457300Y13333D02*
Y10000D01*
G01Y14667D02*
X457133Y14750D01*
Y14917D01*
X457300Y15000D01*
X457467Y14917D01*
Y14750D01*
X457300Y14667D01*
G01X464400Y10000D02*
Y13333D01*
G01Y12750D02*
X464067Y13083D01*
X463567Y13250D01*
X462983Y13333D01*
X462400Y13167D01*
X461900Y12833D01*
X461567Y12333D01*
X461400Y11667D01*
X461567Y11000D01*
X461900Y10500D01*
X462400Y10167D01*
X462983Y10000D01*
X463567Y10083D01*
X464067Y10333D01*
X464400Y10667D01*
G01X466000Y10000D02*
Y13333D01*
G01Y12417D02*
X466250Y12833D01*
X466667Y13167D01*
X467250Y13333D01*
X467833Y13167D01*
X468250Y12833D01*
X468500Y12417D01*
Y10000D01*
G01Y12417D02*
X468750Y12833D01*
X469167Y13167D01*
X469750Y13333D01*
X470333Y13167D01*
X470750Y12833D01*
X471000Y12333D01*
Y10000D01*
G01X472850Y12250D02*
X475517D01*
X475267Y12833D01*
X474850Y13167D01*
X474267Y13333D01*
X473683Y13250D01*
X473183Y13000D01*
X472850Y12417D01*
X472683Y11917D01*
Y11417D01*
X472850Y10917D01*
X473267Y10417D01*
X473767Y10083D01*
X474350Y10000D01*
X474933Y10167D01*
X475517Y10667D01*
G01X479700Y15000D02*
Y10000D01*
G01X478533Y13333D02*
X480867D01*
G01X484050Y12250D02*
X486717D01*
X486467Y12833D01*
X486050Y13167D01*
X485467Y13333D01*
X484883Y13250D01*
X484383Y13000D01*
X484050Y12417D01*
X483883Y11917D01*
Y11417D01*
X484050Y10917D01*
X484467Y10417D01*
X484967Y10083D01*
X485550Y10000D01*
X486133Y10167D01*
X486717Y10667D01*
G01X489733Y10000D02*
Y13333D01*
G01Y12667D02*
X490150Y13000D01*
X490567Y13250D01*
X491150Y13333D01*
X491567Y13250D01*
X492067Y13000D01*
G01X500433Y10000D02*
X503767Y11667D01*
X500433Y13333D01*
G01X507700Y10000D02*
Y15000D01*
X506700Y14000D01*
G01Y10000D02*
X508700D01*
G01X514300D02*
Y15000D01*
X511217Y11417D01*
X515383D01*
G01X522000Y10000D02*
Y13333D01*
G01Y12417D02*
X522250Y12833D01*
X522667Y13167D01*
X523250Y13333D01*
X523833Y13167D01*
X524250Y12833D01*
X524500Y12417D01*
Y10000D01*
G01Y12417D02*
X524750Y12833D01*
X525167Y13167D01*
X525750Y13333D01*
X526333Y13167D01*
X526750Y12833D01*
X527000Y12333D01*
Y10000D01*
G01X530100Y13333D02*
Y10000D01*
G01Y14667D02*
X529933Y14750D01*
Y14917D01*
X530100Y15000D01*
X530267Y14917D01*
Y14750D01*
X530100Y14667D01*
G01X535700Y10000D02*
Y15000D01*
G01X264000Y5500D02*
X694500D01*
G01X272500Y71500D02*
Y66500D01*
G01X271333Y69833D02*
X273667D01*
G01X276933Y66500D02*
Y69833D01*
G01Y69167D02*
X277350Y69500D01*
X277767Y69750D01*
X278350Y69833D01*
X278767Y69750D01*
X279267Y69500D01*
G01X285200Y66500D02*
Y69833D01*
G01Y69250D02*
X284867Y69583D01*
X284367Y69750D01*
X283783Y69833D01*
X283200Y69667D01*
X282700Y69333D01*
X282367Y68833D01*
X282200Y68167D01*
X282367Y67500D01*
X282700Y67000D01*
X283200Y66667D01*
X283783Y66500D01*
X284367Y66583D01*
X284867Y66833D01*
X285200Y67167D01*
G01X290633Y69417D02*
X290050Y69750D01*
X289550Y69833D01*
X288883Y69667D01*
X288383Y69333D01*
X288050Y68750D01*
X287967Y68167D01*
X288050Y67583D01*
X288383Y67083D01*
X288883Y66667D01*
X289550Y66500D01*
X290133Y66667D01*
X290633Y67000D01*
G01X293650Y68750D02*
X296317D01*
X296067Y69333D01*
X295650Y69667D01*
X295067Y69833D01*
X294483Y69750D01*
X293983Y69500D01*
X293650Y68917D01*
X293483Y68417D01*
Y67917D01*
X293650Y67417D01*
X294067Y66917D01*
X294567Y66583D01*
X295150Y66500D01*
X295733Y66667D01*
X296317Y67167D01*
G01X304017Y69833D02*
X305017Y66500D01*
X306100Y69833D01*
X307183Y66500D01*
X308183Y69833D01*
G01X311700D02*
Y66500D01*
G01Y71167D02*
X311533Y71250D01*
Y71417D01*
X311700Y71500D01*
X311867Y71417D01*
Y71250D01*
X311700Y71167D01*
G01X318800Y71500D02*
Y66500D01*
G01Y67250D02*
X318467Y66833D01*
X317967Y66583D01*
X317383Y66500D01*
X316717Y66667D01*
X316217Y67083D01*
X315883Y67583D01*
X315800Y68167D01*
X315883Y68750D01*
X316217Y69250D01*
X316717Y69667D01*
X317383Y69833D01*
X317967Y69750D01*
X318383Y69583D01*
X318800Y69250D01*
G01X322900Y71500D02*
Y66500D01*
G01X321733Y69833D02*
X324067D01*
G01X327083Y66500D02*
Y71500D01*
G01Y69083D02*
X327500Y69500D01*
X327917Y69750D01*
X328583Y69833D01*
X329083Y69750D01*
X329667Y69417D01*
X329917Y68917D01*
Y66500D01*
G01X338033D02*
X341367Y68167D01*
X338033Y69833D01*
G01X350733Y66500D02*
X350900Y67583D01*
X351150Y68500D01*
X351483Y69333D01*
X351900Y70250D01*
X352567Y71500D01*
X349233D01*
G01X359600Y66500D02*
Y69833D01*
G01Y68917D02*
X359850Y69333D01*
X360267Y69667D01*
X360850Y69833D01*
X361433Y69667D01*
X361850Y69333D01*
X362100Y68917D01*
Y66500D01*
G01Y68917D02*
X362350Y69333D01*
X362767Y69667D01*
X363350Y69833D01*
X363933Y69667D01*
X364350Y69333D01*
X364600Y68833D01*
Y66500D01*
G01X367700Y69833D02*
Y66500D01*
G01Y71167D02*
X367533Y71250D01*
Y71417D01*
X367700Y71500D01*
X367867Y71417D01*
Y71250D01*
X367700Y71167D01*
G01X373300Y66500D02*
Y71500D01*
G01X272500Y52000D02*
Y47000D01*
G01X270583Y52000D02*
X274417D01*
G01X276683Y47000D02*
Y52000D01*
G01Y49583D02*
X277100Y50000D01*
X277517Y50250D01*
X278183Y50333D01*
X278683Y50250D01*
X279267Y49917D01*
X279517Y49417D01*
Y47000D01*
G01X282450Y49250D02*
X285117D01*
X284867Y49833D01*
X284450Y50167D01*
X283867Y50333D01*
X283283Y50250D01*
X282783Y50000D01*
X282450Y49417D01*
X282283Y48917D01*
Y48417D01*
X282450Y47917D01*
X282867Y47417D01*
X283367Y47083D01*
X283950Y47000D01*
X284533Y47167D01*
X285117Y47667D01*
G01X294900Y47000D02*
Y52000D01*
G01X302000Y47000D02*
Y50333D01*
G01Y49750D02*
X301667Y50083D01*
X301167Y50250D01*
X300583Y50333D01*
X300000Y50167D01*
X299500Y49833D01*
X299167Y49333D01*
X299000Y48667D01*
X299167Y48000D01*
X299500Y47500D01*
X300000Y47167D01*
X300583Y47000D01*
X301167Y47083D01*
X301667Y47333D01*
X302000Y47667D01*
G01X304933Y47000D02*
Y50333D01*
G01Y49667D02*
X305350Y50000D01*
X305767Y50250D01*
X306350Y50333D01*
X306767Y50250D01*
X307267Y50000D01*
G01X310533Y45750D02*
X311117Y45417D01*
X311783Y45333D01*
X312367Y45417D01*
X312867Y45833D01*
X313200Y46417D01*
Y50333D01*
G01Y49667D02*
X312867Y50000D01*
X312367Y50250D01*
X311783Y50333D01*
X311117Y50167D01*
X310700Y49833D01*
X310367Y49250D01*
X310200Y48667D01*
X310283Y48167D01*
X310617Y47583D01*
X311117Y47167D01*
X311783Y47000D01*
X312283Y47083D01*
X312867Y47417D01*
X313200Y47750D01*
G01X316050Y49250D02*
X318717D01*
X318467Y49833D01*
X318050Y50167D01*
X317467Y50333D01*
X316883Y50250D01*
X316383Y50000D01*
X316050Y49417D01*
X315883Y48917D01*
Y48417D01*
X316050Y47917D01*
X316467Y47417D01*
X316967Y47083D01*
X317550Y47000D01*
X318133Y47167D01*
X318717Y47667D01*
G01X321650Y47583D02*
X322067Y47250D01*
X322650Y47000D01*
X323150D01*
X323650Y47167D01*
X323983Y47417D01*
X324150Y47750D01*
X324067Y48250D01*
X323733Y48500D01*
X322233Y49000D01*
X321900Y49583D01*
X322067Y50000D01*
X322400Y50250D01*
X322900Y50333D01*
X323400Y50250D01*
X323900Y50000D01*
G01X328500Y52000D02*
Y47000D01*
G01X327333Y50333D02*
X329667D01*
G01X341200Y52000D02*
Y47000D01*
G01Y47750D02*
X340867Y47333D01*
X340367Y47083D01*
X339783Y47000D01*
X339117Y47167D01*
X338617Y47583D01*
X338283Y48083D01*
X338200Y48667D01*
X338283Y49250D01*
X338617Y49750D01*
X339117Y50167D01*
X339783Y50333D01*
X340367Y50250D01*
X340783Y50083D01*
X341200Y49750D01*
G01X345300Y50333D02*
Y47000D01*
G01Y51667D02*
X345133Y51750D01*
Y51917D01*
X345300Y52000D01*
X345467Y51917D01*
Y51750D01*
X345300Y51667D01*
G01X348400Y47000D02*
Y50333D01*
G01Y49417D02*
X348650Y49833D01*
X349067Y50167D01*
X349650Y50333D01*
X350233Y50167D01*
X350650Y49833D01*
X350900Y49417D01*
Y47000D01*
G01Y49417D02*
X351150Y49833D01*
X351567Y50167D01*
X352150Y50333D01*
X352733Y50167D01*
X353150Y49833D01*
X353400Y49333D01*
Y47000D01*
G01X355250Y49250D02*
X357917D01*
X357667Y49833D01*
X357250Y50167D01*
X356667Y50333D01*
X356083Y50250D01*
X355583Y50000D01*
X355250Y49417D01*
X355083Y48917D01*
Y48417D01*
X355250Y47917D01*
X355667Y47417D01*
X356167Y47083D01*
X356750Y47000D01*
X357333Y47167D01*
X357917Y47667D01*
G01X360683Y47000D02*
Y50333D01*
G01Y49500D02*
X361017Y49917D01*
X361517Y50250D01*
X362183Y50333D01*
X362767Y50250D01*
X363267Y49917D01*
X363517Y49333D01*
Y47000D01*
G01X366450Y47583D02*
X366867Y47250D01*
X367450Y47000D01*
X367950D01*
X368450Y47167D01*
X368783Y47417D01*
X368950Y47750D01*
X368867Y48250D01*
X368533Y48500D01*
X367033Y49000D01*
X366700Y49583D01*
X366867Y50000D01*
X367200Y50250D01*
X367700Y50333D01*
X368200Y50250D01*
X368700Y50000D01*
G01X373300Y50333D02*
Y47000D01*
G01Y51667D02*
X373133Y51750D01*
Y51917D01*
X373300Y52000D01*
X373467Y51917D01*
Y51750D01*
X373300Y51667D01*
G01X378900Y47000D02*
X378400Y47083D01*
X377900Y47417D01*
X377567Y48000D01*
X377400Y48667D01*
X377567Y49333D01*
X377900Y49917D01*
X378400Y50250D01*
X378900Y50333D01*
X379400Y50250D01*
X379900Y49917D01*
X380233Y49333D01*
X380317Y48667D01*
X380233Y48000D01*
X379900Y47417D01*
X379400Y47083D01*
X378900Y47000D01*
G01X383083D02*
Y50333D01*
G01Y49500D02*
X383417Y49917D01*
X383917Y50250D01*
X384583Y50333D01*
X385167Y50250D01*
X385667Y49917D01*
X385917Y49333D01*
Y47000D01*
G01X395700D02*
X395200Y47083D01*
X394700Y47417D01*
X394367Y48000D01*
X394200Y48667D01*
X394367Y49333D01*
X394700Y49917D01*
X395200Y50250D01*
X395700Y50333D01*
X396200Y50250D01*
X396700Y49917D01*
X397033Y49333D01*
X397117Y48667D01*
X397033Y48000D01*
X396700Y47417D01*
X396200Y47083D01*
X395700Y47000D01*
G01X400800D02*
Y51250D01*
X400967Y51667D01*
X401300Y51917D01*
X401800Y52000D01*
X402300Y51833D01*
X402550Y51417D01*
G01X401550Y50000D02*
X399883D01*
G01X411000Y45333D02*
Y50333D01*
G01Y49583D02*
X411417Y50000D01*
X411833Y50250D01*
X412500Y50333D01*
X413083Y50250D01*
X413667Y49833D01*
X413917Y49250D01*
X414000Y48667D01*
X413917Y48083D01*
X413667Y47500D01*
X413167Y47167D01*
X412500Y47000D01*
X411917Y47083D01*
X411333Y47333D01*
X411000Y47667D01*
G01X419600Y47000D02*
Y50333D01*
G01Y49750D02*
X419267Y50083D01*
X418767Y50250D01*
X418183Y50333D01*
X417600Y50167D01*
X417100Y49833D01*
X416767Y49333D01*
X416600Y48667D01*
X416767Y48000D01*
X417100Y47500D01*
X417600Y47167D01*
X418183Y47000D01*
X418767Y47083D01*
X419267Y47333D01*
X419600Y47667D01*
G01X425200Y52000D02*
Y47000D01*
G01Y47750D02*
X424867Y47333D01*
X424367Y47083D01*
X423783Y47000D01*
X423117Y47167D01*
X422617Y47583D01*
X422283Y48083D01*
X422200Y48667D01*
X422283Y49250D01*
X422617Y49750D01*
X423117Y50167D01*
X423783Y50333D01*
X424367Y50250D01*
X424783Y50083D01*
X425200Y49750D01*
G01X434900Y47000D02*
X434400Y47083D01*
X433900Y47417D01*
X433567Y48000D01*
X433400Y48667D01*
X433567Y49333D01*
X433900Y49917D01*
X434400Y50250D01*
X434900Y50333D01*
X435400Y50250D01*
X435900Y49917D01*
X436233Y49333D01*
X436317Y48667D01*
X436233Y48000D01*
X435900Y47417D01*
X435400Y47083D01*
X434900Y47000D01*
G01X439333D02*
Y50333D01*
G01Y49667D02*
X439750Y50000D01*
X440167Y50250D01*
X440750Y50333D01*
X441167Y50250D01*
X441667Y50000D01*
G01X453200Y52000D02*
Y47000D01*
G01Y47750D02*
X452867Y47333D01*
X452367Y47083D01*
X451783Y47000D01*
X451117Y47167D01*
X450617Y47583D01*
X450283Y48083D01*
X450200Y48667D01*
X450283Y49250D01*
X450617Y49750D01*
X451117Y50167D01*
X451783Y50333D01*
X452367Y50250D01*
X452783Y50083D01*
X453200Y49750D01*
G01X457300Y50333D02*
Y47000D01*
G01Y51667D02*
X457133Y51750D01*
Y51917D01*
X457300Y52000D01*
X457467Y51917D01*
Y51750D01*
X457300Y51667D01*
G01X464400Y47000D02*
Y50333D01*
G01Y49750D02*
X464067Y50083D01*
X463567Y50250D01*
X462983Y50333D01*
X462400Y50167D01*
X461900Y49833D01*
X461567Y49333D01*
X461400Y48667D01*
X461567Y48000D01*
X461900Y47500D01*
X462400Y47167D01*
X462983Y47000D01*
X463567Y47083D01*
X464067Y47333D01*
X464400Y47667D01*
G01X466000Y47000D02*
Y50333D01*
G01Y49417D02*
X466250Y49833D01*
X466667Y50167D01*
X467250Y50333D01*
X467833Y50167D01*
X468250Y49833D01*
X468500Y49417D01*
Y47000D01*
G01Y49417D02*
X468750Y49833D01*
X469167Y50167D01*
X469750Y50333D01*
X470333Y50167D01*
X470750Y49833D01*
X471000Y49333D01*
Y47000D01*
G01X472850Y49250D02*
X475517D01*
X475267Y49833D01*
X474850Y50167D01*
X474267Y50333D01*
X473683Y50250D01*
X473183Y50000D01*
X472850Y49417D01*
X472683Y48917D01*
Y48417D01*
X472850Y47917D01*
X473267Y47417D01*
X473767Y47083D01*
X474350Y47000D01*
X474933Y47167D01*
X475517Y47667D01*
G01X479700Y52000D02*
Y47000D01*
G01X478533Y50333D02*
X480867D01*
G01X484050Y49250D02*
X486717D01*
X486467Y49833D01*
X486050Y50167D01*
X485467Y50333D01*
X484883Y50250D01*
X484383Y50000D01*
X484050Y49417D01*
X483883Y48917D01*
Y48417D01*
X484050Y47917D01*
X484467Y47417D01*
X484967Y47083D01*
X485550Y47000D01*
X486133Y47167D01*
X486717Y47667D01*
G01X489733Y47000D02*
Y50333D01*
G01Y49667D02*
X490150Y50000D01*
X490567Y50250D01*
X491150Y50333D01*
X491567Y50250D01*
X492067Y50000D01*
G01X500433Y47000D02*
X503767Y48667D01*
X500433Y50333D01*
G01X513300Y47000D02*
Y52000D01*
X512300Y51000D01*
G01Y47000D02*
X514300D01*
G01X519900D02*
Y52000D01*
X516817Y48417D01*
X520983D01*
G01X527600Y47000D02*
Y50333D01*
G01Y49417D02*
X527850Y49833D01*
X528267Y50167D01*
X528850Y50333D01*
X529433Y50167D01*
X529850Y49833D01*
X530100Y49417D01*
Y47000D01*
G01Y49417D02*
X530350Y49833D01*
X530767Y50167D01*
X531350Y50333D01*
X531933Y50167D01*
X532350Y49833D01*
X532600Y49333D01*
Y47000D01*
G01X535700Y50333D02*
Y47000D01*
G01Y51667D02*
X535533Y51750D01*
Y51917D01*
X535700Y52000D01*
X535867Y51917D01*
Y51750D01*
X535700Y51667D01*
G01X541300Y47000D02*
Y52000D01*
G01X273580Y32670D02*
Y27670D01*
G01X271663Y32670D02*
X275497D01*
G01X277763Y27670D02*
Y32670D01*
G01Y30253D02*
X278180Y30670D01*
X278597Y30920D01*
X279263Y31003D01*
X279763Y30920D01*
X280347Y30587D01*
X280597Y30087D01*
Y27670D01*
G01X283530Y29920D02*
X286197D01*
X285947Y30503D01*
X285530Y30837D01*
X284947Y31003D01*
X284363Y30920D01*
X283863Y30670D01*
X283530Y30087D01*
X283363Y29587D01*
Y29087D01*
X283530Y28587D01*
X283947Y28087D01*
X284447Y27753D01*
X285030Y27670D01*
X285613Y27837D01*
X286197Y28337D01*
G01X295980Y27670D02*
Y32670D01*
G01X303080Y27670D02*
Y31003D01*
G01Y30420D02*
X302747Y30753D01*
X302247Y30920D01*
X301663Y31003D01*
X301080Y30837D01*
X300580Y30503D01*
X300247Y30003D01*
X300080Y29337D01*
X300247Y28670D01*
X300580Y28170D01*
X301080Y27837D01*
X301663Y27670D01*
X302247Y27753D01*
X302747Y28003D01*
X303080Y28337D01*
G01X306013Y27670D02*
Y31003D01*
G01Y30337D02*
X306430Y30670D01*
X306847Y30920D01*
X307430Y31003D01*
X307847Y30920D01*
X308347Y30670D01*
G01X311613Y26420D02*
X312197Y26087D01*
X312863Y26003D01*
X313447Y26087D01*
X313947Y26503D01*
X314280Y27087D01*
Y31003D01*
G01Y30337D02*
X313947Y30670D01*
X313447Y30920D01*
X312863Y31003D01*
X312197Y30837D01*
X311780Y30503D01*
X311447Y29920D01*
X311280Y29337D01*
X311363Y28837D01*
X311697Y28253D01*
X312197Y27837D01*
X312863Y27670D01*
X313363Y27753D01*
X313947Y28087D01*
X314280Y28420D01*
G01X317130Y29920D02*
X319797D01*
X319547Y30503D01*
X319130Y30837D01*
X318547Y31003D01*
X317963Y30920D01*
X317463Y30670D01*
X317130Y30087D01*
X316963Y29587D01*
Y29087D01*
X317130Y28587D01*
X317547Y28087D01*
X318047Y27753D01*
X318630Y27670D01*
X319213Y27837D01*
X319797Y28337D01*
G01X322730Y28253D02*
X323147Y27920D01*
X323730Y27670D01*
X324230D01*
X324730Y27837D01*
X325063Y28087D01*
X325230Y28420D01*
X325147Y28920D01*
X324813Y29170D01*
X323313Y29670D01*
X322980Y30253D01*
X323147Y30670D01*
X323480Y30920D01*
X323980Y31003D01*
X324480Y30920D01*
X324980Y30670D01*
G01X329580Y32670D02*
Y27670D01*
G01X328413Y31003D02*
X330747D01*
G01X342280Y32670D02*
Y27670D01*
G01Y28420D02*
X341947Y28003D01*
X341447Y27753D01*
X340863Y27670D01*
X340197Y27837D01*
X339697Y28253D01*
X339363Y28753D01*
X339280Y29337D01*
X339363Y29920D01*
X339697Y30420D01*
X340197Y30837D01*
X340863Y31003D01*
X341447Y30920D01*
X341863Y30753D01*
X342280Y30420D01*
G01X346380Y31003D02*
Y27670D01*
G01Y32337D02*
X346213Y32420D01*
Y32587D01*
X346380Y32670D01*
X346547Y32587D01*
Y32420D01*
X346380Y32337D01*
G01X349480Y27670D02*
Y31003D01*
G01Y30087D02*
X349730Y30503D01*
X350147Y30837D01*
X350730Y31003D01*
X351313Y30837D01*
X351730Y30503D01*
X351980Y30087D01*
Y27670D01*
G01Y30087D02*
X352230Y30503D01*
X352647Y30837D01*
X353230Y31003D01*
X353813Y30837D01*
X354230Y30503D01*
X354480Y30003D01*
Y27670D01*
G01X356330Y29920D02*
X358997D01*
X358747Y30503D01*
X358330Y30837D01*
X357747Y31003D01*
X357163Y30920D01*
X356663Y30670D01*
X356330Y30087D01*
X356163Y29587D01*
Y29087D01*
X356330Y28587D01*
X356747Y28087D01*
X357247Y27753D01*
X357830Y27670D01*
X358413Y27837D01*
X358997Y28337D01*
G01X361763Y27670D02*
Y31003D01*
G01Y30170D02*
X362097Y30587D01*
X362597Y30920D01*
X363263Y31003D01*
X363847Y30920D01*
X364347Y30587D01*
X364597Y30003D01*
Y27670D01*
G01X367530Y28253D02*
X367947Y27920D01*
X368530Y27670D01*
X369030D01*
X369530Y27837D01*
X369863Y28087D01*
X370030Y28420D01*
X369947Y28920D01*
X369613Y29170D01*
X368113Y29670D01*
X367780Y30253D01*
X367947Y30670D01*
X368280Y30920D01*
X368780Y31003D01*
X369280Y30920D01*
X369780Y30670D01*
G01X374380Y31003D02*
Y27670D01*
G01Y32337D02*
X374213Y32420D01*
Y32587D01*
X374380Y32670D01*
X374547Y32587D01*
Y32420D01*
X374380Y32337D01*
G01X379980Y27670D02*
X379480Y27753D01*
X378980Y28087D01*
X378647Y28670D01*
X378480Y29337D01*
X378647Y30003D01*
X378980Y30587D01*
X379480Y30920D01*
X379980Y31003D01*
X380480Y30920D01*
X380980Y30587D01*
X381313Y30003D01*
X381397Y29337D01*
X381313Y28670D01*
X380980Y28087D01*
X380480Y27753D01*
X379980Y27670D01*
G01X384163D02*
Y31003D01*
G01Y30170D02*
X384497Y30587D01*
X384997Y30920D01*
X385663Y31003D01*
X386247Y30920D01*
X386747Y30587D01*
X386997Y30003D01*
Y27670D01*
G01X396780D02*
X396280Y27753D01*
X395780Y28087D01*
X395447Y28670D01*
X395280Y29337D01*
X395447Y30003D01*
X395780Y30587D01*
X396280Y30920D01*
X396780Y31003D01*
X397280Y30920D01*
X397780Y30587D01*
X398113Y30003D01*
X398197Y29337D01*
X398113Y28670D01*
X397780Y28087D01*
X397280Y27753D01*
X396780Y27670D01*
G01X401880D02*
Y31920D01*
X402047Y32337D01*
X402380Y32587D01*
X402880Y32670D01*
X403380Y32503D01*
X403630Y32087D01*
G01X402630Y30670D02*
X400963D01*
G01X412080Y26003D02*
Y31003D01*
G01Y30253D02*
X412497Y30670D01*
X412913Y30920D01*
X413580Y31003D01*
X414163Y30920D01*
X414747Y30503D01*
X414997Y29920D01*
X415080Y29337D01*
X414997Y28753D01*
X414747Y28170D01*
X414247Y27837D01*
X413580Y27670D01*
X412997Y27753D01*
X412413Y28003D01*
X412080Y28337D01*
G01X420680Y27670D02*
Y31003D01*
G01Y30420D02*
X420347Y30753D01*
X419847Y30920D01*
X419263Y31003D01*
X418680Y30837D01*
X418180Y30503D01*
X417847Y30003D01*
X417680Y29337D01*
X417847Y28670D01*
X418180Y28170D01*
X418680Y27837D01*
X419263Y27670D01*
X419847Y27753D01*
X420347Y28003D01*
X420680Y28337D01*
G01X426280Y32670D02*
Y27670D01*
G01Y28420D02*
X425947Y28003D01*
X425447Y27753D01*
X424863Y27670D01*
X424197Y27837D01*
X423697Y28253D01*
X423363Y28753D01*
X423280Y29337D01*
X423363Y29920D01*
X423697Y30420D01*
X424197Y30837D01*
X424863Y31003D01*
X425447Y30920D01*
X425863Y30753D01*
X426280Y30420D01*
G01X435980Y27670D02*
X435480Y27753D01*
X434980Y28087D01*
X434647Y28670D01*
X434480Y29337D01*
X434647Y30003D01*
X434980Y30587D01*
X435480Y30920D01*
X435980Y31003D01*
X436480Y30920D01*
X436980Y30587D01*
X437313Y30003D01*
X437397Y29337D01*
X437313Y28670D01*
X436980Y28087D01*
X436480Y27753D01*
X435980Y27670D01*
G01X440413D02*
Y31003D01*
G01Y30337D02*
X440830Y30670D01*
X441247Y30920D01*
X441830Y31003D01*
X442247Y30920D01*
X442747Y30670D01*
G01X454280Y32670D02*
Y27670D01*
G01Y28420D02*
X453947Y28003D01*
X453447Y27753D01*
X452863Y27670D01*
X452197Y27837D01*
X451697Y28253D01*
X451363Y28753D01*
X451280Y29337D01*
X451363Y29920D01*
X451697Y30420D01*
X452197Y30837D01*
X452863Y31003D01*
X453447Y30920D01*
X453863Y30753D01*
X454280Y30420D01*
G01X458380Y31003D02*
Y27670D01*
G01Y32337D02*
X458213Y32420D01*
Y32587D01*
X458380Y32670D01*
X458547Y32587D01*
Y32420D01*
X458380Y32337D01*
G01X465480Y27670D02*
Y31003D01*
G01Y30420D02*
X465147Y30753D01*
X464647Y30920D01*
X464063Y31003D01*
X463480Y30837D01*
X462980Y30503D01*
X462647Y30003D01*
X462480Y29337D01*
X462647Y28670D01*
X462980Y28170D01*
X463480Y27837D01*
X464063Y27670D01*
X464647Y27753D01*
X465147Y28003D01*
X465480Y28337D01*
G01X467080Y27670D02*
Y31003D01*
G01Y30087D02*
X467330Y30503D01*
X467747Y30837D01*
X468330Y31003D01*
X468913Y30837D01*
X469330Y30503D01*
X469580Y30087D01*
Y27670D01*
G01Y30087D02*
X469830Y30503D01*
X470247Y30837D01*
X470830Y31003D01*
X471413Y30837D01*
X471830Y30503D01*
X472080Y30003D01*
Y27670D01*
G01X473930Y29920D02*
X476597D01*
X476347Y30503D01*
X475930Y30837D01*
X475347Y31003D01*
X474763Y30920D01*
X474263Y30670D01*
X473930Y30087D01*
X473763Y29587D01*
Y29087D01*
X473930Y28587D01*
X474347Y28087D01*
X474847Y27753D01*
X475430Y27670D01*
X476013Y27837D01*
X476597Y28337D01*
G01X480780Y32670D02*
Y27670D01*
G01X479613Y31003D02*
X481947D01*
G01X485130Y29920D02*
X487797D01*
X487547Y30503D01*
X487130Y30837D01*
X486547Y31003D01*
X485963Y30920D01*
X485463Y30670D01*
X485130Y30087D01*
X484963Y29587D01*
Y29087D01*
X485130Y28587D01*
X485547Y28087D01*
X486047Y27753D01*
X486630Y27670D01*
X487213Y27837D01*
X487797Y28337D01*
G01X490813Y27670D02*
Y31003D01*
G01Y30337D02*
X491230Y30670D01*
X491647Y30920D01*
X492230Y31003D01*
X492647Y30920D01*
X493147Y30670D01*
G01X504847Y27670D02*
X501513Y29337D01*
X504847Y31003D01*
G01X507697Y28587D02*
X509863D01*
G01Y30087D02*
X507697D01*
G01X519980Y27670D02*
Y32670D01*
X518980Y31670D01*
G01Y27670D02*
X520980D01*
G01X526580D02*
Y32670D01*
X523497Y29087D01*
X527663D01*
G01X534280Y27670D02*
Y31003D01*
G01Y30087D02*
X534530Y30503D01*
X534947Y30837D01*
X535530Y31003D01*
X536113Y30837D01*
X536530Y30503D01*
X536780Y30087D01*
Y27670D01*
G01Y30087D02*
X537030Y30503D01*
X537447Y30837D01*
X538030Y31003D01*
X538613Y30837D01*
X539030Y30503D01*
X539280Y30003D01*
Y27670D01*
G01X542380Y31003D02*
Y27670D01*
G01Y32337D02*
X542213Y32420D01*
Y32587D01*
X542380Y32670D01*
X542547Y32587D01*
Y32420D01*
X542380Y32337D01*
G01X547980Y27670D02*
Y32670D01*
G01X264000Y40500D02*
X694500D01*
G01X272500Y101500D02*
Y96500D01*
G01X271333Y99833D02*
X273667D01*
G01X276933Y96500D02*
Y99833D01*
G01Y99167D02*
X277350Y99500D01*
X277767Y99750D01*
X278350Y99833D01*
X278767Y99750D01*
X279267Y99500D01*
G01X285200Y96500D02*
Y99833D01*
G01Y99250D02*
X284867Y99583D01*
X284367Y99750D01*
X283783Y99833D01*
X283200Y99667D01*
X282700Y99333D01*
X282367Y98833D01*
X282200Y98167D01*
X282367Y97500D01*
X282700Y97000D01*
X283200Y96667D01*
X283783Y96500D01*
X284367Y96583D01*
X284867Y96833D01*
X285200Y97167D01*
G01X290633Y99417D02*
X290050Y99750D01*
X289550Y99833D01*
X288883Y99667D01*
X288383Y99333D01*
X288050Y98750D01*
X287967Y98167D01*
X288050Y97583D01*
X288383Y97083D01*
X288883Y96667D01*
X289550Y96500D01*
X290133Y96667D01*
X290633Y97000D01*
G01X293650Y98750D02*
X296317D01*
X296067Y99333D01*
X295650Y99667D01*
X295067Y99833D01*
X294483Y99750D01*
X293983Y99500D01*
X293650Y98917D01*
X293483Y98417D01*
Y97917D01*
X293650Y97417D01*
X294067Y96917D01*
X294567Y96583D01*
X295150Y96500D01*
X295733Y96667D01*
X296317Y97167D01*
G01X304017Y99833D02*
X305017Y96500D01*
X306100Y99833D01*
X307183Y96500D01*
X308183Y99833D01*
G01X311700D02*
Y96500D01*
G01Y101167D02*
X311533Y101250D01*
Y101417D01*
X311700Y101500D01*
X311867Y101417D01*
Y101250D01*
X311700Y101167D01*
G01X318800Y101500D02*
Y96500D01*
G01Y97250D02*
X318467Y96833D01*
X317967Y96583D01*
X317383Y96500D01*
X316717Y96667D01*
X316217Y97083D01*
X315883Y97583D01*
X315800Y98167D01*
X315883Y98750D01*
X316217Y99250D01*
X316717Y99667D01*
X317383Y99833D01*
X317967Y99750D01*
X318383Y99583D01*
X318800Y99250D01*
G01X322900Y101500D02*
Y96500D01*
G01X321733Y99833D02*
X324067D01*
G01X327083Y96500D02*
Y101500D01*
G01Y99083D02*
X327500Y99500D01*
X327917Y99750D01*
X328583Y99833D01*
X329083Y99750D01*
X329667Y99417D01*
X329917Y98917D01*
Y96500D01*
G01X341367D02*
X338033Y98167D01*
X341367Y99833D01*
G01X344217Y97417D02*
X346383D01*
G01Y98917D02*
X344217D01*
G01X354667Y97250D02*
X355167Y96833D01*
X355750Y96583D01*
X356500Y96500D01*
X357250Y96667D01*
X357833Y97000D01*
X358250Y97583D01*
X358333Y98250D01*
X358167Y98917D01*
X357750Y99333D01*
X357167Y99667D01*
X356583Y99750D01*
X356000Y99667D01*
X355250Y99333D01*
X355500Y101500D01*
X357750D01*
G01X365200Y96500D02*
Y99833D01*
G01Y98917D02*
X365450Y99333D01*
X365867Y99667D01*
X366450Y99833D01*
X367033Y99667D01*
X367450Y99333D01*
X367700Y98917D01*
Y96500D01*
G01Y98917D02*
X367950Y99333D01*
X368367Y99667D01*
X368950Y99833D01*
X369533Y99667D01*
X369950Y99333D01*
X370200Y98833D01*
Y96500D01*
G01X373300Y99833D02*
Y96500D01*
G01Y101167D02*
X373133Y101250D01*
Y101417D01*
X373300Y101500D01*
X373467Y101417D01*
Y101250D01*
X373300Y101167D01*
G01X378900Y96500D02*
Y101500D01*
G01X270667Y82250D02*
X271167Y81833D01*
X271750Y81583D01*
X272500Y81500D01*
X273250Y81667D01*
X273833Y82000D01*
X274250Y82583D01*
X274333Y83250D01*
X274167Y83917D01*
X273750Y84333D01*
X273167Y84667D01*
X272583Y84750D01*
X272000Y84667D01*
X271250Y84333D01*
X271500Y86500D01*
X273750D01*
G01X281200Y81500D02*
Y84833D01*
G01Y83917D02*
X281450Y84333D01*
X281867Y84667D01*
X282450Y84833D01*
X283033Y84667D01*
X283450Y84333D01*
X283700Y83917D01*
Y81500D01*
G01Y83917D02*
X283950Y84333D01*
X284367Y84667D01*
X284950Y84833D01*
X285533Y84667D01*
X285950Y84333D01*
X286200Y83833D01*
Y81500D01*
G01X289300Y84833D02*
Y81500D01*
G01Y86167D02*
X289133Y86250D01*
Y86417D01*
X289300Y86500D01*
X289467Y86417D01*
Y86250D01*
X289300Y86167D01*
G01X294900Y81500D02*
Y86500D01*
G01X307767Y81500D02*
X304433Y83167D01*
X307767Y84833D01*
G01X317300Y86500D02*
Y81500D01*
G01X316133Y84833D02*
X318467D01*
G01X321733Y81500D02*
Y84833D01*
G01Y84167D02*
X322150Y84500D01*
X322567Y84750D01*
X323150Y84833D01*
X323567Y84750D01*
X324067Y84500D01*
G01X330000Y81500D02*
Y84833D01*
G01Y84250D02*
X329667Y84583D01*
X329167Y84750D01*
X328583Y84833D01*
X328000Y84667D01*
X327500Y84333D01*
X327167Y83833D01*
X327000Y83167D01*
X327167Y82500D01*
X327500Y82000D01*
X328000Y81667D01*
X328583Y81500D01*
X329167Y81583D01*
X329667Y81833D01*
X330000Y82167D01*
G01X335433Y84417D02*
X334850Y84750D01*
X334350Y84833D01*
X333683Y84667D01*
X333183Y84333D01*
X332850Y83750D01*
X332767Y83167D01*
X332850Y82583D01*
X333183Y82083D01*
X333683Y81667D01*
X334350Y81500D01*
X334933Y81667D01*
X335433Y82000D01*
G01X338450Y83750D02*
X341117D01*
X340867Y84333D01*
X340450Y84667D01*
X339867Y84833D01*
X339283Y84750D01*
X338783Y84500D01*
X338450Y83917D01*
X338283Y83417D01*
Y82917D01*
X338450Y82417D01*
X338867Y81917D01*
X339367Y81583D01*
X339950Y81500D01*
X340533Y81667D01*
X341117Y82167D01*
G01X348817Y84833D02*
X349817Y81500D01*
X350900Y84833D01*
X351983Y81500D01*
X352983Y84833D01*
G01X356500D02*
Y81500D01*
G01Y86167D02*
X356333Y86250D01*
Y86417D01*
X356500Y86500D01*
X356667Y86417D01*
Y86250D01*
X356500Y86167D01*
G01X363600Y86500D02*
Y81500D01*
G01Y82250D02*
X363267Y81833D01*
X362767Y81583D01*
X362183Y81500D01*
X361517Y81667D01*
X361017Y82083D01*
X360683Y82583D01*
X360600Y83167D01*
X360683Y83750D01*
X361017Y84250D01*
X361517Y84667D01*
X362183Y84833D01*
X362767Y84750D01*
X363183Y84583D01*
X363600Y84250D01*
G01X367700Y86500D02*
Y81500D01*
G01X366533Y84833D02*
X368867D01*
G01X371883Y81500D02*
Y86500D01*
G01Y84083D02*
X372300Y84500D01*
X372717Y84750D01*
X373383Y84833D01*
X373883Y84750D01*
X374467Y84417D01*
X374717Y83917D01*
Y81500D01*
G01X386167D02*
X382833Y83167D01*
X386167Y84833D01*
G01X389017Y82417D02*
X391183D01*
G01Y83917D02*
X389017D01*
G01X401133Y81500D02*
X401300Y82583D01*
X401550Y83500D01*
X401883Y84333D01*
X402300Y85250D01*
X402967Y86500D01*
X399633D01*
G01X410000Y81500D02*
Y84833D01*
G01Y83917D02*
X410250Y84333D01*
X410667Y84667D01*
X411250Y84833D01*
X411833Y84667D01*
X412250Y84333D01*
X412500Y83917D01*
Y81500D01*
G01Y83917D02*
X412750Y84333D01*
X413167Y84667D01*
X413750Y84833D01*
X414333Y84667D01*
X414750Y84333D01*
X415000Y83833D01*
Y81500D01*
G01X418100Y84833D02*
Y81500D01*
G01Y86167D02*
X417933Y86250D01*
Y86417D01*
X418100Y86500D01*
X418267Y86417D01*
Y86250D01*
X418100Y86167D01*
G01X423700Y81500D02*
Y86500D01*
G01X270833Y110000D02*
Y115000D01*
X272917D01*
X273583Y114750D01*
X274000Y114417D01*
X274167Y113750D01*
X274000Y113083D01*
X273500Y112667D01*
X272917Y112417D01*
X270833D01*
G01X272917D02*
X274167Y110000D01*
G01X276850Y112250D02*
X279517D01*
X279267Y112833D01*
X278850Y113167D01*
X278267Y113333D01*
X277683Y113250D01*
X277183Y113000D01*
X276850Y112417D01*
X276683Y111917D01*
Y111417D01*
X276850Y110917D01*
X277267Y110417D01*
X277767Y110083D01*
X278350Y110000D01*
X278933Y110167D01*
X279517Y110667D01*
G01X283700Y110000D02*
Y115000D01*
G01X290800Y110000D02*
Y113333D01*
G01Y112750D02*
X290467Y113083D01*
X289967Y113250D01*
X289383Y113333D01*
X288800Y113167D01*
X288300Y112833D01*
X287967Y112333D01*
X287800Y111667D01*
X287967Y111000D01*
X288300Y110500D01*
X288800Y110167D01*
X289383Y110000D01*
X289967Y110083D01*
X290467Y110333D01*
X290800Y110667D01*
G01X294900Y115000D02*
Y110000D01*
G01X293733Y113333D02*
X296067D01*
G01X300500D02*
Y110000D01*
G01Y114667D02*
X300333Y114750D01*
Y114917D01*
X300500Y115000D01*
X300667Y114917D01*
Y114750D01*
X300500Y114667D01*
G01X304600Y113333D02*
X306100Y110000D01*
X307600Y113333D01*
G01X310450Y112250D02*
X313117D01*
X312867Y112833D01*
X312450Y113167D01*
X311867Y113333D01*
X311283Y113250D01*
X310783Y113000D01*
X310450Y112417D01*
X310283Y111917D01*
Y111417D01*
X310450Y110917D01*
X310867Y110417D01*
X311367Y110083D01*
X311950Y110000D01*
X312533Y110167D01*
X313117Y110667D01*
G01X321400Y108333D02*
Y113333D01*
G01Y112583D02*
X321817Y113000D01*
X322233Y113250D01*
X322900Y113333D01*
X323483Y113250D01*
X324067Y112833D01*
X324317Y112250D01*
X324400Y111667D01*
X324317Y111083D01*
X324067Y110500D01*
X323567Y110167D01*
X322900Y110000D01*
X322317Y110083D01*
X321733Y110333D01*
X321400Y110667D01*
G01X328500Y110000D02*
X328000Y110083D01*
X327500Y110417D01*
X327167Y111000D01*
X327000Y111667D01*
X327167Y112333D01*
X327500Y112917D01*
X328000Y113250D01*
X328500Y113333D01*
X329000Y113250D01*
X329500Y112917D01*
X329833Y112333D01*
X329917Y111667D01*
X329833Y111000D01*
X329500Y110417D01*
X329000Y110083D01*
X328500Y110000D01*
G01X332850Y110583D02*
X333267Y110250D01*
X333850Y110000D01*
X334350D01*
X334850Y110167D01*
X335183Y110417D01*
X335350Y110750D01*
X335267Y111250D01*
X334933Y111500D01*
X333433Y112000D01*
X333100Y112583D01*
X333267Y113000D01*
X333600Y113250D01*
X334100Y113333D01*
X334600Y113250D01*
X335100Y113000D01*
G01X339700Y113333D02*
Y110000D01*
G01Y114667D02*
X339533Y114750D01*
Y114917D01*
X339700Y115000D01*
X339867Y114917D01*
Y114750D01*
X339700Y114667D01*
G01X345300Y115000D02*
Y110000D01*
G01X344133Y113333D02*
X346467D01*
G01X350900D02*
Y110000D01*
G01Y114667D02*
X350733Y114750D01*
Y114917D01*
X350900Y115000D01*
X351067Y114917D01*
Y114750D01*
X350900Y114667D01*
G01X356500Y110000D02*
X356000Y110083D01*
X355500Y110417D01*
X355167Y111000D01*
X355000Y111667D01*
X355167Y112333D01*
X355500Y112917D01*
X356000Y113250D01*
X356500Y113333D01*
X357000Y113250D01*
X357500Y112917D01*
X357833Y112333D01*
X357917Y111667D01*
X357833Y111000D01*
X357500Y110417D01*
X357000Y110083D01*
X356500Y110000D01*
G01X360683D02*
Y113333D01*
G01Y112500D02*
X361017Y112917D01*
X361517Y113250D01*
X362183Y113333D01*
X362767Y113250D01*
X363267Y112917D01*
X363517Y112333D01*
Y110000D01*
G01X371800D02*
Y115000D01*
G01Y112500D02*
X372217Y113000D01*
X372717Y113250D01*
X373217Y113333D01*
X373967Y113167D01*
X374467Y112833D01*
X374800Y112250D01*
Y111583D01*
X374633Y110917D01*
X374300Y110417D01*
X373717Y110083D01*
X373217Y110000D01*
X372717Y110083D01*
X372217Y110333D01*
X371800Y110750D01*
G01X377650Y112250D02*
X380317D01*
X380067Y112833D01*
X379650Y113167D01*
X379067Y113333D01*
X378483Y113250D01*
X377983Y113000D01*
X377650Y112417D01*
X377483Y111917D01*
Y111417D01*
X377650Y110917D01*
X378067Y110417D01*
X378567Y110083D01*
X379150Y110000D01*
X379733Y110167D01*
X380317Y110667D01*
G01X384500Y115000D02*
Y110000D01*
G01X383333Y113333D02*
X385667D01*
G01X388017D02*
X389017Y110000D01*
X390100Y113333D01*
X391183Y110000D01*
X392183Y113333D01*
G01X394450Y112250D02*
X397117D01*
X396867Y112833D01*
X396450Y113167D01*
X395867Y113333D01*
X395283Y113250D01*
X394783Y113000D01*
X394450Y112417D01*
X394283Y111917D01*
Y111417D01*
X394450Y110917D01*
X394867Y110417D01*
X395367Y110083D01*
X395950Y110000D01*
X396533Y110167D01*
X397117Y110667D01*
G01X400050Y112250D02*
X402717D01*
X402467Y112833D01*
X402050Y113167D01*
X401467Y113333D01*
X400883Y113250D01*
X400383Y113000D01*
X400050Y112417D01*
X399883Y111917D01*
Y111417D01*
X400050Y110917D01*
X400467Y110417D01*
X400967Y110083D01*
X401550Y110000D01*
X402133Y110167D01*
X402717Y110667D01*
G01X405483Y110000D02*
Y113333D01*
G01Y112500D02*
X405817Y112917D01*
X406317Y113250D01*
X406983Y113333D01*
X407567Y113250D01*
X408067Y112917D01*
X408317Y112333D01*
Y110000D01*
G01X419600D02*
Y113333D01*
G01Y112750D02*
X419267Y113083D01*
X418767Y113250D01*
X418183Y113333D01*
X417600Y113167D01*
X417100Y112833D01*
X416767Y112333D01*
X416600Y111667D01*
X416767Y111000D01*
X417100Y110500D01*
X417600Y110167D01*
X418183Y110000D01*
X418767Y110083D01*
X419267Y110333D01*
X419600Y110667D01*
G01X422283Y110000D02*
Y113333D01*
G01Y112500D02*
X422617Y112917D01*
X423117Y113250D01*
X423783Y113333D01*
X424367Y113250D01*
X424867Y112917D01*
X425117Y112333D01*
Y110000D01*
G01X427550Y108500D02*
X428050Y108333D01*
X428717Y108500D01*
X429133Y108833D01*
X429467Y109250D01*
X429967Y110583D01*
X431050Y113333D01*
G01X428383D02*
X429967Y110583D01*
G01X439000Y108333D02*
Y113333D01*
G01Y112583D02*
X439417Y113000D01*
X439833Y113250D01*
X440500Y113333D01*
X441083Y113250D01*
X441667Y112833D01*
X441917Y112250D01*
X442000Y111667D01*
X441917Y111083D01*
X441667Y110500D01*
X441167Y110167D01*
X440500Y110000D01*
X439917Y110083D01*
X439333Y110333D01*
X439000Y110667D01*
G01X447600Y110000D02*
Y113333D01*
G01Y112750D02*
X447267Y113083D01*
X446767Y113250D01*
X446183Y113333D01*
X445600Y113167D01*
X445100Y112833D01*
X444767Y112333D01*
X444600Y111667D01*
X444767Y111000D01*
X445100Y110500D01*
X445600Y110167D01*
X446183Y110000D01*
X446767Y110083D01*
X447267Y110333D01*
X447600Y110667D01*
G01X453200Y115000D02*
Y110000D01*
G01Y110750D02*
X452867Y110333D01*
X452367Y110083D01*
X451783Y110000D01*
X451117Y110167D01*
X450617Y110583D01*
X450283Y111083D01*
X450200Y111667D01*
X450283Y112250D01*
X450617Y112750D01*
X451117Y113167D01*
X451783Y113333D01*
X452367Y113250D01*
X452783Y113083D01*
X453200Y112750D01*
G01X462900Y115000D02*
Y110000D01*
G01X461733Y113333D02*
X464067D01*
G01X468500Y110000D02*
X468000Y110083D01*
X467500Y110417D01*
X467167Y111000D01*
X467000Y111667D01*
X467167Y112333D01*
X467500Y112917D01*
X468000Y113250D01*
X468500Y113333D01*
X469000Y113250D01*
X469500Y112917D01*
X469833Y112333D01*
X469917Y111667D01*
X469833Y111000D01*
X469500Y110417D01*
X469000Y110083D01*
X468500Y110000D01*
G01X478200Y108333D02*
Y113333D01*
G01Y112583D02*
X478617Y113000D01*
X479033Y113250D01*
X479700Y113333D01*
X480283Y113250D01*
X480867Y112833D01*
X481117Y112250D01*
X481200Y111667D01*
X481117Y111083D01*
X480867Y110500D01*
X480367Y110167D01*
X479700Y110000D01*
X479117Y110083D01*
X478533Y110333D01*
X478200Y110667D01*
G01X486800Y110000D02*
Y113333D01*
G01Y112750D02*
X486467Y113083D01*
X485967Y113250D01*
X485383Y113333D01*
X484800Y113167D01*
X484300Y112833D01*
X483967Y112333D01*
X483800Y111667D01*
X483967Y111000D01*
X484300Y110500D01*
X484800Y110167D01*
X485383Y110000D01*
X485967Y110083D01*
X486467Y110333D01*
X486800Y110667D01*
G01X492400Y115000D02*
Y110000D01*
G01Y110750D02*
X492067Y110333D01*
X491567Y110083D01*
X490983Y110000D01*
X490317Y110167D01*
X489817Y110583D01*
X489483Y111083D01*
X489400Y111667D01*
X489483Y112250D01*
X489817Y112750D01*
X490317Y113167D01*
X490983Y113333D01*
X491567Y113250D01*
X491983Y113083D01*
X492400Y112750D01*
G01X264000Y75500D02*
X694500D01*
G01X264000Y90500D02*
X694500D01*
G01X271250Y141583D02*
X271667Y141250D01*
X272250Y141000D01*
X272750D01*
X273250Y141167D01*
X273583Y141417D01*
X273750Y141750D01*
X273667Y142250D01*
X273333Y142500D01*
X271833Y143000D01*
X271500Y143583D01*
X271667Y144000D01*
X272000Y144250D01*
X272500Y144333D01*
X273000Y144250D01*
X273500Y144000D01*
G01X276600Y139333D02*
Y144333D01*
G01Y143583D02*
X277017Y144000D01*
X277433Y144250D01*
X278100Y144333D01*
X278683Y144250D01*
X279267Y143833D01*
X279517Y143250D01*
X279600Y142667D01*
X279517Y142083D01*
X279267Y141500D01*
X278767Y141167D01*
X278100Y141000D01*
X277517Y141083D01*
X276933Y141333D01*
X276600Y141667D01*
G01X282450Y143250D02*
X285117D01*
X284867Y143833D01*
X284450Y144167D01*
X283867Y144333D01*
X283283Y144250D01*
X282783Y144000D01*
X282450Y143417D01*
X282283Y142917D01*
Y142417D01*
X282450Y141917D01*
X282867Y141417D01*
X283367Y141083D01*
X283950Y141000D01*
X284533Y141167D01*
X285117Y141667D01*
G01X290633Y143917D02*
X290050Y144250D01*
X289550Y144333D01*
X288883Y144167D01*
X288383Y143833D01*
X288050Y143250D01*
X287967Y142667D01*
X288050Y142083D01*
X288383Y141583D01*
X288883Y141167D01*
X289550Y141000D01*
X290133Y141167D01*
X290633Y141500D01*
G01X294900Y144333D02*
Y141000D01*
G01Y145667D02*
X294733Y145750D01*
Y145917D01*
X294900Y146000D01*
X295067Y145917D01*
Y145750D01*
X294900Y145667D01*
G01X300000Y141000D02*
Y145250D01*
X300167Y145667D01*
X300500Y145917D01*
X301000Y146000D01*
X301500Y145833D01*
X301750Y145417D01*
G01X300750Y144000D02*
X299083D01*
G01X306100Y144333D02*
Y141000D01*
G01Y145667D02*
X305933Y145750D01*
Y145917D01*
X306100Y146000D01*
X306267Y145917D01*
Y145750D01*
X306100Y145667D01*
G01X313033Y143917D02*
X312450Y144250D01*
X311950Y144333D01*
X311283Y144167D01*
X310783Y143833D01*
X310450Y143250D01*
X310367Y142667D01*
X310450Y142083D01*
X310783Y141583D01*
X311283Y141167D01*
X311950Y141000D01*
X312533Y141167D01*
X313033Y141500D01*
G01X318800Y141000D02*
Y144333D01*
G01Y143750D02*
X318467Y144083D01*
X317967Y144250D01*
X317383Y144333D01*
X316800Y144167D01*
X316300Y143833D01*
X315967Y143333D01*
X315800Y142667D01*
X315967Y142000D01*
X316300Y141500D01*
X316800Y141167D01*
X317383Y141000D01*
X317967Y141083D01*
X318467Y141333D01*
X318800Y141667D01*
G01X322900Y146000D02*
Y141000D01*
G01X321733Y144333D02*
X324067D01*
G01X328500D02*
Y141000D01*
G01Y145667D02*
X328333Y145750D01*
Y145917D01*
X328500Y146000D01*
X328667Y145917D01*
Y145750D01*
X328500Y145667D01*
G01X334100Y141000D02*
X333600Y141083D01*
X333100Y141417D01*
X332767Y142000D01*
X332600Y142667D01*
X332767Y143333D01*
X333100Y143917D01*
X333600Y144250D01*
X334100Y144333D01*
X334600Y144250D01*
X335100Y143917D01*
X335433Y143333D01*
X335517Y142667D01*
X335433Y142000D01*
X335100Y141417D01*
X334600Y141083D01*
X334100Y141000D01*
G01X338283D02*
Y144333D01*
G01Y143500D02*
X338617Y143917D01*
X339117Y144250D01*
X339783Y144333D01*
X340367Y144250D01*
X340867Y143917D01*
X341117Y143333D01*
Y141000D01*
G01X345300Y140833D02*
X345133Y140917D01*
Y141083D01*
X345300Y141167D01*
X345467Y141083D01*
Y140917D01*
X345300Y140833D01*
G01X270750Y125000D02*
Y130000D01*
G01X274250D02*
Y125000D01*
G01Y127500D02*
X270750D01*
G01X276267Y125000D02*
Y130000D01*
X277933D01*
X278600Y129750D01*
X279100Y129417D01*
X279517Y128917D01*
X279850Y128333D01*
X279933Y127500D01*
X279850Y126667D01*
X279517Y126083D01*
X279100Y125583D01*
X278600Y125250D01*
X277933Y125000D01*
X276267D01*
G01X282700Y130000D02*
X284700D01*
G01X283700D02*
Y125000D01*
G01X282700D02*
X284700D01*
G01X293233D02*
Y130000D01*
X295233D01*
X295900Y129750D01*
X296400Y129167D01*
X296567Y128500D01*
X296400Y127833D01*
X295983Y127333D01*
X295233Y127083D01*
X293233D01*
G01X302333Y129583D02*
X301833Y129833D01*
X301250Y130000D01*
X300583D01*
X299833Y129750D01*
X299250Y129333D01*
X298833Y128833D01*
X298500Y128000D01*
X298417Y127250D01*
X298583Y126500D01*
X298833Y126000D01*
X299333Y125500D01*
X299917Y125167D01*
X300500Y125000D01*
X301083D01*
X301667Y125167D01*
X302167Y125417D01*
X302583Y125750D01*
G01X306767Y127667D02*
X307100Y127917D01*
X307350Y128333D01*
X307517Y128917D01*
X307350Y129417D01*
X307017Y129750D01*
X306433Y130000D01*
X304183D01*
Y125000D01*
X306933D01*
X307517Y125333D01*
X307850Y125833D01*
X308017Y126417D01*
X307850Y127000D01*
X307350Y127500D01*
X306767Y127667D01*
X304183D01*
G01X311700Y124833D02*
X311533Y124917D01*
Y125083D01*
X311700Y125167D01*
X311867Y125083D01*
Y124917D01*
X311700Y124833D01*
G01X270750Y150667D02*
X271417Y150250D01*
X272167Y150000D01*
X272833D01*
X273500Y150250D01*
X274000Y150667D01*
X274250Y151250D01*
X274083Y151833D01*
X273667Y152333D01*
X272917Y152667D01*
X271917Y152833D01*
X271333Y153167D01*
X271083Y153750D01*
X271250Y154333D01*
X271667Y154750D01*
X272250Y155000D01*
X272833D01*
X273417Y154833D01*
X273917Y154417D01*
G01X276850Y152250D02*
X279517D01*
X279267Y152833D01*
X278850Y153167D01*
X278267Y153333D01*
X277683Y153250D01*
X277183Y153000D01*
X276850Y152417D01*
X276683Y151917D01*
Y151417D01*
X276850Y150917D01*
X277267Y150417D01*
X277767Y150083D01*
X278350Y150000D01*
X278933Y150167D01*
X279517Y150667D01*
G01X282533Y150000D02*
Y153333D01*
G01Y152667D02*
X282950Y153000D01*
X283367Y153250D01*
X283950Y153333D01*
X284367Y153250D01*
X284867Y153000D01*
G01X287800Y153333D02*
X289300Y150000D01*
X290800Y153333D01*
G01X293650Y152250D02*
X296317D01*
X296067Y152833D01*
X295650Y153167D01*
X295067Y153333D01*
X294483Y153250D01*
X293983Y153000D01*
X293650Y152417D01*
X293483Y151917D01*
Y151417D01*
X293650Y150917D01*
X294067Y150417D01*
X294567Y150083D01*
X295150Y150000D01*
X295733Y150167D01*
X296317Y150667D01*
G01X299333Y150000D02*
Y153333D01*
G01Y152667D02*
X299750Y153000D01*
X300167Y153250D01*
X300750Y153333D01*
X301167Y153250D01*
X301667Y153000D01*
G01X310033Y150000D02*
Y155000D01*
X312033D01*
X312700Y154750D01*
X313200Y154167D01*
X313367Y153500D01*
X313200Y152833D01*
X312783Y152333D01*
X312033Y152083D01*
X310033D01*
G01X319133Y154583D02*
X318633Y154833D01*
X318050Y155000D01*
X317383D01*
X316633Y154750D01*
X316050Y154333D01*
X315633Y153833D01*
X315300Y153000D01*
X315217Y152250D01*
X315383Y151500D01*
X315633Y151000D01*
X316133Y150500D01*
X316717Y150167D01*
X317300Y150000D01*
X317883D01*
X318467Y150167D01*
X318967Y150417D01*
X319383Y150750D01*
G01X323567Y152667D02*
X323900Y152917D01*
X324150Y153333D01*
X324317Y153917D01*
X324150Y154417D01*
X323817Y154750D01*
X323233Y155000D01*
X320983D01*
Y150000D01*
X323733D01*
X324317Y150333D01*
X324650Y150833D01*
X324817Y151417D01*
X324650Y152000D01*
X324150Y152500D01*
X323567Y152667D01*
X320983D01*
G01X328500Y149833D02*
X328333Y149917D01*
Y150083D01*
X328500Y150167D01*
X328667Y150083D01*
Y149917D01*
X328500Y149833D01*
G01Y152083D02*
X328333Y152167D01*
Y152333D01*
X328500Y152417D01*
X328667Y152333D01*
Y152167D01*
X328500Y152083D01*
G01X332517Y150000D02*
Y155000D01*
X335683D01*
G01X334517Y152583D02*
X332517D01*
G01X339700Y150000D02*
X339200Y150083D01*
X338700Y150417D01*
X338367Y151000D01*
X338200Y151667D01*
X338367Y152333D01*
X338700Y152917D01*
X339200Y153250D01*
X339700Y153333D01*
X340200Y153250D01*
X340700Y152917D01*
X341033Y152333D01*
X341117Y151667D01*
X341033Y151000D01*
X340700Y150417D01*
X340200Y150083D01*
X339700Y150000D01*
G01X345300D02*
Y155000D01*
G01X350900Y150000D02*
Y155000D01*
G01X356500Y150000D02*
X356000Y150083D01*
X355500Y150417D01*
X355167Y151000D01*
X355000Y151667D01*
X355167Y152333D01*
X355500Y152917D01*
X356000Y153250D01*
X356500Y153333D01*
X357000Y153250D01*
X357500Y152917D01*
X357833Y152333D01*
X357917Y151667D01*
X357833Y151000D01*
X357500Y150417D01*
X357000Y150083D01*
X356500Y150000D01*
G01X360017Y153333D02*
X361017Y150000D01*
X362100Y153333D01*
X363183Y150000D01*
X364183Y153333D01*
G01X372133Y150000D02*
Y153333D01*
G01Y152667D02*
X372550Y153000D01*
X372967Y153250D01*
X373550Y153333D01*
X373967Y153250D01*
X374467Y153000D01*
G01X378900Y153333D02*
Y150000D01*
G01Y154667D02*
X378733Y154750D01*
Y154917D01*
X378900Y155000D01*
X379067Y154917D01*
Y154750D01*
X378900Y154667D01*
G01X383333Y148750D02*
X383917Y148417D01*
X384583Y148333D01*
X385167Y148417D01*
X385667Y148833D01*
X386000Y149417D01*
Y153333D01*
G01Y152667D02*
X385667Y153000D01*
X385167Y153250D01*
X384583Y153333D01*
X383917Y153167D01*
X383500Y152833D01*
X383167Y152250D01*
X383000Y151667D01*
X383083Y151167D01*
X383417Y150583D01*
X383917Y150167D01*
X384583Y150000D01*
X385083Y150083D01*
X385667Y150417D01*
X386000Y150750D01*
G01X388683Y150000D02*
Y155000D01*
G01Y152583D02*
X389100Y153000D01*
X389517Y153250D01*
X390183Y153333D01*
X390683Y153250D01*
X391267Y152917D01*
X391517Y152417D01*
Y150000D01*
G01X395700Y155000D02*
Y150000D01*
G01X394533Y153333D02*
X396867D01*
G01X405650Y150583D02*
X406067Y150250D01*
X406650Y150000D01*
X407150D01*
X407650Y150167D01*
X407983Y150417D01*
X408150Y150750D01*
X408067Y151250D01*
X407733Y151500D01*
X406233Y152000D01*
X405900Y152583D01*
X406067Y153000D01*
X406400Y153250D01*
X406900Y153333D01*
X407400Y153250D01*
X407900Y153000D01*
G01X412500Y153333D02*
Y150000D01*
G01Y154667D02*
X412333Y154750D01*
Y154917D01*
X412500Y155000D01*
X412667Y154917D01*
Y154750D01*
X412500Y154667D01*
G01X419600Y155000D02*
Y150000D01*
G01Y150750D02*
X419267Y150333D01*
X418767Y150083D01*
X418183Y150000D01*
X417517Y150167D01*
X417017Y150583D01*
X416683Y151083D01*
X416600Y151667D01*
X416683Y152250D01*
X417017Y152750D01*
X417517Y153167D01*
X418183Y153333D01*
X418767Y153250D01*
X419183Y153083D01*
X419600Y152750D01*
G01X422450Y152250D02*
X425117D01*
X424867Y152833D01*
X424450Y153167D01*
X423867Y153333D01*
X423283Y153250D01*
X422783Y153000D01*
X422450Y152417D01*
X422283Y151917D01*
Y151417D01*
X422450Y150917D01*
X422867Y150417D01*
X423367Y150083D01*
X423950Y150000D01*
X424533Y150167D01*
X425117Y150667D01*
G01X433650Y150583D02*
X434067Y150250D01*
X434650Y150000D01*
X435150D01*
X435650Y150167D01*
X435983Y150417D01*
X436150Y150750D01*
X436067Y151250D01*
X435733Y151500D01*
X434233Y152000D01*
X433900Y152583D01*
X434067Y153000D01*
X434400Y153250D01*
X434900Y153333D01*
X435400Y153250D01*
X435900Y153000D01*
G01X439000Y148333D02*
Y153333D01*
G01Y152583D02*
X439417Y153000D01*
X439833Y153250D01*
X440500Y153333D01*
X441083Y153250D01*
X441667Y152833D01*
X441917Y152250D01*
X442000Y151667D01*
X441917Y151083D01*
X441667Y150500D01*
X441167Y150167D01*
X440500Y150000D01*
X439917Y150083D01*
X439333Y150333D01*
X439000Y150667D01*
G01X444850Y152250D02*
X447517D01*
X447267Y152833D01*
X446850Y153167D01*
X446267Y153333D01*
X445683Y153250D01*
X445183Y153000D01*
X444850Y152417D01*
X444683Y151917D01*
Y151417D01*
X444850Y150917D01*
X445267Y150417D01*
X445767Y150083D01*
X446350Y150000D01*
X446933Y150167D01*
X447517Y150667D01*
G01X453033Y152917D02*
X452450Y153250D01*
X451950Y153333D01*
X451283Y153167D01*
X450783Y152833D01*
X450450Y152250D01*
X450367Y151667D01*
X450450Y151083D01*
X450783Y150583D01*
X451283Y150167D01*
X451950Y150000D01*
X452533Y150167D01*
X453033Y150500D01*
G01X462733Y149083D02*
X463067Y150167D01*
G01X468500Y153333D02*
Y150000D01*
G01Y154667D02*
X468333Y154750D01*
Y154917D01*
X468500Y155000D01*
X468667Y154917D01*
Y154750D01*
X468500Y154667D01*
G01X473600Y150000D02*
Y154250D01*
X473767Y154667D01*
X474100Y154917D01*
X474600Y155000D01*
X475100Y154833D01*
X475350Y154417D01*
G01X474350Y153000D02*
X472683D01*
G01X484050Y150583D02*
X484467Y150250D01*
X485050Y150000D01*
X485550D01*
X486050Y150167D01*
X486383Y150417D01*
X486550Y150750D01*
X486467Y151250D01*
X486133Y151500D01*
X484633Y152000D01*
X484300Y152583D01*
X484467Y153000D01*
X484800Y153250D01*
X485300Y153333D01*
X485800Y153250D01*
X486300Y153000D01*
G01X490900Y155000D02*
Y150000D01*
G01X489733Y153333D02*
X492067D01*
G01X498000Y150000D02*
Y153333D01*
G01Y152750D02*
X497667Y153083D01*
X497167Y153250D01*
X496583Y153333D01*
X496000Y153167D01*
X495500Y152833D01*
X495167Y152333D01*
X495000Y151667D01*
X495167Y151000D01*
X495500Y150500D01*
X496000Y150167D01*
X496583Y150000D01*
X497167Y150083D01*
X497667Y150333D01*
X498000Y150667D01*
G01X503433Y152917D02*
X502850Y153250D01*
X502350Y153333D01*
X501683Y153167D01*
X501183Y152833D01*
X500850Y152250D01*
X500767Y151667D01*
X500850Y151083D01*
X501183Y150583D01*
X501683Y150167D01*
X502350Y150000D01*
X502933Y150167D01*
X503433Y150500D01*
G01X506283Y150000D02*
Y155000D01*
G01X508950Y153333D02*
X506283Y151417D01*
G01X507367Y152167D02*
X509117Y150000D01*
G01X517483Y153333D02*
Y151000D01*
X517817Y150417D01*
X518317Y150083D01*
X518900Y150000D01*
X519483Y150083D01*
X519983Y150417D01*
X520317Y151000D01*
G01Y150000D02*
Y153333D01*
G01X523000Y148333D02*
Y153333D01*
G01Y152583D02*
X523417Y153000D01*
X523833Y153250D01*
X524500Y153333D01*
X525083Y153250D01*
X525667Y152833D01*
X525917Y152250D01*
X526000Y151667D01*
X525917Y151083D01*
X525667Y150500D01*
X525167Y150167D01*
X524500Y150000D01*
X523917Y150083D01*
X523333Y150333D01*
X523000Y150667D01*
G01X533617Y153333D02*
X534617Y150000D01*
X535700Y153333D01*
X536783Y150000D01*
X537783Y153333D01*
G01X541300D02*
Y150000D01*
G01Y154667D02*
X541133Y154750D01*
Y154917D01*
X541300Y155000D01*
X541467Y154917D01*
Y154750D01*
X541300Y154667D01*
G01X546900Y155000D02*
Y150000D01*
G01X545733Y153333D02*
X548067D01*
G01X551083Y150000D02*
Y155000D01*
G01Y152583D02*
X551500Y153000D01*
X551917Y153250D01*
X552583Y153333D01*
X553083Y153250D01*
X553667Y152917D01*
X553917Y152417D01*
Y150000D01*
G01X558100D02*
X557600Y150083D01*
X557100Y150417D01*
X556767Y151000D01*
X556600Y151667D01*
X556767Y152333D01*
X557100Y152917D01*
X557600Y153250D01*
X558100Y153333D01*
X558600Y153250D01*
X559100Y152917D01*
X559433Y152333D01*
X559517Y151667D01*
X559433Y151000D01*
X559100Y150417D01*
X558600Y150083D01*
X558100Y150000D01*
G01X562283Y153333D02*
Y151000D01*
X562617Y150417D01*
X563117Y150083D01*
X563700Y150000D01*
X564283Y150083D01*
X564783Y150417D01*
X565117Y151000D01*
G01Y150000D02*
Y153333D01*
G01X569300Y155000D02*
Y150000D01*
G01X568133Y153333D02*
X570467D01*
G01X272500Y170000D02*
Y165000D01*
G01X270583Y170000D02*
X274417D01*
G01X276933Y165000D02*
Y168333D01*
G01Y167667D02*
X277350Y168000D01*
X277767Y168250D01*
X278350Y168333D01*
X278767Y168250D01*
X279267Y168000D01*
G01X285200Y165000D02*
Y168333D01*
G01Y167750D02*
X284867Y168083D01*
X284367Y168250D01*
X283783Y168333D01*
X283200Y168167D01*
X282700Y167833D01*
X282367Y167333D01*
X282200Y166667D01*
X282367Y166000D01*
X282700Y165500D01*
X283200Y165167D01*
X283783Y165000D01*
X284367Y165083D01*
X284867Y165333D01*
X285200Y165667D01*
G01X290800Y170000D02*
Y165000D01*
G01Y165750D02*
X290467Y165333D01*
X289967Y165083D01*
X289383Y165000D01*
X288717Y165167D01*
X288217Y165583D01*
X287883Y166083D01*
X287800Y166667D01*
X287883Y167250D01*
X288217Y167750D01*
X288717Y168167D01*
X289383Y168333D01*
X289967Y168250D01*
X290383Y168083D01*
X290800Y167750D01*
G01X294900Y168333D02*
Y165000D01*
G01Y169667D02*
X294733Y169750D01*
Y169917D01*
X294900Y170000D01*
X295067Y169917D01*
Y169750D01*
X294900Y169667D01*
G01X300500Y170000D02*
Y165000D01*
G01X299333Y168333D02*
X301667D01*
G01X306100D02*
Y165000D01*
G01Y169667D02*
X305933Y169750D01*
Y169917D01*
X306100Y170000D01*
X306267Y169917D01*
Y169750D01*
X306100Y169667D01*
G01X311700Y165000D02*
X311200Y165083D01*
X310700Y165417D01*
X310367Y166000D01*
X310200Y166667D01*
X310367Y167333D01*
X310700Y167917D01*
X311200Y168250D01*
X311700Y168333D01*
X312200Y168250D01*
X312700Y167917D01*
X313033Y167333D01*
X313117Y166667D01*
X313033Y166000D01*
X312700Y165417D01*
X312200Y165083D01*
X311700Y165000D01*
G01X315883D02*
Y168333D01*
G01Y167500D02*
X316217Y167917D01*
X316717Y168250D01*
X317383Y168333D01*
X317967Y168250D01*
X318467Y167917D01*
X318717Y167333D01*
Y165000D01*
G01X324400D02*
Y168333D01*
G01Y167750D02*
X324067Y168083D01*
X323567Y168250D01*
X322983Y168333D01*
X322400Y168167D01*
X321900Y167833D01*
X321567Y167333D01*
X321400Y166667D01*
X321567Y166000D01*
X321900Y165500D01*
X322400Y165167D01*
X322983Y165000D01*
X323567Y165083D01*
X324067Y165333D01*
X324400Y165667D01*
G01X328500Y165000D02*
Y170000D01*
G01X338033Y165000D02*
Y170000D01*
X340033D01*
X340700Y169750D01*
X341200Y169167D01*
X341367Y168500D01*
X341200Y167833D01*
X340783Y167333D01*
X340033Y167083D01*
X338033D01*
G01X347133Y169583D02*
X346633Y169833D01*
X346050Y170000D01*
X345383D01*
X344633Y169750D01*
X344050Y169333D01*
X343633Y168833D01*
X343300Y168000D01*
X343217Y167250D01*
X343383Y166500D01*
X343633Y166000D01*
X344133Y165500D01*
X344717Y165167D01*
X345300Y165000D01*
X345883D01*
X346467Y165167D01*
X346967Y165417D01*
X347383Y165750D01*
G01X351567Y167667D02*
X351900Y167917D01*
X352150Y168333D01*
X352317Y168917D01*
X352150Y169417D01*
X351817Y169750D01*
X351233Y170000D01*
X348983D01*
Y165000D01*
X351733D01*
X352317Y165333D01*
X352650Y165833D01*
X352817Y166417D01*
X352650Y167000D01*
X352150Y167500D01*
X351567Y167667D01*
X348983D01*
G01X356500Y164833D02*
X356333Y164917D01*
Y165083D01*
X356500Y165167D01*
X356667Y165083D01*
Y164917D01*
X356500Y164833D01*
G01X264000Y135500D02*
X694500D01*
G01X264000Y160500D02*
X694500D01*
G01X262500Y237500D02*
X694500D01*
G01X262500Y290500D02*
X694500D01*
G01X270000Y374000D02*
Y369000D01*
G01X268833Y372333D02*
X271167D01*
G01X275600Y369000D02*
X275100Y369083D01*
X274600Y369417D01*
X274267Y370000D01*
X274100Y370667D01*
X274267Y371333D01*
X274600Y371917D01*
X275100Y372250D01*
X275600Y372333D01*
X276100Y372250D01*
X276600Y371917D01*
X276933Y371333D01*
X277017Y370667D01*
X276933Y370000D01*
X276600Y369417D01*
X276100Y369083D01*
X275600Y369000D01*
G01X281200D02*
Y374000D01*
G01X285550Y371250D02*
X288217D01*
X287967Y371833D01*
X287550Y372167D01*
X286967Y372333D01*
X286383Y372250D01*
X285883Y372000D01*
X285550Y371417D01*
X285383Y370917D01*
Y370417D01*
X285550Y369917D01*
X285967Y369417D01*
X286467Y369083D01*
X287050Y369000D01*
X287633Y369167D01*
X288217Y369667D01*
G01X291233Y369000D02*
Y372333D01*
G01Y371667D02*
X291650Y372000D01*
X292067Y372250D01*
X292650Y372333D01*
X293067Y372250D01*
X293567Y372000D01*
G01X299500Y369000D02*
Y372333D01*
G01Y371750D02*
X299167Y372083D01*
X298667Y372250D01*
X298083Y372333D01*
X297500Y372167D01*
X297000Y371833D01*
X296667Y371333D01*
X296500Y370667D01*
X296667Y370000D01*
X297000Y369500D01*
X297500Y369167D01*
X298083Y369000D01*
X298667Y369083D01*
X299167Y369333D01*
X299500Y369667D01*
G01X302183Y369000D02*
Y372333D01*
G01Y371500D02*
X302517Y371917D01*
X303017Y372250D01*
X303683Y372333D01*
X304267Y372250D01*
X304767Y371917D01*
X305017Y371333D01*
Y369000D01*
G01X310533Y371917D02*
X309950Y372250D01*
X309450Y372333D01*
X308783Y372167D01*
X308283Y371833D01*
X307950Y371250D01*
X307867Y370667D01*
X307950Y370083D01*
X308283Y369583D01*
X308783Y369167D01*
X309450Y369000D01*
X310033Y369167D01*
X310533Y369500D01*
G01X313550Y371250D02*
X316217D01*
X315967Y371833D01*
X315550Y372167D01*
X314967Y372333D01*
X314383Y372250D01*
X313883Y372000D01*
X313550Y371417D01*
X313383Y370917D01*
Y370417D01*
X313550Y369917D01*
X313967Y369417D01*
X314467Y369083D01*
X315050Y369000D01*
X315633Y369167D01*
X316217Y369667D01*
G01X326000Y374000D02*
Y369000D01*
G01X324833Y372333D02*
X327167D01*
G01X333100Y369000D02*
Y372333D01*
G01Y371750D02*
X332767Y372083D01*
X332267Y372250D01*
X331683Y372333D01*
X331100Y372167D01*
X330600Y371833D01*
X330267Y371333D01*
X330100Y370667D01*
X330267Y370000D01*
X330600Y369500D01*
X331100Y369167D01*
X331683Y369000D01*
X332267Y369083D01*
X332767Y369333D01*
X333100Y369667D01*
G01X335700Y369000D02*
Y374000D01*
G01Y371500D02*
X336117Y372000D01*
X336617Y372250D01*
X337117Y372333D01*
X337867Y372167D01*
X338367Y371833D01*
X338700Y371250D01*
Y370583D01*
X338533Y369917D01*
X338200Y369417D01*
X337617Y369083D01*
X337117Y369000D01*
X336617Y369083D01*
X336117Y369333D01*
X335700Y369750D01*
G01X342800Y369000D02*
Y374000D01*
G01X347150Y371250D02*
X349817D01*
X349567Y371833D01*
X349150Y372167D01*
X348567Y372333D01*
X347983Y372250D01*
X347483Y372000D01*
X347150Y371417D01*
X346983Y370917D01*
Y370417D01*
X347150Y369917D01*
X347567Y369417D01*
X348067Y369083D01*
X348650Y369000D01*
X349233Y369167D01*
X349817Y369667D01*
G01X354000Y368833D02*
X353833Y368917D01*
Y369083D01*
X354000Y369167D01*
X354167Y369083D01*
Y368917D01*
X354000Y368833D01*
G01X268667Y379750D02*
X269250Y379417D01*
X269750Y379333D01*
X270417Y379500D01*
X270917Y379917D01*
X271167Y380667D01*
Y384333D01*
G01Y385667D02*
X271000Y385750D01*
Y385917D01*
X271167Y386000D01*
X271333Y385917D01*
Y385750D01*
X271167Y385667D01*
G01X274183Y384333D02*
Y382000D01*
X274517Y381417D01*
X275017Y381083D01*
X275600Y381000D01*
X276183Y381083D01*
X276683Y381417D01*
X277017Y382000D01*
G01Y381000D02*
Y384333D01*
G01X279783Y381000D02*
Y384333D01*
G01Y383500D02*
X280117Y383917D01*
X280617Y384250D01*
X281283Y384333D01*
X281867Y384250D01*
X282367Y383917D01*
X282617Y383333D01*
Y381000D01*
G01X288133Y383917D02*
X287550Y384250D01*
X287050Y384333D01*
X286383Y384167D01*
X285883Y383833D01*
X285550Y383250D01*
X285467Y382667D01*
X285550Y382083D01*
X285883Y381583D01*
X286383Y381167D01*
X287050Y381000D01*
X287633Y381167D01*
X288133Y381500D01*
G01X292400Y386000D02*
Y381000D01*
G01X291233Y384333D02*
X293567D01*
G01X298000D02*
Y381000D01*
G01Y385667D02*
X297833Y385750D01*
Y385917D01*
X298000Y386000D01*
X298167Y385917D01*
Y385750D01*
X298000Y385667D01*
G01X303600Y381000D02*
X303100Y381083D01*
X302600Y381417D01*
X302267Y382000D01*
X302100Y382667D01*
X302267Y383333D01*
X302600Y383917D01*
X303100Y384250D01*
X303600Y384333D01*
X304100Y384250D01*
X304600Y383917D01*
X304933Y383333D01*
X305017Y382667D01*
X304933Y382000D01*
X304600Y381417D01*
X304100Y381083D01*
X303600Y381000D01*
G01X307783D02*
Y384333D01*
G01Y383500D02*
X308117Y383917D01*
X308617Y384250D01*
X309283Y384333D01*
X309867Y384250D01*
X310367Y383917D01*
X310617Y383333D01*
Y381000D01*
G01X318900D02*
Y386000D01*
G01Y383500D02*
X319317Y384000D01*
X319817Y384250D01*
X320317Y384333D01*
X321067Y384167D01*
X321567Y383833D01*
X321900Y383250D01*
Y382583D01*
X321733Y381917D01*
X321400Y381417D01*
X320817Y381083D01*
X320317Y381000D01*
X319817Y381083D01*
X319317Y381333D01*
X318900Y381750D01*
G01X324750Y383250D02*
X327417D01*
X327167Y383833D01*
X326750Y384167D01*
X326167Y384333D01*
X325583Y384250D01*
X325083Y384000D01*
X324750Y383417D01*
X324583Y382917D01*
Y382417D01*
X324750Y381917D01*
X325167Y381417D01*
X325667Y381083D01*
X326250Y381000D01*
X326833Y381167D01*
X327417Y381667D01*
G01X331600Y381000D02*
Y386000D01*
G01X337200Y381000D02*
X336700Y381083D01*
X336200Y381417D01*
X335867Y382000D01*
X335700Y382667D01*
X335867Y383333D01*
X336200Y383917D01*
X336700Y384250D01*
X337200Y384333D01*
X337700Y384250D01*
X338200Y383917D01*
X338533Y383333D01*
X338617Y382667D01*
X338533Y382000D01*
X338200Y381417D01*
X337700Y381083D01*
X337200Y381000D01*
G01X340717Y384333D02*
X341717Y381000D01*
X342800Y384333D01*
X343883Y381000D01*
X344883Y384333D01*
G01X354000Y386000D02*
Y381000D01*
G01X352833Y384333D02*
X355167D01*
G01X358183Y381000D02*
Y386000D01*
G01Y383583D02*
X358600Y384000D01*
X359017Y384250D01*
X359683Y384333D01*
X360183Y384250D01*
X360767Y383917D01*
X361017Y383417D01*
Y381000D01*
G01X363950Y383250D02*
X366617D01*
X366367Y383833D01*
X365950Y384167D01*
X365367Y384333D01*
X364783Y384250D01*
X364283Y384000D01*
X363950Y383417D01*
X363783Y382917D01*
Y382417D01*
X363950Y381917D01*
X364367Y381417D01*
X364867Y381083D01*
X365450Y381000D01*
X366033Y381167D01*
X366617Y381667D01*
G01X373900Y381000D02*
Y384333D01*
G01Y383417D02*
X374150Y383833D01*
X374567Y384167D01*
X375150Y384333D01*
X375733Y384167D01*
X376150Y383833D01*
X376400Y383417D01*
Y381000D01*
G01Y383417D02*
X376650Y383833D01*
X377067Y384167D01*
X377650Y384333D01*
X378233Y384167D01*
X378650Y383833D01*
X378900Y383333D01*
Y381000D01*
G01X382000Y384333D02*
Y381000D01*
G01Y385667D02*
X381833Y385750D01*
Y385917D01*
X382000Y386000D01*
X382167Y385917D01*
Y385750D01*
X382000Y385667D01*
G01X386183Y381000D02*
Y384333D01*
G01Y383500D02*
X386517Y383917D01*
X387017Y384250D01*
X387683Y384333D01*
X388267Y384250D01*
X388767Y383917D01*
X389017Y383333D01*
Y381000D01*
G01X400133Y383917D02*
X399550Y384250D01*
X399050Y384333D01*
X398383Y384167D01*
X397883Y383833D01*
X397550Y383250D01*
X397467Y382667D01*
X397550Y382083D01*
X397883Y381583D01*
X398383Y381167D01*
X399050Y381000D01*
X399633Y381167D01*
X400133Y381500D01*
G01X404400Y381000D02*
X403900Y381083D01*
X403400Y381417D01*
X403067Y382000D01*
X402900Y382667D01*
X403067Y383333D01*
X403400Y383917D01*
X403900Y384250D01*
X404400Y384333D01*
X404900Y384250D01*
X405400Y383917D01*
X405733Y383333D01*
X405817Y382667D01*
X405733Y382000D01*
X405400Y381417D01*
X404900Y381083D01*
X404400Y381000D01*
G01X408583D02*
Y384333D01*
G01Y383500D02*
X408917Y383917D01*
X409417Y384250D01*
X410083Y384333D01*
X410667Y384250D01*
X411167Y383917D01*
X411417Y383333D01*
Y381000D01*
G01X417100Y386000D02*
Y381000D01*
G01Y381750D02*
X416767Y381333D01*
X416267Y381083D01*
X415683Y381000D01*
X415017Y381167D01*
X414517Y381583D01*
X414183Y382083D01*
X414100Y382667D01*
X414183Y383250D01*
X414517Y383750D01*
X415017Y384167D01*
X415683Y384333D01*
X416267Y384250D01*
X416683Y384083D01*
X417100Y383750D01*
G01X419783Y384333D02*
Y382000D01*
X420117Y381417D01*
X420617Y381083D01*
X421200Y381000D01*
X421783Y381083D01*
X422283Y381417D01*
X422617Y382000D01*
G01Y381000D02*
Y384333D01*
G01X428133Y383917D02*
X427550Y384250D01*
X427050Y384333D01*
X426383Y384167D01*
X425883Y383833D01*
X425550Y383250D01*
X425467Y382667D01*
X425550Y382083D01*
X425883Y381583D01*
X426383Y381167D01*
X427050Y381000D01*
X427633Y381167D01*
X428133Y381500D01*
G01X432400Y386000D02*
Y381000D01*
G01X431233Y384333D02*
X433567D01*
G01X438000Y381000D02*
X437500Y381083D01*
X437000Y381417D01*
X436667Y382000D01*
X436500Y382667D01*
X436667Y383333D01*
X437000Y383917D01*
X437500Y384250D01*
X438000Y384333D01*
X438500Y384250D01*
X439000Y383917D01*
X439333Y383333D01*
X439417Y382667D01*
X439333Y382000D01*
X439000Y381417D01*
X438500Y381083D01*
X438000Y381000D01*
G01X442433D02*
Y384333D01*
G01Y383667D02*
X442850Y384000D01*
X443267Y384250D01*
X443850Y384333D01*
X444267Y384250D01*
X444767Y384000D01*
G01X452717Y384333D02*
X453717Y381000D01*
X454800Y384333D01*
X455883Y381000D01*
X456883Y384333D01*
G01X460400D02*
Y381000D01*
G01Y385667D02*
X460233Y385750D01*
Y385917D01*
X460400Y386000D01*
X460567Y385917D01*
Y385750D01*
X460400Y385667D01*
G01X467500Y386000D02*
Y381000D01*
G01Y381750D02*
X467167Y381333D01*
X466667Y381083D01*
X466083Y381000D01*
X465417Y381167D01*
X464917Y381583D01*
X464583Y382083D01*
X464500Y382667D01*
X464583Y383250D01*
X464917Y383750D01*
X465417Y384167D01*
X466083Y384333D01*
X466667Y384250D01*
X467083Y384083D01*
X467500Y383750D01*
G01X471600Y386000D02*
Y381000D01*
G01X470433Y384333D02*
X472767D01*
G01X475783Y381000D02*
Y386000D01*
G01Y383583D02*
X476200Y384000D01*
X476617Y384250D01*
X477283Y384333D01*
X477783Y384250D01*
X478367Y383917D01*
X478617Y383417D01*
Y381000D01*
G01X487150Y381583D02*
X487567Y381250D01*
X488150Y381000D01*
X488650D01*
X489150Y381167D01*
X489483Y381417D01*
X489650Y381750D01*
X489567Y382250D01*
X489233Y382500D01*
X487733Y383000D01*
X487400Y383583D01*
X487567Y384000D01*
X487900Y384250D01*
X488400Y384333D01*
X488900Y384250D01*
X489400Y384000D01*
G01X492500Y379333D02*
Y384333D01*
G01Y383583D02*
X492917Y384000D01*
X493333Y384250D01*
X494000Y384333D01*
X494583Y384250D01*
X495167Y383833D01*
X495417Y383250D01*
X495500Y382667D01*
X495417Y382083D01*
X495167Y381500D01*
X494667Y381167D01*
X494000Y381000D01*
X493417Y381083D01*
X492833Y381333D01*
X492500Y381667D01*
G01X498350Y383250D02*
X501017D01*
X500767Y383833D01*
X500350Y384167D01*
X499767Y384333D01*
X499183Y384250D01*
X498683Y384000D01*
X498350Y383417D01*
X498183Y382917D01*
Y382417D01*
X498350Y381917D01*
X498767Y381417D01*
X499267Y381083D01*
X499850Y381000D01*
X500433Y381167D01*
X501017Y381667D01*
G01X506533Y383917D02*
X505950Y384250D01*
X505450Y384333D01*
X504783Y384167D01*
X504283Y383833D01*
X503950Y383250D01*
X503867Y382667D01*
X503950Y382083D01*
X504283Y381583D01*
X504783Y381167D01*
X505450Y381000D01*
X506033Y381167D01*
X506533Y381500D01*
G01X510800Y384333D02*
Y381000D01*
G01Y385667D02*
X510633Y385750D01*
Y385917D01*
X510800Y386000D01*
X510967Y385917D01*
Y385750D01*
X510800Y385667D01*
G01X515900Y381000D02*
Y385250D01*
X516067Y385667D01*
X516400Y385917D01*
X516900Y386000D01*
X517400Y385833D01*
X517650Y385417D01*
G01X516650Y384000D02*
X514983D01*
G01X522000Y384333D02*
Y381000D01*
G01Y385667D02*
X521833Y385750D01*
Y385917D01*
X522000Y386000D01*
X522167Y385917D01*
Y385750D01*
X522000Y385667D01*
G01X526350Y383250D02*
X529017D01*
X528767Y383833D01*
X528350Y384167D01*
X527767Y384333D01*
X527183Y384250D01*
X526683Y384000D01*
X526350Y383417D01*
X526183Y382917D01*
Y382417D01*
X526350Y381917D01*
X526767Y381417D01*
X527267Y381083D01*
X527850Y381000D01*
X528433Y381167D01*
X529017Y381667D01*
G01X534700Y386000D02*
Y381000D01*
G01Y381750D02*
X534367Y381333D01*
X533867Y381083D01*
X533283Y381000D01*
X532617Y381167D01*
X532117Y381583D01*
X531783Y382083D01*
X531700Y382667D01*
X531783Y383250D01*
X532117Y383750D01*
X532617Y384167D01*
X533283Y384333D01*
X533867Y384250D01*
X534283Y384083D01*
X534700Y383750D01*
G01X544400Y381000D02*
X543900Y381083D01*
X543400Y381417D01*
X543067Y382000D01*
X542900Y382667D01*
X543067Y383333D01*
X543400Y383917D01*
X543900Y384250D01*
X544400Y384333D01*
X544900Y384250D01*
X545400Y383917D01*
X545733Y383333D01*
X545817Y382667D01*
X545733Y382000D01*
X545400Y381417D01*
X544900Y381083D01*
X544400Y381000D01*
G01X548583D02*
Y384333D01*
G01Y383500D02*
X548917Y383917D01*
X549417Y384250D01*
X550083Y384333D01*
X550667Y384250D01*
X551167Y383917D01*
X551417Y383333D01*
Y381000D01*
G01X561200Y386000D02*
Y381000D01*
G01X560033Y384333D02*
X562367D01*
G01X565383Y381000D02*
Y386000D01*
G01Y383583D02*
X565800Y384000D01*
X566217Y384250D01*
X566883Y384333D01*
X567383Y384250D01*
X567967Y383917D01*
X568217Y383417D01*
Y381000D01*
G01X571150Y383250D02*
X573817D01*
X573567Y383833D01*
X573150Y384167D01*
X572567Y384333D01*
X571983Y384250D01*
X571483Y384000D01*
X571150Y383417D01*
X570983Y382917D01*
Y382417D01*
X571150Y381917D01*
X571567Y381417D01*
X572067Y381083D01*
X572650Y381000D01*
X573233Y381167D01*
X573817Y381667D01*
G01X268250Y391500D02*
Y396500D01*
G01X271750D02*
Y391500D01*
G01Y394000D02*
X268250D01*
G01X275600Y391500D02*
X275100Y391583D01*
X274600Y391917D01*
X274267Y392500D01*
X274100Y393167D01*
X274267Y393833D01*
X274600Y394417D01*
X275100Y394750D01*
X275600Y394833D01*
X276100Y394750D01*
X276600Y394417D01*
X276933Y393833D01*
X277017Y393167D01*
X276933Y392500D01*
X276600Y391917D01*
X276100Y391583D01*
X275600Y391500D01*
G01X279117Y394833D02*
X280117Y391500D01*
X281200Y394833D01*
X282283Y391500D01*
X283283Y394833D01*
G01X285550Y393750D02*
X288217D01*
X287967Y394333D01*
X287550Y394667D01*
X286967Y394833D01*
X286383Y394750D01*
X285883Y394500D01*
X285550Y393917D01*
X285383Y393417D01*
Y392917D01*
X285550Y392417D01*
X285967Y391917D01*
X286467Y391583D01*
X287050Y391500D01*
X287633Y391667D01*
X288217Y392167D01*
G01X290900Y394833D02*
X292400Y391500D01*
X293900Y394833D01*
G01X296750Y393750D02*
X299417D01*
X299167Y394333D01*
X298750Y394667D01*
X298167Y394833D01*
X297583Y394750D01*
X297083Y394500D01*
X296750Y393917D01*
X296583Y393417D01*
Y392917D01*
X296750Y392417D01*
X297167Y391917D01*
X297667Y391583D01*
X298250Y391500D01*
X298833Y391667D01*
X299417Y392167D01*
G01X302433Y391500D02*
Y394833D01*
G01Y394167D02*
X302850Y394500D01*
X303267Y394750D01*
X303850Y394833D01*
X304267Y394750D01*
X304767Y394500D01*
G01X309033Y390583D02*
X309367Y391667D01*
G01X314800Y396500D02*
Y391500D01*
G01X313633Y394833D02*
X315967D01*
G01X318983Y391500D02*
Y396500D01*
G01Y394083D02*
X319400Y394500D01*
X319817Y394750D01*
X320483Y394833D01*
X320983Y394750D01*
X321567Y394417D01*
X321817Y393917D01*
Y391500D01*
G01X324750Y393750D02*
X327417D01*
X327167Y394333D01*
X326750Y394667D01*
X326167Y394833D01*
X325583Y394750D01*
X325083Y394500D01*
X324750Y393917D01*
X324583Y393417D01*
Y392917D01*
X324750Y392417D01*
X325167Y391917D01*
X325667Y391583D01*
X326250Y391500D01*
X326833Y391667D01*
X327417Y392167D01*
G01X337200Y396500D02*
Y391500D01*
G01X336033Y394833D02*
X338367D01*
G01X344300Y391500D02*
Y394833D01*
G01Y394250D02*
X343967Y394583D01*
X343467Y394750D01*
X342883Y394833D01*
X342300Y394667D01*
X341800Y394333D01*
X341467Y393833D01*
X341300Y393167D01*
X341467Y392500D01*
X341800Y392000D01*
X342300Y391667D01*
X342883Y391500D01*
X343467Y391583D01*
X343967Y391833D01*
X344300Y392167D01*
G01X346983Y391500D02*
Y394833D01*
G01Y394000D02*
X347317Y394417D01*
X347817Y394750D01*
X348483Y394833D01*
X349067Y394750D01*
X349567Y394417D01*
X349817Y393833D01*
Y391500D01*
G01X352833Y390250D02*
X353417Y389917D01*
X354083Y389833D01*
X354667Y389917D01*
X355167Y390333D01*
X355500Y390917D01*
Y394833D01*
G01Y394167D02*
X355167Y394500D01*
X354667Y394750D01*
X354083Y394833D01*
X353417Y394667D01*
X353000Y394333D01*
X352667Y393750D01*
X352500Y393167D01*
X352583Y392667D01*
X352917Y392083D01*
X353417Y391667D01*
X354083Y391500D01*
X354583Y391583D01*
X355167Y391917D01*
X355500Y392250D01*
G01X358350Y393750D02*
X361017D01*
X360767Y394333D01*
X360350Y394667D01*
X359767Y394833D01*
X359183Y394750D01*
X358683Y394500D01*
X358350Y393917D01*
X358183Y393417D01*
Y392917D01*
X358350Y392417D01*
X358767Y391917D01*
X359267Y391583D01*
X359850Y391500D01*
X360433Y391667D01*
X361017Y392167D01*
G01X363783Y391500D02*
Y394833D01*
G01Y394000D02*
X364117Y394417D01*
X364617Y394750D01*
X365283Y394833D01*
X365867Y394750D01*
X366367Y394417D01*
X366617Y393833D01*
Y391500D01*
G01X372133Y394417D02*
X371550Y394750D01*
X371050Y394833D01*
X370383Y394667D01*
X369883Y394333D01*
X369550Y393750D01*
X369467Y393167D01*
X369550Y392583D01*
X369883Y392083D01*
X370383Y391667D01*
X371050Y391500D01*
X371633Y391667D01*
X372133Y392000D01*
G01X374650Y390000D02*
X375150Y389833D01*
X375817Y390000D01*
X376233Y390333D01*
X376567Y390750D01*
X377067Y392083D01*
X378150Y394833D01*
G01X375483D02*
X377067Y392083D01*
G01X386350D02*
X386767Y391750D01*
X387350Y391500D01*
X387850D01*
X388350Y391667D01*
X388683Y391917D01*
X388850Y392250D01*
X388767Y392750D01*
X388433Y393000D01*
X386933Y393500D01*
X386600Y394083D01*
X386767Y394500D01*
X387100Y394750D01*
X387600Y394833D01*
X388100Y394750D01*
X388600Y394500D01*
G01X391783Y391500D02*
Y396500D01*
G01Y394083D02*
X392200Y394500D01*
X392617Y394750D01*
X393283Y394833D01*
X393783Y394750D01*
X394367Y394417D01*
X394617Y393917D01*
Y391500D01*
G01X398800D02*
X398300Y391583D01*
X397800Y391917D01*
X397467Y392500D01*
X397300Y393167D01*
X397467Y393833D01*
X397800Y394417D01*
X398300Y394750D01*
X398800Y394833D01*
X399300Y394750D01*
X399800Y394417D01*
X400133Y393833D01*
X400217Y393167D01*
X400133Y392500D01*
X399800Y391917D01*
X399300Y391583D01*
X398800Y391500D01*
G01X402983Y394833D02*
Y392500D01*
X403317Y391917D01*
X403817Y391583D01*
X404400Y391500D01*
X404983Y391583D01*
X405483Y391917D01*
X405817Y392500D01*
G01Y391500D02*
Y394833D01*
G01X410000Y391500D02*
Y396500D01*
G01X417100D02*
Y391500D01*
G01Y392250D02*
X416767Y391833D01*
X416267Y391583D01*
X415683Y391500D01*
X415017Y391667D01*
X414517Y392083D01*
X414183Y392583D01*
X414100Y393167D01*
X414183Y393750D01*
X414517Y394250D01*
X415017Y394667D01*
X415683Y394833D01*
X416267Y394750D01*
X416683Y394583D01*
X417100Y394250D01*
G01X425383Y391500D02*
Y394833D01*
G01Y394000D02*
X425717Y394417D01*
X426217Y394750D01*
X426883Y394833D01*
X427467Y394750D01*
X427967Y394417D01*
X428217Y393833D01*
Y391500D01*
G01X432400D02*
X431900Y391583D01*
X431400Y391917D01*
X431067Y392500D01*
X430900Y393167D01*
X431067Y393833D01*
X431400Y394417D01*
X431900Y394750D01*
X432400Y394833D01*
X432900Y394750D01*
X433400Y394417D01*
X433733Y393833D01*
X433817Y393167D01*
X433733Y392500D01*
X433400Y391917D01*
X432900Y391583D01*
X432400Y391500D01*
G01X438000Y396500D02*
Y391500D01*
G01X436833Y394833D02*
X439167D01*
G01X448033Y391500D02*
Y394833D01*
G01Y394167D02*
X448450Y394500D01*
X448867Y394750D01*
X449450Y394833D01*
X449867Y394750D01*
X450367Y394500D01*
G01X453550Y393750D02*
X456217D01*
X455967Y394333D01*
X455550Y394667D01*
X454967Y394833D01*
X454383Y394750D01*
X453883Y394500D01*
X453550Y393917D01*
X453383Y393417D01*
Y392917D01*
X453550Y392417D01*
X453967Y391917D01*
X454467Y391583D01*
X455050Y391500D01*
X455633Y391667D01*
X456217Y392167D01*
G01X461900Y396500D02*
Y391500D01*
G01Y392250D02*
X461567Y391833D01*
X461067Y391583D01*
X460483Y391500D01*
X459817Y391667D01*
X459317Y392083D01*
X458983Y392583D01*
X458900Y393167D01*
X458983Y393750D01*
X459317Y394250D01*
X459817Y394667D01*
X460483Y394833D01*
X461067Y394750D01*
X461483Y394583D01*
X461900Y394250D01*
G01X464583Y394833D02*
Y392500D01*
X464917Y391917D01*
X465417Y391583D01*
X466000Y391500D01*
X466583Y391583D01*
X467083Y391917D01*
X467417Y392500D01*
G01Y391500D02*
Y394833D01*
G01X472933Y394417D02*
X472350Y394750D01*
X471850Y394833D01*
X471183Y394667D01*
X470683Y394333D01*
X470350Y393750D01*
X470267Y393167D01*
X470350Y392583D01*
X470683Y392083D01*
X471183Y391667D01*
X471850Y391500D01*
X472433Y391667D01*
X472933Y392000D01*
G01X475950Y393750D02*
X478617D01*
X478367Y394333D01*
X477950Y394667D01*
X477367Y394833D01*
X476783Y394750D01*
X476283Y394500D01*
X475950Y393917D01*
X475783Y393417D01*
Y392917D01*
X475950Y392417D01*
X476367Y391917D01*
X476867Y391583D01*
X477450Y391500D01*
X478033Y391667D01*
X478617Y392167D01*
G01X488400Y396500D02*
Y391500D01*
G01X487233Y394833D02*
X489567D01*
G01X492583Y391500D02*
Y396500D01*
G01Y394083D02*
X493000Y394500D01*
X493417Y394750D01*
X494083Y394833D01*
X494583Y394750D01*
X495167Y394417D01*
X495417Y393917D01*
Y391500D01*
G01X498350Y393750D02*
X501017D01*
X500767Y394333D01*
X500350Y394667D01*
X499767Y394833D01*
X499183Y394750D01*
X498683Y394500D01*
X498350Y393917D01*
X498183Y393417D01*
Y392917D01*
X498350Y392417D01*
X498767Y391917D01*
X499267Y391583D01*
X499850Y391500D01*
X500433Y391667D01*
X501017Y392167D01*
G01X510800Y391500D02*
Y396500D01*
G01X517900Y391500D02*
Y394833D01*
G01Y394250D02*
X517567Y394583D01*
X517067Y394750D01*
X516483Y394833D01*
X515900Y394667D01*
X515400Y394333D01*
X515067Y393833D01*
X514900Y393167D01*
X515067Y392500D01*
X515400Y392000D01*
X515900Y391667D01*
X516483Y391500D01*
X517067Y391583D01*
X517567Y391833D01*
X517900Y392167D01*
G01X520583Y391500D02*
Y394833D01*
G01Y394000D02*
X520917Y394417D01*
X521417Y394750D01*
X522083Y394833D01*
X522667Y394750D01*
X523167Y394417D01*
X523417Y393833D01*
Y391500D01*
G01X529100Y396500D02*
Y391500D01*
G01Y392250D02*
X528767Y391833D01*
X528267Y391583D01*
X527683Y391500D01*
X527017Y391667D01*
X526517Y392083D01*
X526183Y392583D01*
X526100Y393167D01*
X526183Y393750D01*
X526517Y394250D01*
X527017Y394667D01*
X527683Y394833D01*
X528267Y394750D01*
X528683Y394583D01*
X529100Y394250D01*
G01X531700Y391333D02*
X534700Y396500D01*
G01X540133Y394417D02*
X539550Y394750D01*
X539050Y394833D01*
X538383Y394667D01*
X537883Y394333D01*
X537550Y393750D01*
X537467Y393167D01*
X537550Y392583D01*
X537883Y392083D01*
X538383Y391667D01*
X539050Y391500D01*
X539633Y391667D01*
X540133Y392000D01*
G01X544400Y391500D02*
X543900Y391583D01*
X543400Y391917D01*
X543067Y392500D01*
X542900Y393167D01*
X543067Y393833D01*
X543400Y394417D01*
X543900Y394750D01*
X544400Y394833D01*
X544900Y394750D01*
X545400Y394417D01*
X545733Y393833D01*
X545817Y393167D01*
X545733Y392500D01*
X545400Y391917D01*
X544900Y391583D01*
X544400Y391500D01*
G01X548583D02*
Y394833D01*
G01Y394000D02*
X548917Y394417D01*
X549417Y394750D01*
X550083Y394833D01*
X550667Y394750D01*
X551167Y394417D01*
X551417Y393833D01*
Y391500D01*
G01X557100Y396500D02*
Y391500D01*
G01Y392250D02*
X556767Y391833D01*
X556267Y391583D01*
X555683Y391500D01*
X555017Y391667D01*
X554517Y392083D01*
X554183Y392583D01*
X554100Y393167D01*
X554183Y393750D01*
X554517Y394250D01*
X555017Y394667D01*
X555683Y394833D01*
X556267Y394750D01*
X556683Y394583D01*
X557100Y394250D01*
G01X559783Y394833D02*
Y392500D01*
X560117Y391917D01*
X560617Y391583D01*
X561200Y391500D01*
X561783Y391583D01*
X562283Y391917D01*
X562617Y392500D01*
G01Y391500D02*
Y394833D01*
G01X568133Y394417D02*
X567550Y394750D01*
X567050Y394833D01*
X566383Y394667D01*
X565883Y394333D01*
X565550Y393750D01*
X565467Y393167D01*
X565550Y392583D01*
X565883Y392083D01*
X566383Y391667D01*
X567050Y391500D01*
X567633Y391667D01*
X568133Y392000D01*
G01X572400Y396500D02*
Y391500D01*
G01X571233Y394833D02*
X573567D01*
G01X578000Y391500D02*
X577500Y391583D01*
X577000Y391917D01*
X576667Y392500D01*
X576500Y393167D01*
X576667Y393833D01*
X577000Y394417D01*
X577500Y394750D01*
X578000Y394833D01*
X578500Y394750D01*
X579000Y394417D01*
X579333Y393833D01*
X579417Y393167D01*
X579333Y392500D01*
X579000Y391917D01*
X578500Y391583D01*
X578000Y391500D01*
G01X582433D02*
Y394833D01*
G01Y394167D02*
X582850Y394500D01*
X583267Y394750D01*
X583850Y394833D01*
X584267Y394750D01*
X584767Y394500D01*
G01X271500Y402000D02*
Y405333D01*
G01Y404750D02*
X271167Y405083D01*
X270667Y405250D01*
X270083Y405333D01*
X269500Y405167D01*
X269000Y404833D01*
X268667Y404333D01*
X268500Y403667D01*
X268667Y403000D01*
X269000Y402500D01*
X269500Y402167D01*
X270083Y402000D01*
X270667Y402083D01*
X271167Y402333D01*
X271500Y402667D01*
G01X276933Y404917D02*
X276350Y405250D01*
X275850Y405333D01*
X275183Y405167D01*
X274683Y404833D01*
X274350Y404250D01*
X274267Y403667D01*
X274350Y403083D01*
X274683Y402583D01*
X275183Y402167D01*
X275850Y402000D01*
X276433Y402167D01*
X276933Y402500D01*
G01X282533Y404917D02*
X281950Y405250D01*
X281450Y405333D01*
X280783Y405167D01*
X280283Y404833D01*
X279950Y404250D01*
X279867Y403667D01*
X279950Y403083D01*
X280283Y402583D01*
X280783Y402167D01*
X281450Y402000D01*
X282033Y402167D01*
X282533Y402500D01*
G01X285550Y404250D02*
X288217D01*
X287967Y404833D01*
X287550Y405167D01*
X286967Y405333D01*
X286383Y405250D01*
X285883Y405000D01*
X285550Y404417D01*
X285383Y403917D01*
Y403417D01*
X285550Y402917D01*
X285967Y402417D01*
X286467Y402083D01*
X287050Y402000D01*
X287633Y402167D01*
X288217Y402667D01*
G01X290900Y400333D02*
Y405333D01*
G01Y404583D02*
X291317Y405000D01*
X291733Y405250D01*
X292400Y405333D01*
X292983Y405250D01*
X293567Y404833D01*
X293817Y404250D01*
X293900Y403667D01*
X293817Y403083D01*
X293567Y402500D01*
X293067Y402167D01*
X292400Y402000D01*
X291817Y402083D01*
X291233Y402333D01*
X290900Y402667D01*
G01X298000Y407000D02*
Y402000D01*
G01X296833Y405333D02*
X299167D01*
G01X305100Y402000D02*
Y405333D01*
G01Y404750D02*
X304767Y405083D01*
X304267Y405250D01*
X303683Y405333D01*
X303100Y405167D01*
X302600Y404833D01*
X302267Y404333D01*
X302100Y403667D01*
X302267Y403000D01*
X302600Y402500D01*
X303100Y402167D01*
X303683Y402000D01*
X304267Y402083D01*
X304767Y402333D01*
X305100Y402667D01*
G01X307700Y402000D02*
Y407000D01*
G01Y404500D02*
X308117Y405000D01*
X308617Y405250D01*
X309117Y405333D01*
X309867Y405167D01*
X310367Y404833D01*
X310700Y404250D01*
Y403583D01*
X310533Y402917D01*
X310200Y402417D01*
X309617Y402083D01*
X309117Y402000D01*
X308617Y402083D01*
X308117Y402333D01*
X307700Y402750D01*
G01X314800Y402000D02*
Y407000D01*
G01X319150Y404250D02*
X321817D01*
X321567Y404833D01*
X321150Y405167D01*
X320567Y405333D01*
X319983Y405250D01*
X319483Y405000D01*
X319150Y404417D01*
X318983Y403917D01*
Y403417D01*
X319150Y402917D01*
X319567Y402417D01*
X320067Y402083D01*
X320650Y402000D01*
X321233Y402167D01*
X321817Y402667D01*
G01X326000Y401833D02*
X325833Y401917D01*
Y402083D01*
X326000Y402167D01*
X326167Y402083D01*
Y401917D01*
X326000Y401833D01*
G01X262500Y397000D02*
Y679000D01*
G01X270000Y417500D02*
Y412500D01*
G01X268083Y417500D02*
X271917D01*
G01X274183Y412500D02*
Y417500D01*
G01Y415083D02*
X274600Y415500D01*
X275017Y415750D01*
X275683Y415833D01*
X276183Y415750D01*
X276767Y415417D01*
X277017Y414917D01*
Y412500D01*
G01X279950Y414750D02*
X282617D01*
X282367Y415333D01*
X281950Y415667D01*
X281367Y415833D01*
X280783Y415750D01*
X280283Y415500D01*
X279950Y414917D01*
X279783Y414417D01*
Y413917D01*
X279950Y413417D01*
X280367Y412917D01*
X280867Y412583D01*
X281450Y412500D01*
X282033Y412667D01*
X282617Y413167D01*
G01X290900Y412500D02*
Y417500D01*
G01Y415000D02*
X291317Y415500D01*
X291817Y415750D01*
X292317Y415833D01*
X293067Y415667D01*
X293567Y415333D01*
X293900Y414750D01*
Y414083D01*
X293733Y413417D01*
X293400Y412917D01*
X292817Y412583D01*
X292317Y412500D01*
X291817Y412583D01*
X291317Y412833D01*
X290900Y413250D01*
G01X296833Y412500D02*
Y415833D01*
G01Y415167D02*
X297250Y415500D01*
X297667Y415750D01*
X298250Y415833D01*
X298667Y415750D01*
X299167Y415500D01*
G01X302350Y414750D02*
X305017D01*
X304767Y415333D01*
X304350Y415667D01*
X303767Y415833D01*
X303183Y415750D01*
X302683Y415500D01*
X302350Y414917D01*
X302183Y414417D01*
Y413917D01*
X302350Y413417D01*
X302767Y412917D01*
X303267Y412583D01*
X303850Y412500D01*
X304433Y412667D01*
X305017Y413167D01*
G01X310700Y412500D02*
Y415833D01*
G01Y415250D02*
X310367Y415583D01*
X309867Y415750D01*
X309283Y415833D01*
X308700Y415667D01*
X308200Y415333D01*
X307867Y414833D01*
X307700Y414167D01*
X307867Y413500D01*
X308200Y413000D01*
X308700Y412667D01*
X309283Y412500D01*
X309867Y412583D01*
X310367Y412833D01*
X310700Y413167D01*
G01X313383Y412500D02*
Y417500D01*
G01X316050Y415833D02*
X313383Y413917D01*
G01X314467Y414667D02*
X316217Y412500D01*
G01X320400D02*
X319900Y412583D01*
X319400Y412917D01*
X319067Y413500D01*
X318900Y414167D01*
X319067Y414833D01*
X319400Y415417D01*
X319900Y415750D01*
X320400Y415833D01*
X320900Y415750D01*
X321400Y415417D01*
X321733Y414833D01*
X321817Y414167D01*
X321733Y413500D01*
X321400Y412917D01*
X320900Y412583D01*
X320400Y412500D01*
G01X324583Y415833D02*
Y413500D01*
X324917Y412917D01*
X325417Y412583D01*
X326000Y412500D01*
X326583Y412583D01*
X327083Y412917D01*
X327417Y413500D01*
G01Y412500D02*
Y415833D01*
G01X331600Y417500D02*
Y412500D01*
G01X330433Y415833D02*
X332767D01*
G01X342800D02*
Y412500D01*
G01Y417167D02*
X342633Y417250D01*
Y417417D01*
X342800Y417500D01*
X342967Y417417D01*
Y417250D01*
X342800Y417167D01*
G01X347150Y413083D02*
X347567Y412750D01*
X348150Y412500D01*
X348650D01*
X349150Y412667D01*
X349483Y412917D01*
X349650Y413250D01*
X349567Y413750D01*
X349233Y414000D01*
X347733Y414500D01*
X347400Y415083D01*
X347567Y415500D01*
X347900Y415750D01*
X348400Y415833D01*
X348900Y415750D01*
X349400Y415500D01*
G01X358183Y412500D02*
Y415833D01*
G01Y415000D02*
X358517Y415417D01*
X359017Y415750D01*
X359683Y415833D01*
X360267Y415750D01*
X360767Y415417D01*
X361017Y414833D01*
Y412500D01*
G01X365200D02*
X364700Y412583D01*
X364200Y412917D01*
X363867Y413500D01*
X363700Y414167D01*
X363867Y414833D01*
X364200Y415417D01*
X364700Y415750D01*
X365200Y415833D01*
X365700Y415750D01*
X366200Y415417D01*
X366533Y414833D01*
X366617Y414167D01*
X366533Y413500D01*
X366200Y412917D01*
X365700Y412583D01*
X365200Y412500D01*
G01X370800Y417500D02*
Y412500D01*
G01X369633Y415833D02*
X371967D01*
G01X383500Y412500D02*
Y415833D01*
G01Y415250D02*
X383167Y415583D01*
X382667Y415750D01*
X382083Y415833D01*
X381500Y415667D01*
X381000Y415333D01*
X380667Y414833D01*
X380500Y414167D01*
X380667Y413500D01*
X381000Y413000D01*
X381500Y412667D01*
X382083Y412500D01*
X382667Y412583D01*
X383167Y412833D01*
X383500Y413167D01*
G01X387600Y412500D02*
Y417500D01*
G01X393200Y412500D02*
Y417500D01*
G01X398800Y412500D02*
X398300Y412583D01*
X397800Y412917D01*
X397467Y413500D01*
X397300Y414167D01*
X397467Y414833D01*
X397800Y415417D01*
X398300Y415750D01*
X398800Y415833D01*
X399300Y415750D01*
X399800Y415417D01*
X400133Y414833D01*
X400217Y414167D01*
X400133Y413500D01*
X399800Y412917D01*
X399300Y412583D01*
X398800Y412500D01*
G01X402317Y415833D02*
X403317Y412500D01*
X404400Y415833D01*
X405483Y412500D01*
X406483Y415833D01*
G01X408750Y414750D02*
X411417D01*
X411167Y415333D01*
X410750Y415667D01*
X410167Y415833D01*
X409583Y415750D01*
X409083Y415500D01*
X408750Y414917D01*
X408583Y414417D01*
Y413917D01*
X408750Y413417D01*
X409167Y412917D01*
X409667Y412583D01*
X410250Y412500D01*
X410833Y412667D01*
X411417Y413167D01*
G01X417100Y417500D02*
Y412500D01*
G01Y413250D02*
X416767Y412833D01*
X416267Y412583D01*
X415683Y412500D01*
X415017Y412667D01*
X414517Y413083D01*
X414183Y413583D01*
X414100Y414167D01*
X414183Y414750D01*
X414517Y415250D01*
X415017Y415667D01*
X415683Y415833D01*
X416267Y415750D01*
X416683Y415583D01*
X417100Y415250D01*
G01X421033Y411583D02*
X421367Y412667D01*
G01X436500Y412500D02*
Y417500D01*
G01Y415000D02*
X436917Y415500D01*
X437417Y415750D01*
X437917Y415833D01*
X438667Y415667D01*
X439167Y415333D01*
X439500Y414750D01*
Y414083D01*
X439333Y413417D01*
X439000Y412917D01*
X438417Y412583D01*
X437917Y412500D01*
X437417Y412583D01*
X436917Y412833D01*
X436500Y413250D01*
G01X442183Y415833D02*
Y413500D01*
X442517Y412917D01*
X443017Y412583D01*
X443600Y412500D01*
X444183Y412583D01*
X444683Y412917D01*
X445017Y413500D01*
G01Y412500D02*
Y415833D01*
G01X449200Y417500D02*
Y412500D01*
G01X448033Y415833D02*
X450367D01*
G01X461900Y412500D02*
Y415833D01*
G01Y415250D02*
X461567Y415583D01*
X461067Y415750D01*
X460483Y415833D01*
X459900Y415667D01*
X459400Y415333D01*
X459067Y414833D01*
X458900Y414167D01*
X459067Y413500D01*
X459400Y413000D01*
X459900Y412667D01*
X460483Y412500D01*
X461067Y412583D01*
X461567Y412833D01*
X461900Y413167D01*
G01X464583Y412500D02*
Y415833D01*
G01Y415000D02*
X464917Y415417D01*
X465417Y415750D01*
X466083Y415833D01*
X466667Y415750D01*
X467167Y415417D01*
X467417Y414833D01*
Y412500D01*
G01X470183D02*
Y415833D01*
G01Y415000D02*
X470517Y415417D01*
X471017Y415750D01*
X471683Y415833D01*
X472267Y415750D01*
X472767Y415417D01*
X473017Y414833D01*
Y412500D01*
G01X475783Y415833D02*
Y413500D01*
X476117Y412917D01*
X476617Y412583D01*
X477200Y412500D01*
X477783Y412583D01*
X478283Y412917D01*
X478617Y413500D01*
G01Y412500D02*
Y415833D01*
G01X484300Y412500D02*
Y415833D01*
G01Y415250D02*
X483967Y415583D01*
X483467Y415750D01*
X482883Y415833D01*
X482300Y415667D01*
X481800Y415333D01*
X481467Y414833D01*
X481300Y414167D01*
X481467Y413500D01*
X481800Y413000D01*
X482300Y412667D01*
X482883Y412500D01*
X483467Y412583D01*
X483967Y412833D01*
X484300Y413167D01*
G01X488400Y412500D02*
Y417500D01*
G01X498433Y412500D02*
Y415833D01*
G01Y415167D02*
X498850Y415500D01*
X499267Y415750D01*
X499850Y415833D01*
X500267Y415750D01*
X500767Y415500D01*
G01X505200Y415833D02*
Y412500D01*
G01Y417167D02*
X505033Y417250D01*
Y417417D01*
X505200Y417500D01*
X505367Y417417D01*
Y417250D01*
X505200Y417167D01*
G01X509383Y412500D02*
Y415833D01*
G01Y415000D02*
X509717Y415417D01*
X510217Y415750D01*
X510883Y415833D01*
X511467Y415750D01*
X511967Y415417D01*
X512217Y414833D01*
Y412500D01*
G01X515233Y411250D02*
X515817Y410917D01*
X516483Y410833D01*
X517067Y410917D01*
X517567Y411333D01*
X517900Y411917D01*
Y415833D01*
G01Y415167D02*
X517567Y415500D01*
X517067Y415750D01*
X516483Y415833D01*
X515817Y415667D01*
X515400Y415333D01*
X515067Y414750D01*
X514900Y414167D01*
X514983Y413667D01*
X515317Y413083D01*
X515817Y412667D01*
X516483Y412500D01*
X516983Y412583D01*
X517567Y412917D01*
X517900Y413250D01*
G01X527600Y417500D02*
Y412500D01*
G01X526433Y415833D02*
X528767D01*
G01X534700Y412500D02*
Y415833D01*
G01Y415250D02*
X534367Y415583D01*
X533867Y415750D01*
X533283Y415833D01*
X532700Y415667D01*
X532200Y415333D01*
X531867Y414833D01*
X531700Y414167D01*
X531867Y413500D01*
X532200Y413000D01*
X532700Y412667D01*
X533283Y412500D01*
X533867Y412583D01*
X534367Y412833D01*
X534700Y413167D01*
G01X537383Y412500D02*
Y415833D01*
G01Y415000D02*
X537717Y415417D01*
X538217Y415750D01*
X538883Y415833D01*
X539467Y415750D01*
X539967Y415417D01*
X540217Y414833D01*
Y412500D01*
G01X543233Y411250D02*
X543817Y410917D01*
X544483Y410833D01*
X545067Y410917D01*
X545567Y411333D01*
X545900Y411917D01*
Y415833D01*
G01Y415167D02*
X545567Y415500D01*
X545067Y415750D01*
X544483Y415833D01*
X543817Y415667D01*
X543400Y415333D01*
X543067Y414750D01*
X542900Y414167D01*
X542983Y413667D01*
X543317Y413083D01*
X543817Y412667D01*
X544483Y412500D01*
X544983Y412583D01*
X545567Y412917D01*
X545900Y413250D01*
G01X548750Y414750D02*
X551417D01*
X551167Y415333D01*
X550750Y415667D01*
X550167Y415833D01*
X549583Y415750D01*
X549083Y415500D01*
X548750Y414917D01*
X548583Y414417D01*
Y413917D01*
X548750Y413417D01*
X549167Y412917D01*
X549667Y412583D01*
X550250Y412500D01*
X550833Y412667D01*
X551417Y413167D01*
G01X554183Y412500D02*
Y415833D01*
G01Y415000D02*
X554517Y415417D01*
X555017Y415750D01*
X555683Y415833D01*
X556267Y415750D01*
X556767Y415417D01*
X557017Y414833D01*
Y412500D01*
G01X562533Y415417D02*
X561950Y415750D01*
X561450Y415833D01*
X560783Y415667D01*
X560283Y415333D01*
X559950Y414750D01*
X559867Y414167D01*
X559950Y413583D01*
X560283Y413083D01*
X560783Y412667D01*
X561450Y412500D01*
X562033Y412667D01*
X562533Y413000D01*
G01X565050Y411000D02*
X565550Y410833D01*
X566217Y411000D01*
X566633Y411333D01*
X566967Y411750D01*
X567467Y413083D01*
X568550Y415833D01*
G01X565883D02*
X567467Y413083D01*
G01X578000Y415833D02*
Y412500D01*
G01Y417167D02*
X577833Y417250D01*
Y417417D01*
X578000Y417500D01*
X578167Y417417D01*
Y417250D01*
X578000Y417167D01*
G01X582350Y413083D02*
X582767Y412750D01*
X583350Y412500D01*
X583850D01*
X584350Y412667D01*
X584683Y412917D01*
X584850Y413250D01*
X584767Y413750D01*
X584433Y414000D01*
X582933Y414500D01*
X582600Y415083D01*
X582767Y415500D01*
X583100Y415750D01*
X583600Y415833D01*
X584100Y415750D01*
X584600Y415500D01*
G01X273000Y437500D02*
Y432500D01*
G01Y433250D02*
X272667Y432833D01*
X272167Y432583D01*
X271583Y432500D01*
X270917Y432667D01*
X270417Y433083D01*
X270083Y433583D01*
X270000Y434167D01*
X270083Y434750D01*
X270417Y435250D01*
X270917Y435667D01*
X271583Y435833D01*
X272167Y435750D01*
X272583Y435583D01*
X273000Y435250D01*
G01X275850Y434750D02*
X278517D01*
X278267Y435333D01*
X277850Y435667D01*
X277267Y435833D01*
X276683Y435750D01*
X276183Y435500D01*
X275850Y434917D01*
X275683Y434417D01*
Y433917D01*
X275850Y433417D01*
X276267Y432917D01*
X276767Y432583D01*
X277350Y432500D01*
X277933Y432667D01*
X278517Y433167D01*
G01X281200Y430833D02*
Y435833D01*
G01Y435083D02*
X281617Y435500D01*
X282033Y435750D01*
X282700Y435833D01*
X283283Y435750D01*
X283867Y435333D01*
X284117Y434750D01*
X284200Y434167D01*
X284117Y433583D01*
X283867Y433000D01*
X283367Y432667D01*
X282700Y432500D01*
X282117Y432583D01*
X281533Y432833D01*
X281200Y433167D01*
G01X288300Y437500D02*
Y432500D01*
G01X287133Y435833D02*
X289467D01*
G01X292483Y432500D02*
Y437500D01*
G01Y435083D02*
X292900Y435500D01*
X293317Y435750D01*
X293983Y435833D01*
X294483Y435750D01*
X295067Y435417D01*
X295317Y434917D01*
Y432500D01*
G01X305100Y437500D02*
Y432500D01*
G01X303933Y435833D02*
X306267D01*
G01X310700Y432500D02*
X310200Y432583D01*
X309700Y432917D01*
X309367Y433500D01*
X309200Y434167D01*
X309367Y434833D01*
X309700Y435417D01*
X310200Y435750D01*
X310700Y435833D01*
X311200Y435750D01*
X311700Y435417D01*
X312033Y434833D01*
X312117Y434167D01*
X312033Y433500D01*
X311700Y432917D01*
X311200Y432583D01*
X310700Y432500D01*
G01X316300D02*
Y437500D01*
G01X320650Y434750D02*
X323317D01*
X323067Y435333D01*
X322650Y435667D01*
X322067Y435833D01*
X321483Y435750D01*
X320983Y435500D01*
X320650Y434917D01*
X320483Y434417D01*
Y433917D01*
X320650Y433417D01*
X321067Y432917D01*
X321567Y432583D01*
X322150Y432500D01*
X322733Y432667D01*
X323317Y433167D01*
G01X326333Y432500D02*
Y435833D01*
G01Y435167D02*
X326750Y435500D01*
X327167Y435750D01*
X327750Y435833D01*
X328167Y435750D01*
X328667Y435500D01*
G01X334600Y432500D02*
Y435833D01*
G01Y435250D02*
X334267Y435583D01*
X333767Y435750D01*
X333183Y435833D01*
X332600Y435667D01*
X332100Y435333D01*
X331767Y434833D01*
X331600Y434167D01*
X331767Y433500D01*
X332100Y433000D01*
X332600Y432667D01*
X333183Y432500D01*
X333767Y432583D01*
X334267Y432833D01*
X334600Y433167D01*
G01X337283Y432500D02*
Y435833D01*
G01Y435000D02*
X337617Y435417D01*
X338117Y435750D01*
X338783Y435833D01*
X339367Y435750D01*
X339867Y435417D01*
X340117Y434833D01*
Y432500D01*
G01X345633Y435417D02*
X345050Y435750D01*
X344550Y435833D01*
X343883Y435667D01*
X343383Y435333D01*
X343050Y434750D01*
X342967Y434167D01*
X343050Y433583D01*
X343383Y433083D01*
X343883Y432667D01*
X344550Y432500D01*
X345133Y432667D01*
X345633Y433000D01*
G01X348650Y434750D02*
X351317D01*
X351067Y435333D01*
X350650Y435667D01*
X350067Y435833D01*
X349483Y435750D01*
X348983Y435500D01*
X348650Y434917D01*
X348483Y434417D01*
Y433917D01*
X348650Y433417D01*
X349067Y432917D01*
X349567Y432583D01*
X350150Y432500D01*
X350733Y432667D01*
X351317Y433167D01*
G01X270750Y453500D02*
Y458500D01*
G01X274250D02*
Y453500D01*
G01Y456000D02*
X270750D01*
G01X278100Y453500D02*
X277600Y453583D01*
X277100Y453917D01*
X276767Y454500D01*
X276600Y455167D01*
X276767Y455833D01*
X277100Y456417D01*
X277600Y456750D01*
X278100Y456833D01*
X278600Y456750D01*
X279100Y456417D01*
X279433Y455833D01*
X279517Y455167D01*
X279433Y454500D01*
X279100Y453917D01*
X278600Y453583D01*
X278100Y453500D01*
G01X283700D02*
Y458500D01*
G01X288050Y455750D02*
X290717D01*
X290467Y456333D01*
X290050Y456667D01*
X289467Y456833D01*
X288883Y456750D01*
X288383Y456500D01*
X288050Y455917D01*
X287883Y455417D01*
Y454917D01*
X288050Y454417D01*
X288467Y453917D01*
X288967Y453583D01*
X289550Y453500D01*
X290133Y453667D01*
X290717Y454167D01*
G01X298000Y458500D02*
X299167Y453500D01*
X300500Y458500D01*
X301833Y453500D01*
X303000Y458500D01*
G01X307600Y453500D02*
Y456833D01*
G01Y456250D02*
X307267Y456583D01*
X306767Y456750D01*
X306183Y456833D01*
X305600Y456667D01*
X305100Y456333D01*
X304767Y455833D01*
X304600Y455167D01*
X304767Y454500D01*
X305100Y454000D01*
X305600Y453667D01*
X306183Y453500D01*
X306767Y453583D01*
X307267Y453833D01*
X307600Y454167D01*
G01X311700Y453500D02*
Y458500D01*
G01X317300Y453500D02*
Y458500D01*
G01X326833Y453500D02*
Y458500D01*
X328917D01*
X329583Y458250D01*
X330000Y457917D01*
X330167Y457250D01*
X330000Y456583D01*
X329500Y456167D01*
X328917Y455917D01*
X326833D01*
G01X328917D02*
X330167Y453500D01*
G01X334100D02*
X333600Y453583D01*
X333100Y453917D01*
X332767Y454500D01*
X332600Y455167D01*
X332767Y455833D01*
X333100Y456417D01*
X333600Y456750D01*
X334100Y456833D01*
X334600Y456750D01*
X335100Y456417D01*
X335433Y455833D01*
X335517Y455167D01*
X335433Y454500D01*
X335100Y453917D01*
X334600Y453583D01*
X334100Y453500D01*
G01X338283Y456833D02*
Y454500D01*
X338617Y453917D01*
X339117Y453583D01*
X339700Y453500D01*
X340283Y453583D01*
X340783Y453917D01*
X341117Y454500D01*
G01Y453500D02*
Y456833D01*
G01X344133Y452250D02*
X344717Y451917D01*
X345383Y451833D01*
X345967Y451917D01*
X346467Y452333D01*
X346800Y452917D01*
Y456833D01*
G01Y456167D02*
X346467Y456500D01*
X345967Y456750D01*
X345383Y456833D01*
X344717Y456667D01*
X344300Y456333D01*
X343967Y455750D01*
X343800Y455167D01*
X343883Y454667D01*
X344217Y454083D01*
X344717Y453667D01*
X345383Y453500D01*
X345883Y453583D01*
X346467Y453917D01*
X346800Y454250D01*
G01X349483Y453500D02*
Y458500D01*
G01Y456083D02*
X349900Y456500D01*
X350317Y456750D01*
X350983Y456833D01*
X351483Y456750D01*
X352067Y456417D01*
X352317Y455917D01*
Y453500D01*
G01X355083D02*
Y456833D01*
G01Y456000D02*
X355417Y456417D01*
X355917Y456750D01*
X356583Y456833D01*
X357167Y456750D01*
X357667Y456417D01*
X357917Y455833D01*
Y453500D01*
G01X360850Y455750D02*
X363517D01*
X363267Y456333D01*
X362850Y456667D01*
X362267Y456833D01*
X361683Y456750D01*
X361183Y456500D01*
X360850Y455917D01*
X360683Y455417D01*
Y454917D01*
X360850Y454417D01*
X361267Y453917D01*
X361767Y453583D01*
X362350Y453500D01*
X362933Y453667D01*
X363517Y454167D01*
G01X366450Y454083D02*
X366867Y453750D01*
X367450Y453500D01*
X367950D01*
X368450Y453667D01*
X368783Y453917D01*
X368950Y454250D01*
X368867Y454750D01*
X368533Y455000D01*
X367033Y455500D01*
X366700Y456083D01*
X366867Y456500D01*
X367200Y456750D01*
X367700Y456833D01*
X368200Y456750D01*
X368700Y456500D01*
G01X372050Y454083D02*
X372467Y453750D01*
X373050Y453500D01*
X373550D01*
X374050Y453667D01*
X374383Y453917D01*
X374550Y454250D01*
X374467Y454750D01*
X374133Y455000D01*
X372633Y455500D01*
X372300Y456083D01*
X372467Y456500D01*
X372800Y456750D01*
X373300Y456833D01*
X373800Y456750D01*
X374300Y456500D01*
G01X272500Y470000D02*
X271833Y470083D01*
X271250Y470417D01*
X270750Y470917D01*
X270417Y471500D01*
X270250Y472167D01*
Y472833D01*
X270417Y473500D01*
X270750Y474083D01*
X271250Y474583D01*
X271833Y474917D01*
X272500Y475000D01*
X273167Y474917D01*
X273750Y474583D01*
X274250Y474083D01*
X274583Y473500D01*
X274750Y472833D01*
Y472167D01*
X274583Y471500D01*
X274250Y470917D01*
X273750Y470417D01*
X273167Y470083D01*
X272500Y470000D01*
G01X278100Y475000D02*
Y470000D01*
G01X276933Y473333D02*
X279267D01*
G01X282283Y470000D02*
Y475000D01*
G01Y472583D02*
X282700Y473000D01*
X283117Y473250D01*
X283783Y473333D01*
X284283Y473250D01*
X284867Y472917D01*
X285117Y472417D01*
Y470000D01*
G01X288050Y472250D02*
X290717D01*
X290467Y472833D01*
X290050Y473167D01*
X289467Y473333D01*
X288883Y473250D01*
X288383Y473000D01*
X288050Y472417D01*
X287883Y471917D01*
Y471417D01*
X288050Y470917D01*
X288467Y470417D01*
X288967Y470083D01*
X289550Y470000D01*
X290133Y470167D01*
X290717Y470667D01*
G01X293733Y470000D02*
Y473333D01*
G01Y472667D02*
X294150Y473000D01*
X294567Y473250D01*
X295150Y473333D01*
X295567Y473250D01*
X296067Y473000D01*
G01X299250Y470583D02*
X299667Y470250D01*
X300250Y470000D01*
X300750D01*
X301250Y470167D01*
X301583Y470417D01*
X301750Y470750D01*
X301667Y471250D01*
X301333Y471500D01*
X299833Y472000D01*
X299500Y472583D01*
X299667Y473000D01*
X300000Y473250D01*
X300500Y473333D01*
X301000Y473250D01*
X301500Y473000D01*
G01X311283Y468333D02*
X310450Y469167D01*
X310033Y470000D01*
Y473333D01*
X310450Y474167D01*
X311283Y475000D01*
G01X317300Y470000D02*
Y475000D01*
G01X322900Y473333D02*
Y470000D01*
G01Y474667D02*
X322733Y474750D01*
Y474917D01*
X322900Y475000D01*
X323067Y474917D01*
Y474750D01*
X322900Y474667D01*
G01X327083Y470000D02*
Y475000D01*
G01X329750Y473333D02*
X327083Y471417D01*
G01X328167Y472167D02*
X329917Y470000D01*
G01X332850Y472250D02*
X335517D01*
X335267Y472833D01*
X334850Y473167D01*
X334267Y473333D01*
X333683Y473250D01*
X333183Y473000D01*
X332850Y472417D01*
X332683Y471917D01*
Y471417D01*
X332850Y470917D01*
X333267Y470417D01*
X333767Y470083D01*
X334350Y470000D01*
X334933Y470167D01*
X335517Y470667D01*
G01X344050Y472250D02*
X346717D01*
X346467Y472833D01*
X346050Y473167D01*
X345467Y473333D01*
X344883Y473250D01*
X344383Y473000D01*
X344050Y472417D01*
X343883Y471917D01*
Y471417D01*
X344050Y470917D01*
X344467Y470417D01*
X344967Y470083D01*
X345550Y470000D01*
X346133Y470167D01*
X346717Y470667D01*
G01X350900Y470000D02*
Y475000D01*
G01X356500Y470000D02*
Y475000D01*
G01X362100Y473333D02*
Y470000D01*
G01Y474667D02*
X361933Y474750D01*
Y474917D01*
X362100Y475000D01*
X362267Y474917D01*
Y474750D01*
X362100Y474667D01*
G01X366200Y468333D02*
Y473333D01*
G01Y472583D02*
X366617Y473000D01*
X367033Y473250D01*
X367700Y473333D01*
X368283Y473250D01*
X368867Y472833D01*
X369117Y472250D01*
X369200Y471667D01*
X369117Y471083D01*
X368867Y470500D01*
X368367Y470167D01*
X367700Y470000D01*
X367117Y470083D01*
X366533Y470333D01*
X366200Y470667D01*
G01X372050Y470583D02*
X372467Y470250D01*
X373050Y470000D01*
X373550D01*
X374050Y470167D01*
X374383Y470417D01*
X374550Y470750D01*
X374467Y471250D01*
X374133Y471500D01*
X372633Y472000D01*
X372300Y472583D01*
X372467Y473000D01*
X372800Y473250D01*
X373300Y473333D01*
X373800Y473250D01*
X374300Y473000D01*
G01X377650Y472250D02*
X380317D01*
X380067Y472833D01*
X379650Y473167D01*
X379067Y473333D01*
X378483Y473250D01*
X377983Y473000D01*
X377650Y472417D01*
X377483Y471917D01*
Y471417D01*
X377650Y470917D01*
X378067Y470417D01*
X378567Y470083D01*
X379150Y470000D01*
X379733Y470167D01*
X380317Y470667D01*
G01X391600Y470000D02*
Y473333D01*
G01Y472750D02*
X391267Y473083D01*
X390767Y473250D01*
X390183Y473333D01*
X389600Y473167D01*
X389100Y472833D01*
X388767Y472333D01*
X388600Y471667D01*
X388767Y471000D01*
X389100Y470500D01*
X389600Y470167D01*
X390183Y470000D01*
X390767Y470083D01*
X391267Y470333D01*
X391600Y470667D01*
G01X394283Y470000D02*
Y473333D01*
G01Y472500D02*
X394617Y472917D01*
X395117Y473250D01*
X395783Y473333D01*
X396367Y473250D01*
X396867Y472917D01*
X397117Y472333D01*
Y470000D01*
G01X402800Y475000D02*
Y470000D01*
G01Y470750D02*
X402467Y470333D01*
X401967Y470083D01*
X401383Y470000D01*
X400717Y470167D01*
X400217Y470583D01*
X399883Y471083D01*
X399800Y471667D01*
X399883Y472250D01*
X400217Y472750D01*
X400717Y473167D01*
X401383Y473333D01*
X401967Y473250D01*
X402383Y473083D01*
X402800Y472750D01*
G01X412500Y470000D02*
X412000Y470083D01*
X411500Y470417D01*
X411167Y471000D01*
X411000Y471667D01*
X411167Y472333D01*
X411500Y472917D01*
X412000Y473250D01*
X412500Y473333D01*
X413000Y473250D01*
X413500Y472917D01*
X413833Y472333D01*
X413917Y471667D01*
X413833Y471000D01*
X413500Y470417D01*
X413000Y470083D01*
X412500Y470000D01*
G01X418100Y475000D02*
Y470000D01*
G01X416933Y473333D02*
X419267D01*
G01X422283Y470000D02*
Y475000D01*
G01Y472583D02*
X422700Y473000D01*
X423117Y473250D01*
X423783Y473333D01*
X424283Y473250D01*
X424867Y472917D01*
X425117Y472417D01*
Y470000D01*
G01X428050Y472250D02*
X430717D01*
X430467Y472833D01*
X430050Y473167D01*
X429467Y473333D01*
X428883Y473250D01*
X428383Y473000D01*
X428050Y472417D01*
X427883Y471917D01*
Y471417D01*
X428050Y470917D01*
X428467Y470417D01*
X428967Y470083D01*
X429550Y470000D01*
X430133Y470167D01*
X430717Y470667D01*
G01X433733Y470000D02*
Y473333D01*
G01Y472667D02*
X434150Y473000D01*
X434567Y473250D01*
X435150Y473333D01*
X435567Y473250D01*
X436067Y473000D01*
G01X439250Y470583D02*
X439667Y470250D01*
X440250Y470000D01*
X440750D01*
X441250Y470167D01*
X441583Y470417D01*
X441750Y470750D01*
X441667Y471250D01*
X441333Y471500D01*
X439833Y472000D01*
X439500Y472583D01*
X439667Y473000D01*
X440000Y473250D01*
X440500Y473333D01*
X441000Y473250D01*
X441500Y473000D01*
G01X446517Y468333D02*
X447350Y469167D01*
X447767Y470000D01*
Y473333D01*
X447350Y474167D01*
X446517Y475000D01*
G01X270833Y485000D02*
Y490000D01*
X272833D01*
X273500Y489750D01*
X274000Y489167D01*
X274167Y488500D01*
X274000Y487833D01*
X273583Y487333D01*
X272833Y487083D01*
X270833D01*
G01X278100Y490000D02*
Y485000D01*
G01X276183Y490000D02*
X280017D01*
G01X281950Y485000D02*
Y490000D01*
G01X285450D02*
Y485000D01*
G01Y487500D02*
X281950D01*
G01X287800Y484833D02*
X290800Y490000D01*
G01X292983Y485000D02*
Y490000D01*
X296817Y485000D01*
Y490000D01*
G01X298833Y485000D02*
Y490000D01*
X300833D01*
X301500Y489750D01*
X302000Y489167D01*
X302167Y488500D01*
X302000Y487833D01*
X301583Y487333D01*
X300833Y487083D01*
X298833D01*
G01X306100Y490000D02*
Y485000D01*
G01X304183Y490000D02*
X308017D01*
G01X309950Y485000D02*
Y490000D01*
G01X313450D02*
Y485000D01*
G01Y487500D02*
X309950D01*
G01X321233Y485000D02*
X324567Y486667D01*
X321233Y488333D01*
G01X327417Y485917D02*
X329583D01*
G01Y487417D02*
X327417D01*
G01X332267Y485750D02*
X332767Y485333D01*
X333350Y485083D01*
X334100Y485000D01*
X334850Y485167D01*
X335433Y485500D01*
X335850Y486083D01*
X335933Y486750D01*
X335767Y487417D01*
X335350Y487833D01*
X334767Y488167D01*
X334183Y488250D01*
X333600Y488167D01*
X332850Y487833D01*
X333100Y490000D01*
X335350D01*
G01X342800Y485000D02*
Y488333D01*
G01Y487417D02*
X343050Y487833D01*
X343467Y488167D01*
X344050Y488333D01*
X344633Y488167D01*
X345050Y487833D01*
X345300Y487417D01*
Y485000D01*
G01Y487417D02*
X345550Y487833D01*
X345967Y488167D01*
X346550Y488333D01*
X347133Y488167D01*
X347550Y487833D01*
X347800Y487333D01*
Y485000D01*
G01X348400D02*
Y488333D01*
G01Y487417D02*
X348650Y487833D01*
X349067Y488167D01*
X349650Y488333D01*
X350233Y488167D01*
X350650Y487833D01*
X350900Y487417D01*
Y485000D01*
G01Y487417D02*
X351150Y487833D01*
X351567Y488167D01*
X352150Y488333D01*
X352733Y488167D01*
X353150Y487833D01*
X353400Y487333D01*
Y485000D01*
G01X270583Y498500D02*
Y503500D01*
X274417Y498500D01*
Y503500D01*
G01X276433Y498500D02*
Y503500D01*
X278433D01*
X279100Y503250D01*
X279600Y502667D01*
X279767Y502000D01*
X279600Y501333D01*
X279183Y500833D01*
X278433Y500583D01*
X276433D01*
G01X283700Y503500D02*
Y498500D01*
G01X281783Y503500D02*
X285617D01*
G01X287550Y498500D02*
Y503500D01*
G01X291050D02*
Y498500D01*
G01Y501000D02*
X287550D01*
G01X298750Y499167D02*
X299417Y498750D01*
X300167Y498500D01*
X300833D01*
X301500Y498750D01*
X302000Y499167D01*
X302250Y499750D01*
X302083Y500333D01*
X301667Y500833D01*
X300917Y501167D01*
X299917Y501333D01*
X299333Y501667D01*
X299083Y502250D01*
X299250Y502833D01*
X299667Y503250D01*
X300250Y503500D01*
X300833D01*
X301417Y503333D01*
X301917Y502917D01*
G01X306100Y501833D02*
Y498500D01*
G01Y503167D02*
X305933Y503250D01*
Y503417D01*
X306100Y503500D01*
X306267Y503417D01*
Y503250D01*
X306100Y503167D01*
G01X310450Y501833D02*
X312950D01*
X310450Y498500D01*
X312950D01*
G01X316050Y500750D02*
X318717D01*
X318467Y501333D01*
X318050Y501667D01*
X317467Y501833D01*
X316883Y501750D01*
X316383Y501500D01*
X316050Y500917D01*
X315883Y500417D01*
Y499917D01*
X316050Y499417D01*
X316467Y498917D01*
X316967Y498583D01*
X317550Y498500D01*
X318133Y498667D01*
X318717Y499167D01*
G01X326667Y499500D02*
X327167Y498917D01*
X327833Y498583D01*
X328583Y498500D01*
X329250Y498583D01*
X329917Y499000D01*
X330333Y499500D01*
X330417Y500000D01*
X330250Y500583D01*
X329667Y501000D01*
X329083Y501167D01*
X328333D01*
G01X329083D02*
X329583Y501417D01*
X330000Y501833D01*
X330167Y502333D01*
X330000Y502833D01*
X329583Y503250D01*
X328833Y503500D01*
X328083Y503417D01*
X327333Y503083D01*
G01X334100Y498333D02*
X333933Y498417D01*
Y498583D01*
X334100Y498667D01*
X334267Y498583D01*
Y498417D01*
X334100Y498333D01*
G01X337867Y499250D02*
X338367Y498833D01*
X338950Y498583D01*
X339700Y498500D01*
X340450Y498667D01*
X341033Y499000D01*
X341450Y499583D01*
X341533Y500250D01*
X341367Y500917D01*
X340950Y501333D01*
X340367Y501667D01*
X339783Y501750D01*
X339200Y501667D01*
X338450Y501333D01*
X338700Y503500D01*
X340950D01*
G01X343467Y499250D02*
X343967Y498833D01*
X344550Y498583D01*
X345300Y498500D01*
X346050Y498667D01*
X346633Y499000D01*
X347050Y499583D01*
X347133Y500250D01*
X346967Y500917D01*
X346550Y501333D01*
X345967Y501667D01*
X345383Y501750D01*
X344800Y501667D01*
X344050Y501333D01*
X344300Y503500D01*
X346550D01*
G01X348400Y498500D02*
Y501833D01*
G01Y500917D02*
X348650Y501333D01*
X349067Y501667D01*
X349650Y501833D01*
X350233Y501667D01*
X350650Y501333D01*
X350900Y500917D01*
Y498500D01*
G01Y500917D02*
X351150Y501333D01*
X351567Y501667D01*
X352150Y501833D01*
X352733Y501667D01*
X353150Y501333D01*
X353400Y500833D01*
Y498500D01*
G01X354000D02*
Y501833D01*
G01Y500917D02*
X354250Y501333D01*
X354667Y501667D01*
X355250Y501833D01*
X355833Y501667D01*
X356250Y501333D01*
X356500Y500917D01*
Y498500D01*
G01Y500917D02*
X356750Y501333D01*
X357167Y501667D01*
X357750Y501833D01*
X358333Y501667D01*
X358750Y501333D01*
X359000Y500833D01*
Y498500D01*
G01X262500Y479000D02*
X694500D01*
G01X262500Y494000D02*
X694500D01*
G01X270583Y513500D02*
Y518500D01*
X274417Y513500D01*
Y518500D01*
G01X276433Y513500D02*
Y518500D01*
X278433D01*
X279100Y518250D01*
X279600Y517667D01*
X279767Y517000D01*
X279600Y516333D01*
X279183Y515833D01*
X278433Y515583D01*
X276433D01*
G01X283700Y518500D02*
Y513500D01*
G01X281783Y518500D02*
X285617D01*
G01X287550Y513500D02*
Y518500D01*
G01X291050D02*
Y513500D01*
G01Y516000D02*
X287550D01*
G01X298750Y514167D02*
X299417Y513750D01*
X300167Y513500D01*
X300833D01*
X301500Y513750D01*
X302000Y514167D01*
X302250Y514750D01*
X302083Y515333D01*
X301667Y515833D01*
X300917Y516167D01*
X299917Y516333D01*
X299333Y516667D01*
X299083Y517250D01*
X299250Y517833D01*
X299667Y518250D01*
X300250Y518500D01*
X300833D01*
X301417Y518333D01*
X301917Y517917D01*
G01X306100Y516833D02*
Y513500D01*
G01Y518167D02*
X305933Y518250D01*
Y518417D01*
X306100Y518500D01*
X306267Y518417D01*
Y518250D01*
X306100Y518167D01*
G01X310450Y516833D02*
X312950D01*
X310450Y513500D01*
X312950D01*
G01X316050Y515750D02*
X318717D01*
X318467Y516333D01*
X318050Y516667D01*
X317467Y516833D01*
X316883Y516750D01*
X316383Y516500D01*
X316050Y515917D01*
X315883Y515417D01*
Y514917D01*
X316050Y514417D01*
X316467Y513917D01*
X316967Y513583D01*
X317550Y513500D01*
X318133Y513667D01*
X318717Y514167D01*
G01X324567Y513500D02*
X321233Y515167D01*
X324567Y516833D01*
G01X332267Y514250D02*
X332767Y513833D01*
X333350Y513583D01*
X334100Y513500D01*
X334850Y513667D01*
X335433Y514000D01*
X335850Y514583D01*
X335933Y515250D01*
X335767Y515917D01*
X335350Y516333D01*
X334767Y516667D01*
X334183Y516750D01*
X333600Y516667D01*
X332850Y516333D01*
X333100Y518500D01*
X335350D01*
G01X337200Y513500D02*
Y516833D01*
G01Y515917D02*
X337450Y516333D01*
X337867Y516667D01*
X338450Y516833D01*
X339033Y516667D01*
X339450Y516333D01*
X339700Y515917D01*
Y513500D01*
G01Y515917D02*
X339950Y516333D01*
X340367Y516667D01*
X340950Y516833D01*
X341533Y516667D01*
X341950Y516333D01*
X342200Y515833D01*
Y513500D01*
G01X342800D02*
Y516833D01*
G01Y515917D02*
X343050Y516333D01*
X343467Y516667D01*
X344050Y516833D01*
X344633Y516667D01*
X345050Y516333D01*
X345300Y515917D01*
Y513500D01*
G01Y515917D02*
X345550Y516333D01*
X345967Y516667D01*
X346550Y516833D01*
X347133Y516667D01*
X347550Y516333D01*
X347800Y515833D01*
Y513500D01*
G01X270667Y535000D02*
Y531417D01*
X271000Y530667D01*
X271667Y530167D01*
X272500Y530000D01*
X273333Y530167D01*
X274000Y530667D01*
X274333Y531417D01*
Y535000D01*
G01X276683Y530000D02*
Y533333D01*
G01Y532500D02*
X277017Y532917D01*
X277517Y533250D01*
X278183Y533333D01*
X278767Y533250D01*
X279267Y532917D01*
X279517Y532333D01*
Y530000D01*
G01X282617Y531667D02*
X284783D01*
G01X287800Y528333D02*
Y533333D01*
G01Y532583D02*
X288217Y533000D01*
X288633Y533250D01*
X289300Y533333D01*
X289883Y533250D01*
X290467Y532833D01*
X290717Y532250D01*
X290800Y531667D01*
X290717Y531083D01*
X290467Y530500D01*
X289967Y530167D01*
X289300Y530000D01*
X288717Y530083D01*
X288133Y530333D01*
X287800Y530667D01*
G01X294900Y530000D02*
Y535000D01*
G01X299083Y533333D02*
Y531000D01*
X299417Y530417D01*
X299917Y530083D01*
X300500Y530000D01*
X301083Y530083D01*
X301583Y530417D01*
X301917Y531000D01*
G01Y530000D02*
Y533333D01*
G01X304933Y528750D02*
X305517Y528417D01*
X306183Y528333D01*
X306767Y528417D01*
X307267Y528833D01*
X307600Y529417D01*
Y533333D01*
G01Y532667D02*
X307267Y533000D01*
X306767Y533250D01*
X306183Y533333D01*
X305517Y533167D01*
X305100Y532833D01*
X304767Y532250D01*
X304600Y531667D01*
X304683Y531167D01*
X305017Y530583D01*
X305517Y530167D01*
X306183Y530000D01*
X306683Y530083D01*
X307267Y530417D01*
X307600Y530750D01*
G01X310533Y528750D02*
X311117Y528417D01*
X311783Y528333D01*
X312367Y528417D01*
X312867Y528833D01*
X313200Y529417D01*
Y533333D01*
G01Y532667D02*
X312867Y533000D01*
X312367Y533250D01*
X311783Y533333D01*
X311117Y533167D01*
X310700Y532833D01*
X310367Y532250D01*
X310200Y531667D01*
X310283Y531167D01*
X310617Y530583D01*
X311117Y530167D01*
X311783Y530000D01*
X312283Y530083D01*
X312867Y530417D01*
X313200Y530750D01*
G01X316050Y532250D02*
X318717D01*
X318467Y532833D01*
X318050Y533167D01*
X317467Y533333D01*
X316883Y533250D01*
X316383Y533000D01*
X316050Y532417D01*
X315883Y531917D01*
Y531417D01*
X316050Y530917D01*
X316467Y530417D01*
X316967Y530083D01*
X317550Y530000D01*
X318133Y530167D01*
X318717Y530667D01*
G01X324400Y535000D02*
Y530000D01*
G01Y530750D02*
X324067Y530333D01*
X323567Y530083D01*
X322983Y530000D01*
X322317Y530167D01*
X321817Y530583D01*
X321483Y531083D01*
X321400Y531667D01*
X321483Y532250D01*
X321817Y532750D01*
X322317Y533167D01*
X322983Y533333D01*
X323567Y533250D01*
X323983Y533083D01*
X324400Y532750D01*
G01X332433Y530000D02*
Y535000D01*
X334433D01*
X335100Y534750D01*
X335600Y534167D01*
X335767Y533500D01*
X335600Y532833D01*
X335183Y532333D01*
X334433Y532083D01*
X332433D01*
G01X339700Y535000D02*
Y530000D01*
G01X337783Y535000D02*
X341617D01*
G01X343550Y530000D02*
Y535000D01*
G01X347050D02*
Y530000D01*
G01Y532500D02*
X343550D01*
G01X356083Y528333D02*
X355250Y529167D01*
X354833Y530000D01*
Y533333D01*
X355250Y534167D01*
X356083Y535000D01*
G01X360350Y530000D02*
Y535000D01*
G01X363850D02*
Y530000D01*
G01Y532500D02*
X360350D01*
G01X367700Y530000D02*
X367200Y530083D01*
X366700Y530417D01*
X366367Y531000D01*
X366200Y531667D01*
X366367Y532333D01*
X366700Y532917D01*
X367200Y533250D01*
X367700Y533333D01*
X368200Y533250D01*
X368700Y532917D01*
X369033Y532333D01*
X369117Y531667D01*
X369033Y531000D01*
X368700Y530417D01*
X368200Y530083D01*
X367700Y530000D01*
G01X373300D02*
Y535000D01*
G01X377650Y532250D02*
X380317D01*
X380067Y532833D01*
X379650Y533167D01*
X379067Y533333D01*
X378483Y533250D01*
X377983Y533000D01*
X377650Y532417D01*
X377483Y531917D01*
Y531417D01*
X377650Y530917D01*
X378067Y530417D01*
X378567Y530083D01*
X379150Y530000D01*
X379733Y530167D01*
X380317Y530667D01*
G01X388350D02*
X389017Y530250D01*
X389767Y530000D01*
X390433D01*
X391100Y530250D01*
X391600Y530667D01*
X391850Y531250D01*
X391683Y531833D01*
X391267Y532333D01*
X390517Y532667D01*
X389517Y532833D01*
X388933Y533167D01*
X388683Y533750D01*
X388850Y534333D01*
X389267Y534750D01*
X389850Y535000D01*
X390433D01*
X391017Y534833D01*
X391517Y534417D01*
G01X395700Y533333D02*
Y530000D01*
G01Y534667D02*
X395533Y534750D01*
Y534917D01*
X395700Y535000D01*
X395867Y534917D01*
Y534750D01*
X395700Y534667D01*
G01X400050Y533333D02*
X402550D01*
X400050Y530000D01*
X402550D01*
G01X405650Y532250D02*
X408317D01*
X408067Y532833D01*
X407650Y533167D01*
X407067Y533333D01*
X406483Y533250D01*
X405983Y533000D01*
X405650Y532417D01*
X405483Y531917D01*
Y531417D01*
X405650Y530917D01*
X406067Y530417D01*
X406567Y530083D01*
X407150Y530000D01*
X407733Y530167D01*
X408317Y530667D01*
G01X414167Y530000D02*
X410833Y531667D01*
X414167Y533333D01*
G01X418100Y530000D02*
Y535000D01*
X417100Y534000D01*
G01Y530000D02*
X419100D01*
G01X422283Y530583D02*
X422867Y530167D01*
X423533Y530000D01*
X424200Y530167D01*
X424783Y530667D01*
X425200Y531417D01*
X425367Y532167D01*
Y533083D01*
X425200Y533833D01*
X424783Y534500D01*
X424283Y534833D01*
X423700Y535000D01*
X423033Y534833D01*
X422533Y534500D01*
X422200Y534000D01*
X422033Y533333D01*
X422200Y532750D01*
X422617Y532167D01*
X423117Y531833D01*
X423700Y531750D01*
X424367Y531917D01*
X424867Y532333D01*
X425367Y533083D01*
G01X429133Y530000D02*
X429300Y531083D01*
X429550Y532000D01*
X429883Y532833D01*
X430300Y533750D01*
X430967Y535000D01*
X427633D01*
G01X432400Y530000D02*
Y533333D01*
G01Y532417D02*
X432650Y532833D01*
X433067Y533167D01*
X433650Y533333D01*
X434233Y533167D01*
X434650Y532833D01*
X434900Y532417D01*
Y530000D01*
G01Y532417D02*
X435150Y532833D01*
X435567Y533167D01*
X436150Y533333D01*
X436733Y533167D01*
X437150Y532833D01*
X437400Y532333D01*
Y530000D01*
G01X440500Y533333D02*
Y530000D01*
G01Y534667D02*
X440333Y534750D01*
Y534917D01*
X440500Y535000D01*
X440667Y534917D01*
Y534750D01*
X440500Y534667D01*
G01X446100Y530000D02*
Y535000D01*
G01X455217Y533333D02*
X456217Y530000D01*
X457300Y533333D01*
X458383Y530000D01*
X459383Y533333D01*
G01X462900D02*
Y530000D01*
G01Y534667D02*
X462733Y534750D01*
Y534917D01*
X462900Y535000D01*
X463067Y534917D01*
Y534750D01*
X462900Y534667D01*
G01X468500Y535000D02*
Y530000D01*
G01X467333Y533333D02*
X469667D01*
G01X472683Y530000D02*
Y535000D01*
G01Y532583D02*
X473100Y533000D01*
X473517Y533250D01*
X474183Y533333D01*
X474683Y533250D01*
X475267Y532917D01*
X475517Y532417D01*
Y530000D01*
G01X483550D02*
Y535000D01*
G01X487050D02*
Y530000D01*
G01Y532500D02*
X483550D01*
G01X488817Y530000D02*
X490900Y535000D01*
X492983Y530000D01*
G01X492233Y531750D02*
X489567D01*
G01X494750Y530667D02*
X495417Y530250D01*
X496167Y530000D01*
X496833D01*
X497500Y530250D01*
X498000Y530667D01*
X498250Y531250D01*
X498083Y531833D01*
X497667Y532333D01*
X496917Y532667D01*
X495917Y532833D01*
X495333Y533167D01*
X495083Y533750D01*
X495250Y534333D01*
X495667Y534750D01*
X496250Y535000D01*
X496833D01*
X497417Y534833D01*
X497917Y534417D01*
G01X500433Y535000D02*
Y530000D01*
X503767D01*
G01X511800Y528333D02*
Y533333D01*
G01Y532583D02*
X512217Y533000D01*
X512633Y533250D01*
X513300Y533333D01*
X513883Y533250D01*
X514467Y532833D01*
X514717Y532250D01*
X514800Y531667D01*
X514717Y531083D01*
X514467Y530500D01*
X513967Y530167D01*
X513300Y530000D01*
X512717Y530083D01*
X512133Y530333D01*
X511800Y530667D01*
G01X517733Y530000D02*
Y533333D01*
G01Y532667D02*
X518150Y533000D01*
X518567Y533250D01*
X519150Y533333D01*
X519567Y533250D01*
X520067Y533000D01*
G01X524500Y530000D02*
X524000Y530083D01*
X523500Y530417D01*
X523167Y531000D01*
X523000Y531667D01*
X523167Y532333D01*
X523500Y532917D01*
X524000Y533250D01*
X524500Y533333D01*
X525000Y533250D01*
X525500Y532917D01*
X525833Y532333D01*
X525917Y531667D01*
X525833Y531000D01*
X525500Y530417D01*
X525000Y530083D01*
X524500Y530000D01*
G01X531600Y535000D02*
Y530000D01*
G01Y530750D02*
X531267Y530333D01*
X530767Y530083D01*
X530183Y530000D01*
X529517Y530167D01*
X529017Y530583D01*
X528683Y531083D01*
X528600Y531667D01*
X528683Y532250D01*
X529017Y532750D01*
X529517Y533167D01*
X530183Y533333D01*
X530767Y533250D01*
X531183Y533083D01*
X531600Y532750D01*
G01X534283Y533333D02*
Y531000D01*
X534617Y530417D01*
X535117Y530083D01*
X535700Y530000D01*
X536283Y530083D01*
X536783Y530417D01*
X537117Y531000D01*
G01Y530000D02*
Y533333D01*
G01X542633Y532917D02*
X542050Y533250D01*
X541550Y533333D01*
X540883Y533167D01*
X540383Y532833D01*
X540050Y532250D01*
X539967Y531667D01*
X540050Y531083D01*
X540383Y530583D01*
X540883Y530167D01*
X541550Y530000D01*
X542133Y530167D01*
X542633Y530500D01*
G01X546900Y535000D02*
Y530000D01*
G01X545733Y533333D02*
X548067D01*
G01X551250Y530583D02*
X551667Y530250D01*
X552250Y530000D01*
X552750D01*
X553250Y530167D01*
X553583Y530417D01*
X553750Y530750D01*
X553667Y531250D01*
X553333Y531500D01*
X551833Y532000D01*
X551500Y532583D01*
X551667Y533000D01*
X552000Y533250D01*
X552500Y533333D01*
X553000Y533250D01*
X553500Y533000D01*
G01X558517Y528333D02*
X559350Y529167D01*
X559767Y530000D01*
Y533333D01*
X559350Y534167D01*
X558517Y535000D01*
G01X270667Y550000D02*
Y546417D01*
X271000Y545667D01*
X271667Y545167D01*
X272500Y545000D01*
X273333Y545167D01*
X274000Y545667D01*
X274333Y546417D01*
Y550000D01*
G01X276683Y545000D02*
Y548333D01*
G01Y547500D02*
X277017Y547917D01*
X277517Y548250D01*
X278183Y548333D01*
X278767Y548250D01*
X279267Y547917D01*
X279517Y547333D01*
Y545000D01*
G01X282617Y546667D02*
X284783D01*
G01X287800Y543333D02*
Y548333D01*
G01Y547583D02*
X288217Y548000D01*
X288633Y548250D01*
X289300Y548333D01*
X289883Y548250D01*
X290467Y547833D01*
X290717Y547250D01*
X290800Y546667D01*
X290717Y546083D01*
X290467Y545500D01*
X289967Y545167D01*
X289300Y545000D01*
X288717Y545083D01*
X288133Y545333D01*
X287800Y545667D01*
G01X294900Y545000D02*
Y550000D01*
G01X299083Y548333D02*
Y546000D01*
X299417Y545417D01*
X299917Y545083D01*
X300500Y545000D01*
X301083Y545083D01*
X301583Y545417D01*
X301917Y546000D01*
G01Y545000D02*
Y548333D01*
G01X304933Y543750D02*
X305517Y543417D01*
X306183Y543333D01*
X306767Y543417D01*
X307267Y543833D01*
X307600Y544417D01*
Y548333D01*
G01Y547667D02*
X307267Y548000D01*
X306767Y548250D01*
X306183Y548333D01*
X305517Y548167D01*
X305100Y547833D01*
X304767Y547250D01*
X304600Y546667D01*
X304683Y546167D01*
X305017Y545583D01*
X305517Y545167D01*
X306183Y545000D01*
X306683Y545083D01*
X307267Y545417D01*
X307600Y545750D01*
G01X310533Y543750D02*
X311117Y543417D01*
X311783Y543333D01*
X312367Y543417D01*
X312867Y543833D01*
X313200Y544417D01*
Y548333D01*
G01Y547667D02*
X312867Y548000D01*
X312367Y548250D01*
X311783Y548333D01*
X311117Y548167D01*
X310700Y547833D01*
X310367Y547250D01*
X310200Y546667D01*
X310283Y546167D01*
X310617Y545583D01*
X311117Y545167D01*
X311783Y545000D01*
X312283Y545083D01*
X312867Y545417D01*
X313200Y545750D01*
G01X316050Y547250D02*
X318717D01*
X318467Y547833D01*
X318050Y548167D01*
X317467Y548333D01*
X316883Y548250D01*
X316383Y548000D01*
X316050Y547417D01*
X315883Y546917D01*
Y546417D01*
X316050Y545917D01*
X316467Y545417D01*
X316967Y545083D01*
X317550Y545000D01*
X318133Y545167D01*
X318717Y545667D01*
G01X324400Y550000D02*
Y545000D01*
G01Y545750D02*
X324067Y545333D01*
X323567Y545083D01*
X322983Y545000D01*
X322317Y545167D01*
X321817Y545583D01*
X321483Y546083D01*
X321400Y546667D01*
X321483Y547250D01*
X321817Y547750D01*
X322317Y548167D01*
X322983Y548333D01*
X323567Y548250D01*
X323983Y548083D01*
X324400Y547750D01*
G01X332433Y545000D02*
Y550000D01*
X334433D01*
X335100Y549750D01*
X335600Y549167D01*
X335767Y548500D01*
X335600Y547833D01*
X335183Y547333D01*
X334433Y547083D01*
X332433D01*
G01X339700Y550000D02*
Y545000D01*
G01X337783Y550000D02*
X341617D01*
G01X343550Y545000D02*
Y550000D01*
G01X347050D02*
Y545000D01*
G01Y547500D02*
X343550D01*
G01X356083Y543333D02*
X355250Y544167D01*
X354833Y545000D01*
Y548333D01*
X355250Y549167D01*
X356083Y550000D01*
G01X360350Y545000D02*
Y550000D01*
G01X363850D02*
Y545000D01*
G01Y547500D02*
X360350D01*
G01X367700Y545000D02*
X367200Y545083D01*
X366700Y545417D01*
X366367Y546000D01*
X366200Y546667D01*
X366367Y547333D01*
X366700Y547917D01*
X367200Y548250D01*
X367700Y548333D01*
X368200Y548250D01*
X368700Y547917D01*
X369033Y547333D01*
X369117Y546667D01*
X369033Y546000D01*
X368700Y545417D01*
X368200Y545083D01*
X367700Y545000D01*
G01X373300D02*
Y550000D01*
G01X377650Y547250D02*
X380317D01*
X380067Y547833D01*
X379650Y548167D01*
X379067Y548333D01*
X378483Y548250D01*
X377983Y548000D01*
X377650Y547417D01*
X377483Y546917D01*
Y546417D01*
X377650Y545917D01*
X378067Y545417D01*
X378567Y545083D01*
X379150Y545000D01*
X379733Y545167D01*
X380317Y545667D01*
G01X388350D02*
X389017Y545250D01*
X389767Y545000D01*
X390433D01*
X391100Y545250D01*
X391600Y545667D01*
X391850Y546250D01*
X391683Y546833D01*
X391267Y547333D01*
X390517Y547667D01*
X389517Y547833D01*
X388933Y548167D01*
X388683Y548750D01*
X388850Y549333D01*
X389267Y549750D01*
X389850Y550000D01*
X390433D01*
X391017Y549833D01*
X391517Y549417D01*
G01X395700Y548333D02*
Y545000D01*
G01Y549667D02*
X395533Y549750D01*
Y549917D01*
X395700Y550000D01*
X395867Y549917D01*
Y549750D01*
X395700Y549667D01*
G01X400050Y548333D02*
X402550D01*
X400050Y545000D01*
X402550D01*
G01X405650Y547250D02*
X408317D01*
X408067Y547833D01*
X407650Y548167D01*
X407067Y548333D01*
X406483Y548250D01*
X405983Y548000D01*
X405650Y547417D01*
X405483Y546917D01*
Y546417D01*
X405650Y545917D01*
X406067Y545417D01*
X406567Y545083D01*
X407150Y545000D01*
X407733Y545167D01*
X408317Y545667D01*
G01X414167Y545000D02*
X410833Y546667D01*
X414167Y548333D01*
G01X418100Y545000D02*
Y550000D01*
X417100Y549000D01*
G01Y545000D02*
X419100D01*
G01X422283Y545583D02*
X422867Y545167D01*
X423533Y545000D01*
X424200Y545167D01*
X424783Y545667D01*
X425200Y546417D01*
X425367Y547167D01*
Y548083D01*
X425200Y548833D01*
X424783Y549500D01*
X424283Y549833D01*
X423700Y550000D01*
X423033Y549833D01*
X422533Y549500D01*
X422200Y549000D01*
X422033Y548333D01*
X422200Y547750D01*
X422617Y547167D01*
X423117Y546833D01*
X423700Y546750D01*
X424367Y546917D01*
X424867Y547333D01*
X425367Y548083D01*
G01X429133Y545000D02*
X429300Y546083D01*
X429550Y547000D01*
X429883Y547833D01*
X430300Y548750D01*
X430967Y550000D01*
X427633D01*
G01X432400Y545000D02*
Y548333D01*
G01Y547417D02*
X432650Y547833D01*
X433067Y548167D01*
X433650Y548333D01*
X434233Y548167D01*
X434650Y547833D01*
X434900Y547417D01*
Y545000D01*
G01Y547417D02*
X435150Y547833D01*
X435567Y548167D01*
X436150Y548333D01*
X436733Y548167D01*
X437150Y547833D01*
X437400Y547333D01*
Y545000D01*
G01X440500Y548333D02*
Y545000D01*
G01Y549667D02*
X440333Y549750D01*
Y549917D01*
X440500Y550000D01*
X440667Y549917D01*
Y549750D01*
X440500Y549667D01*
G01X446100Y545000D02*
Y550000D01*
G01X455217Y548333D02*
X456217Y545000D01*
X457300Y548333D01*
X458383Y545000D01*
X459383Y548333D01*
G01X462900D02*
Y545000D01*
G01Y549667D02*
X462733Y549750D01*
Y549917D01*
X462900Y550000D01*
X463067Y549917D01*
Y549750D01*
X462900Y549667D01*
G01X468500Y550000D02*
Y545000D01*
G01X467333Y548333D02*
X469667D01*
G01X472683Y545000D02*
Y550000D01*
G01Y547583D02*
X473100Y548000D01*
X473517Y548250D01*
X474183Y548333D01*
X474683Y548250D01*
X475267Y547917D01*
X475517Y547417D01*
Y545000D01*
G01X483883D02*
Y548333D01*
G01Y547500D02*
X484217Y547917D01*
X484717Y548250D01*
X485383Y548333D01*
X485967Y548250D01*
X486467Y547917D01*
X486717Y547333D01*
Y545000D01*
G01X490900D02*
X490400Y545083D01*
X489900Y545417D01*
X489567Y546000D01*
X489400Y546667D01*
X489567Y547333D01*
X489900Y547917D01*
X490400Y548250D01*
X490900Y548333D01*
X491400Y548250D01*
X491900Y547917D01*
X492233Y547333D01*
X492317Y546667D01*
X492233Y546000D01*
X491900Y545417D01*
X491400Y545083D01*
X490900Y545000D01*
G01X495083D02*
Y548333D01*
G01Y547500D02*
X495417Y547917D01*
X495917Y548250D01*
X496583Y548333D01*
X497167Y548250D01*
X497667Y547917D01*
X497917Y547333D01*
Y545000D01*
G01X501017Y546667D02*
X503183D01*
G01X505950Y545000D02*
Y550000D01*
G01X509450D02*
Y545000D01*
G01Y547500D02*
X505950D01*
G01X511217Y545000D02*
X513300Y550000D01*
X515383Y545000D01*
G01X514633Y546750D02*
X511967D01*
G01X517150Y545667D02*
X517817Y545250D01*
X518567Y545000D01*
X519233D01*
X519900Y545250D01*
X520400Y545667D01*
X520650Y546250D01*
X520483Y546833D01*
X520067Y547333D01*
X519317Y547667D01*
X518317Y547833D01*
X517733Y548167D01*
X517483Y548750D01*
X517650Y549333D01*
X518067Y549750D01*
X518650Y550000D01*
X519233D01*
X519817Y549833D01*
X520317Y549417D01*
G01X522833Y550000D02*
Y545000D01*
X526167D01*
G01X534200Y543333D02*
Y548333D01*
G01Y547583D02*
X534617Y548000D01*
X535033Y548250D01*
X535700Y548333D01*
X536283Y548250D01*
X536867Y547833D01*
X537117Y547250D01*
X537200Y546667D01*
X537117Y546083D01*
X536867Y545500D01*
X536367Y545167D01*
X535700Y545000D01*
X535117Y545083D01*
X534533Y545333D01*
X534200Y545667D01*
G01X540133Y545000D02*
Y548333D01*
G01Y547667D02*
X540550Y548000D01*
X540967Y548250D01*
X541550Y548333D01*
X541967Y548250D01*
X542467Y548000D01*
G01X546900Y545000D02*
X546400Y545083D01*
X545900Y545417D01*
X545567Y546000D01*
X545400Y546667D01*
X545567Y547333D01*
X545900Y547917D01*
X546400Y548250D01*
X546900Y548333D01*
X547400Y548250D01*
X547900Y547917D01*
X548233Y547333D01*
X548317Y546667D01*
X548233Y546000D01*
X547900Y545417D01*
X547400Y545083D01*
X546900Y545000D01*
G01X554000Y550000D02*
Y545000D01*
G01Y545750D02*
X553667Y545333D01*
X553167Y545083D01*
X552583Y545000D01*
X551917Y545167D01*
X551417Y545583D01*
X551083Y546083D01*
X551000Y546667D01*
X551083Y547250D01*
X551417Y547750D01*
X551917Y548167D01*
X552583Y548333D01*
X553167Y548250D01*
X553583Y548083D01*
X554000Y547750D01*
G01X556683Y548333D02*
Y546000D01*
X557017Y545417D01*
X557517Y545083D01*
X558100Y545000D01*
X558683Y545083D01*
X559183Y545417D01*
X559517Y546000D01*
G01Y545000D02*
Y548333D01*
G01X565033Y547917D02*
X564450Y548250D01*
X563950Y548333D01*
X563283Y548167D01*
X562783Y547833D01*
X562450Y547250D01*
X562367Y546667D01*
X562450Y546083D01*
X562783Y545583D01*
X563283Y545167D01*
X563950Y545000D01*
X564533Y545167D01*
X565033Y545500D01*
G01X569300Y550000D02*
Y545000D01*
G01X568133Y548333D02*
X570467D01*
G01X573650Y545583D02*
X574067Y545250D01*
X574650Y545000D01*
X575150D01*
X575650Y545167D01*
X575983Y545417D01*
X576150Y545750D01*
X576067Y546250D01*
X575733Y546500D01*
X574233Y547000D01*
X573900Y547583D01*
X574067Y548000D01*
X574400Y548250D01*
X574900Y548333D01*
X575400Y548250D01*
X575900Y548000D01*
G01X580917Y543333D02*
X581750Y544167D01*
X582167Y545000D01*
Y548333D01*
X581750Y549167D01*
X580917Y550000D01*
G01X262500Y509000D02*
X694500D01*
G01X262500Y524000D02*
X694500D01*
G01X262500Y539000D02*
X694500D01*
G01X270417Y588500D02*
X272500Y593500D01*
X274583Y588500D01*
G01X273833Y590250D02*
X271167D01*
G01X276683Y588500D02*
Y591833D01*
G01Y591000D02*
X277017Y591417D01*
X277517Y591750D01*
X278183Y591833D01*
X278767Y591750D01*
X279267Y591417D01*
X279517Y590833D01*
Y588500D01*
G01X281950Y587000D02*
X282450Y586833D01*
X283117Y587000D01*
X283533Y587333D01*
X283867Y587750D01*
X284367Y589083D01*
X285450Y591833D01*
G01X282783D02*
X284367Y589083D01*
G01X293483Y588500D02*
Y593500D01*
G01Y591083D02*
X293900Y591500D01*
X294317Y591750D01*
X294983Y591833D01*
X295483Y591750D01*
X296067Y591417D01*
X296317Y590917D01*
Y588500D01*
G01X300500D02*
X300000Y588583D01*
X299500Y588917D01*
X299167Y589500D01*
X299000Y590167D01*
X299167Y590833D01*
X299500Y591417D01*
X300000Y591750D01*
X300500Y591833D01*
X301000Y591750D01*
X301500Y591417D01*
X301833Y590833D01*
X301917Y590167D01*
X301833Y589500D01*
X301500Y588917D01*
X301000Y588583D01*
X300500Y588500D01*
G01X306100D02*
Y593500D01*
G01X310450Y590750D02*
X313117D01*
X312867Y591333D01*
X312450Y591667D01*
X311867Y591833D01*
X311283Y591750D01*
X310783Y591500D01*
X310450Y590917D01*
X310283Y590417D01*
Y589917D01*
X310450Y589417D01*
X310867Y588917D01*
X311367Y588583D01*
X311950Y588500D01*
X312533Y588667D01*
X313117Y589167D01*
G01X322900Y593500D02*
Y588500D01*
G01X321733Y591833D02*
X324067D01*
G01X328500Y588500D02*
X328000Y588583D01*
X327500Y588917D01*
X327167Y589500D01*
X327000Y590167D01*
X327167Y590833D01*
X327500Y591417D01*
X328000Y591750D01*
X328500Y591833D01*
X329000Y591750D01*
X329500Y591417D01*
X329833Y590833D01*
X329917Y590167D01*
X329833Y589500D01*
X329500Y588917D01*
X329000Y588583D01*
X328500Y588500D01*
G01X338283D02*
Y593500D01*
G01Y591083D02*
X338700Y591500D01*
X339117Y591750D01*
X339783Y591833D01*
X340283Y591750D01*
X340867Y591417D01*
X341117Y590917D01*
Y588500D01*
G01X345300D02*
X344800Y588583D01*
X344300Y588917D01*
X343967Y589500D01*
X343800Y590167D01*
X343967Y590833D01*
X344300Y591417D01*
X344800Y591750D01*
X345300Y591833D01*
X345800Y591750D01*
X346300Y591417D01*
X346633Y590833D01*
X346717Y590167D01*
X346633Y589500D01*
X346300Y588917D01*
X345800Y588583D01*
X345300Y588500D01*
G01X350900D02*
Y593500D01*
G01X355250Y590750D02*
X357917D01*
X357667Y591333D01*
X357250Y591667D01*
X356667Y591833D01*
X356083Y591750D01*
X355583Y591500D01*
X355250Y590917D01*
X355083Y590417D01*
Y589917D01*
X355250Y589417D01*
X355667Y588917D01*
X356167Y588583D01*
X356750Y588500D01*
X357333Y588667D01*
X357917Y589167D01*
G01X270833Y575000D02*
Y580000D01*
X272833D01*
X273500Y579750D01*
X274000Y579167D01*
X274167Y578500D01*
X274000Y577833D01*
X273583Y577333D01*
X272833Y577083D01*
X270833D01*
G01X278100Y575000D02*
Y580000D01*
G01X282283Y578333D02*
Y576000D01*
X282617Y575417D01*
X283117Y575083D01*
X283700Y575000D01*
X284283Y575083D01*
X284783Y575417D01*
X285117Y576000D01*
G01Y575000D02*
Y578333D01*
G01X288133Y573750D02*
X288717Y573417D01*
X289383Y573333D01*
X289967Y573417D01*
X290467Y573833D01*
X290800Y574417D01*
Y578333D01*
G01Y577667D02*
X290467Y578000D01*
X289967Y578250D01*
X289383Y578333D01*
X288717Y578167D01*
X288300Y577833D01*
X287967Y577250D01*
X287800Y576667D01*
X287883Y576167D01*
X288217Y575583D01*
X288717Y575167D01*
X289383Y575000D01*
X289883Y575083D01*
X290467Y575417D01*
X290800Y575750D01*
G01X293733Y573750D02*
X294317Y573417D01*
X294983Y573333D01*
X295567Y573417D01*
X296067Y573833D01*
X296400Y574417D01*
Y578333D01*
G01Y577667D02*
X296067Y578000D01*
X295567Y578250D01*
X294983Y578333D01*
X294317Y578167D01*
X293900Y577833D01*
X293567Y577250D01*
X293400Y576667D01*
X293483Y576167D01*
X293817Y575583D01*
X294317Y575167D01*
X294983Y575000D01*
X295483Y575083D01*
X296067Y575417D01*
X296400Y575750D01*
G01X299250Y577250D02*
X301917D01*
X301667Y577833D01*
X301250Y578167D01*
X300667Y578333D01*
X300083Y578250D01*
X299583Y578000D01*
X299250Y577417D01*
X299083Y576917D01*
Y576417D01*
X299250Y575917D01*
X299667Y575417D01*
X300167Y575083D01*
X300750Y575000D01*
X301333Y575167D01*
X301917Y575667D01*
G01X307600Y580000D02*
Y575000D01*
G01Y575750D02*
X307267Y575333D01*
X306767Y575083D01*
X306183Y575000D01*
X305517Y575167D01*
X305017Y575583D01*
X304683Y576083D01*
X304600Y576667D01*
X304683Y577250D01*
X305017Y577750D01*
X305517Y578167D01*
X306183Y578333D01*
X306767Y578250D01*
X307183Y578083D01*
X307600Y577750D01*
G01X315217Y580000D02*
X317300Y575000D01*
X319383Y580000D01*
G01X322900Y578333D02*
Y575000D01*
G01Y579667D02*
X322733Y579750D01*
Y579917D01*
X322900Y580000D01*
X323067Y579917D01*
Y579750D01*
X322900Y579667D01*
G01X330000Y575000D02*
Y578333D01*
G01Y577750D02*
X329667Y578083D01*
X329167Y578250D01*
X328583Y578333D01*
X328000Y578167D01*
X327500Y577833D01*
X327167Y577333D01*
X327000Y576667D01*
X327167Y576000D01*
X327500Y575500D01*
X328000Y575167D01*
X328583Y575000D01*
X329167Y575083D01*
X329667Y575333D01*
X330000Y575667D01*
G01X333683Y573333D02*
X332850Y574167D01*
X332433Y575000D01*
Y578333D01*
X332850Y579167D01*
X333683Y580000D01*
G01X338283Y575000D02*
Y580000D01*
G01Y577583D02*
X338700Y578000D01*
X339117Y578250D01*
X339783Y578333D01*
X340283Y578250D01*
X340867Y577917D01*
X341117Y577417D01*
Y575000D01*
G01X345300D02*
X344800Y575083D01*
X344300Y575417D01*
X343967Y576000D01*
X343800Y576667D01*
X343967Y577333D01*
X344300Y577917D01*
X344800Y578250D01*
X345300Y578333D01*
X345800Y578250D01*
X346300Y577917D01*
X346633Y577333D01*
X346717Y576667D01*
X346633Y576000D01*
X346300Y575417D01*
X345800Y575083D01*
X345300Y575000D01*
G01X350900D02*
Y580000D01*
G01X355250Y577250D02*
X357917D01*
X357667Y577833D01*
X357250Y578167D01*
X356667Y578333D01*
X356083Y578250D01*
X355583Y578000D01*
X355250Y577417D01*
X355083Y576917D01*
Y576417D01*
X355250Y575917D01*
X355667Y575417D01*
X356167Y575083D01*
X356750Y575000D01*
X357333Y575167D01*
X357917Y575667D01*
G01X366450Y575583D02*
X366867Y575250D01*
X367450Y575000D01*
X367950D01*
X368450Y575167D01*
X368783Y575417D01*
X368950Y575750D01*
X368867Y576250D01*
X368533Y576500D01*
X367033Y577000D01*
X366700Y577583D01*
X366867Y578000D01*
X367200Y578250D01*
X367700Y578333D01*
X368200Y578250D01*
X368700Y578000D01*
G01X373300Y578333D02*
Y575000D01*
G01Y579667D02*
X373133Y579750D01*
Y579917D01*
X373300Y580000D01*
X373467Y579917D01*
Y579750D01*
X373300Y579667D01*
G01X377650Y578333D02*
X380150D01*
X377650Y575000D01*
X380150D01*
G01X383250Y577250D02*
X385917D01*
X385667Y577833D01*
X385250Y578167D01*
X384667Y578333D01*
X384083Y578250D01*
X383583Y578000D01*
X383250Y577417D01*
X383083Y576917D01*
Y576417D01*
X383250Y575917D01*
X383667Y575417D01*
X384167Y575083D01*
X384750Y575000D01*
X385333Y575167D01*
X385917Y575667D01*
G01X391767Y575000D02*
X388433Y576667D01*
X391767Y578333D01*
G01X395700Y575000D02*
Y580000D01*
X394700Y579000D01*
G01Y575000D02*
X396700D01*
G01X399717Y577083D02*
X400300Y577667D01*
X400800Y578000D01*
X401467Y578167D01*
X402050Y578000D01*
X402467Y577667D01*
X402800Y577167D01*
X402883Y576583D01*
X402800Y576083D01*
X402467Y575583D01*
X401967Y575167D01*
X401383Y575000D01*
X400717Y575167D01*
X400133Y575667D01*
X399800Y576417D01*
X399717Y577250D01*
X399883Y578333D01*
X400133Y578917D01*
X400550Y579500D01*
X401133Y579917D01*
X401717Y580000D01*
X402300Y579833D01*
X402717Y579417D01*
G01X410000Y575000D02*
Y578333D01*
G01Y577417D02*
X410250Y577833D01*
X410667Y578167D01*
X411250Y578333D01*
X411833Y578167D01*
X412250Y577833D01*
X412500Y577417D01*
Y575000D01*
G01Y577417D02*
X412750Y577833D01*
X413167Y578167D01*
X413750Y578333D01*
X414333Y578167D01*
X414750Y577833D01*
X415000Y577333D01*
Y575000D01*
G01X418100Y578333D02*
Y575000D01*
G01Y579667D02*
X417933Y579750D01*
Y579917D01*
X418100Y580000D01*
X418267Y579917D01*
Y579750D01*
X418100Y579667D01*
G01X423700Y575000D02*
Y580000D01*
G01X429717Y573333D02*
X430550Y574167D01*
X430967Y575000D01*
Y578333D01*
X430550Y579167D01*
X429717Y580000D01*
G01X270833Y560000D02*
Y565000D01*
X272833D01*
X273500Y564750D01*
X274000Y564167D01*
X274167Y563500D01*
X274000Y562833D01*
X273583Y562333D01*
X272833Y562083D01*
X270833D01*
G01X278100Y560000D02*
Y565000D01*
G01X282283Y563333D02*
Y561000D01*
X282617Y560417D01*
X283117Y560083D01*
X283700Y560000D01*
X284283Y560083D01*
X284783Y560417D01*
X285117Y561000D01*
G01Y560000D02*
Y563333D01*
G01X288133Y558750D02*
X288717Y558417D01*
X289383Y558333D01*
X289967Y558417D01*
X290467Y558833D01*
X290800Y559417D01*
Y563333D01*
G01Y562667D02*
X290467Y563000D01*
X289967Y563250D01*
X289383Y563333D01*
X288717Y563167D01*
X288300Y562833D01*
X287967Y562250D01*
X287800Y561667D01*
X287883Y561167D01*
X288217Y560583D01*
X288717Y560167D01*
X289383Y560000D01*
X289883Y560083D01*
X290467Y560417D01*
X290800Y560750D01*
G01X293733Y558750D02*
X294317Y558417D01*
X294983Y558333D01*
X295567Y558417D01*
X296067Y558833D01*
X296400Y559417D01*
Y563333D01*
G01Y562667D02*
X296067Y563000D01*
X295567Y563250D01*
X294983Y563333D01*
X294317Y563167D01*
X293900Y562833D01*
X293567Y562250D01*
X293400Y561667D01*
X293483Y561167D01*
X293817Y560583D01*
X294317Y560167D01*
X294983Y560000D01*
X295483Y560083D01*
X296067Y560417D01*
X296400Y560750D01*
G01X299250Y562250D02*
X301917D01*
X301667Y562833D01*
X301250Y563167D01*
X300667Y563333D01*
X300083Y563250D01*
X299583Y563000D01*
X299250Y562417D01*
X299083Y561917D01*
Y561417D01*
X299250Y560917D01*
X299667Y560417D01*
X300167Y560083D01*
X300750Y560000D01*
X301333Y560167D01*
X301917Y560667D01*
G01X307600Y565000D02*
Y560000D01*
G01Y560750D02*
X307267Y560333D01*
X306767Y560083D01*
X306183Y560000D01*
X305517Y560167D01*
X305017Y560583D01*
X304683Y561083D01*
X304600Y561667D01*
X304683Y562250D01*
X305017Y562750D01*
X305517Y563167D01*
X306183Y563333D01*
X306767Y563250D01*
X307183Y563083D01*
X307600Y562750D01*
G01X315633Y560000D02*
Y565000D01*
X317633D01*
X318300Y564750D01*
X318800Y564167D01*
X318967Y563500D01*
X318800Y562833D01*
X318383Y562333D01*
X317633Y562083D01*
X315633D01*
G01X322900Y565000D02*
Y560000D01*
G01X320983Y565000D02*
X324817D01*
G01X326750Y560000D02*
Y565000D01*
G01X330250D02*
Y560000D01*
G01Y562500D02*
X326750D01*
G01X333683Y558333D02*
X332850Y559167D01*
X332433Y560000D01*
Y563333D01*
X332850Y564167D01*
X333683Y565000D01*
G01X338283Y560000D02*
Y565000D01*
G01Y562583D02*
X338700Y563000D01*
X339117Y563250D01*
X339783Y563333D01*
X340283Y563250D01*
X340867Y562917D01*
X341117Y562417D01*
Y560000D01*
G01X345300D02*
X344800Y560083D01*
X344300Y560417D01*
X343967Y561000D01*
X343800Y561667D01*
X343967Y562333D01*
X344300Y562917D01*
X344800Y563250D01*
X345300Y563333D01*
X345800Y563250D01*
X346300Y562917D01*
X346633Y562333D01*
X346717Y561667D01*
X346633Y561000D01*
X346300Y560417D01*
X345800Y560083D01*
X345300Y560000D01*
G01X350900D02*
Y565000D01*
G01X355250Y562250D02*
X357917D01*
X357667Y562833D01*
X357250Y563167D01*
X356667Y563333D01*
X356083Y563250D01*
X355583Y563000D01*
X355250Y562417D01*
X355083Y561917D01*
Y561417D01*
X355250Y560917D01*
X355667Y560417D01*
X356167Y560083D01*
X356750Y560000D01*
X357333Y560167D01*
X357917Y560667D01*
G01X366450Y560583D02*
X366867Y560250D01*
X367450Y560000D01*
X367950D01*
X368450Y560167D01*
X368783Y560417D01*
X368950Y560750D01*
X368867Y561250D01*
X368533Y561500D01*
X367033Y562000D01*
X366700Y562583D01*
X366867Y563000D01*
X367200Y563250D01*
X367700Y563333D01*
X368200Y563250D01*
X368700Y563000D01*
G01X373300Y563333D02*
Y560000D01*
G01Y564667D02*
X373133Y564750D01*
Y564917D01*
X373300Y565000D01*
X373467Y564917D01*
Y564750D01*
X373300Y564667D01*
G01X377650Y563333D02*
X380150D01*
X377650Y560000D01*
X380150D01*
G01X383250Y562250D02*
X385917D01*
X385667Y562833D01*
X385250Y563167D01*
X384667Y563333D01*
X384083Y563250D01*
X383583Y563000D01*
X383250Y562417D01*
X383083Y561917D01*
Y561417D01*
X383250Y560917D01*
X383667Y560417D01*
X384167Y560083D01*
X384750Y560000D01*
X385333Y560167D01*
X385917Y560667D01*
G01X388433Y560000D02*
X391767Y561667D01*
X388433Y563333D01*
G01X394617Y560917D02*
X396783D01*
G01Y562417D02*
X394617D01*
G01X401300Y560000D02*
Y565000D01*
X400300Y564000D01*
G01Y560000D02*
X402300D01*
G01X405317Y562083D02*
X405900Y562667D01*
X406400Y563000D01*
X407067Y563167D01*
X407650Y563000D01*
X408067Y562667D01*
X408400Y562167D01*
X408483Y561583D01*
X408400Y561083D01*
X408067Y560583D01*
X407567Y560167D01*
X406983Y560000D01*
X406317Y560167D01*
X405733Y560667D01*
X405400Y561417D01*
X405317Y562250D01*
X405483Y563333D01*
X405733Y563917D01*
X406150Y564500D01*
X406733Y564917D01*
X407317Y565000D01*
X407900Y564833D01*
X408317Y564417D01*
G01X415600Y560000D02*
Y563333D01*
G01Y562417D02*
X415850Y562833D01*
X416267Y563167D01*
X416850Y563333D01*
X417433Y563167D01*
X417850Y562833D01*
X418100Y562417D01*
Y560000D01*
G01Y562417D02*
X418350Y562833D01*
X418767Y563167D01*
X419350Y563333D01*
X419933Y563167D01*
X420350Y562833D01*
X420600Y562333D01*
Y560000D01*
G01X423700Y563333D02*
Y560000D01*
G01Y564667D02*
X423533Y564750D01*
Y564917D01*
X423700Y565000D01*
X423867Y564917D01*
Y564750D01*
X423700Y564667D01*
G01X429300Y560000D02*
Y565000D01*
G01X435317Y558333D02*
X436150Y559167D01*
X436567Y560000D01*
Y563333D01*
X436150Y564167D01*
X435317Y565000D01*
G01X262500Y554000D02*
X694500D01*
G01X262500Y569000D02*
X694500D01*
G01X273000Y609000D02*
Y604000D01*
G01X271083Y609000D02*
X274917D01*
G01X277183Y604000D02*
Y609000D01*
G01Y606583D02*
X277600Y607000D01*
X278017Y607250D01*
X278683Y607333D01*
X279183Y607250D01*
X279767Y606917D01*
X280017Y606417D01*
Y604000D01*
G01X282950Y606250D02*
X285617D01*
X285367Y606833D01*
X284950Y607167D01*
X284367Y607333D01*
X283783Y607250D01*
X283283Y607000D01*
X282950Y606417D01*
X282783Y605917D01*
Y605417D01*
X282950Y604917D01*
X283367Y604417D01*
X283867Y604083D01*
X284450Y604000D01*
X285033Y604167D01*
X285617Y604667D01*
G01X288633Y604000D02*
Y607333D01*
G01Y606667D02*
X289050Y607000D01*
X289467Y607250D01*
X290050Y607333D01*
X290467Y607250D01*
X290967Y607000D01*
G01X292900Y604000D02*
Y607333D01*
G01Y606417D02*
X293150Y606833D01*
X293567Y607167D01*
X294150Y607333D01*
X294733Y607167D01*
X295150Y606833D01*
X295400Y606417D01*
Y604000D01*
G01Y606417D02*
X295650Y606833D01*
X296067Y607167D01*
X296650Y607333D01*
X297233Y607167D01*
X297650Y606833D01*
X297900Y606333D01*
Y604000D01*
G01X302500D02*
Y607333D01*
G01Y606750D02*
X302167Y607083D01*
X301667Y607250D01*
X301083Y607333D01*
X300500Y607167D01*
X300000Y606833D01*
X299667Y606333D01*
X299500Y605667D01*
X299667Y605000D01*
X300000Y604500D01*
X300500Y604167D01*
X301083Y604000D01*
X301667Y604083D01*
X302167Y604333D01*
X302500Y604667D01*
G01X306600Y604000D02*
Y609000D01*
G01X316300Y602333D02*
Y607333D01*
G01Y606583D02*
X316717Y607000D01*
X317133Y607250D01*
X317800Y607333D01*
X318383Y607250D01*
X318967Y606833D01*
X319217Y606250D01*
X319300Y605667D01*
X319217Y605083D01*
X318967Y604500D01*
X318467Y604167D01*
X317800Y604000D01*
X317217Y604083D01*
X316633Y604333D01*
X316300Y604667D01*
G01X324900Y604000D02*
Y607333D01*
G01Y606750D02*
X324567Y607083D01*
X324067Y607250D01*
X323483Y607333D01*
X322900Y607167D01*
X322400Y606833D01*
X322067Y606333D01*
X321900Y605667D01*
X322067Y605000D01*
X322400Y604500D01*
X322900Y604167D01*
X323483Y604000D01*
X324067Y604083D01*
X324567Y604333D01*
X324900Y604667D01*
G01X330500Y609000D02*
Y604000D01*
G01Y604750D02*
X330167Y604333D01*
X329667Y604083D01*
X329083Y604000D01*
X328417Y604167D01*
X327917Y604583D01*
X327583Y605083D01*
X327500Y605667D01*
X327583Y606250D01*
X327917Y606750D01*
X328417Y607167D01*
X329083Y607333D01*
X329667Y607250D01*
X330083Y607083D01*
X330500Y606750D01*
G01X341533Y606917D02*
X340950Y607250D01*
X340450Y607333D01*
X339783Y607167D01*
X339283Y606833D01*
X338950Y606250D01*
X338867Y605667D01*
X338950Y605083D01*
X339283Y604583D01*
X339783Y604167D01*
X340450Y604000D01*
X341033Y604167D01*
X341533Y604500D01*
G01X347300Y604000D02*
Y607333D01*
G01Y606750D02*
X346967Y607083D01*
X346467Y607250D01*
X345883Y607333D01*
X345300Y607167D01*
X344800Y606833D01*
X344467Y606333D01*
X344300Y605667D01*
X344467Y605000D01*
X344800Y604500D01*
X345300Y604167D01*
X345883Y604000D01*
X346467Y604083D01*
X346967Y604333D01*
X347300Y604667D01*
G01X349983Y604000D02*
Y607333D01*
G01Y606500D02*
X350317Y606917D01*
X350817Y607250D01*
X351483Y607333D01*
X352067Y607250D01*
X352567Y606917D01*
X352817Y606333D01*
Y604000D01*
G01X363933Y606917D02*
X363350Y607250D01*
X362850Y607333D01*
X362183Y607167D01*
X361683Y606833D01*
X361350Y606250D01*
X361267Y605667D01*
X361350Y605083D01*
X361683Y604583D01*
X362183Y604167D01*
X362850Y604000D01*
X363433Y604167D01*
X363933Y604500D01*
G01X366783Y604000D02*
Y609000D01*
G01Y606583D02*
X367200Y607000D01*
X367617Y607250D01*
X368283Y607333D01*
X368783Y607250D01*
X369367Y606917D01*
X369617Y606417D01*
Y604000D01*
G01X375300D02*
Y607333D01*
G01Y606750D02*
X374967Y607083D01*
X374467Y607250D01*
X373883Y607333D01*
X373300Y607167D01*
X372800Y606833D01*
X372467Y606333D01*
X372300Y605667D01*
X372467Y605000D01*
X372800Y604500D01*
X373300Y604167D01*
X373883Y604000D01*
X374467Y604083D01*
X374967Y604333D01*
X375300Y604667D01*
G01X377983Y604000D02*
Y607333D01*
G01Y606500D02*
X378317Y606917D01*
X378817Y607250D01*
X379483Y607333D01*
X380067Y607250D01*
X380567Y606917D01*
X380817Y606333D01*
Y604000D01*
G01X383833Y602750D02*
X384417Y602417D01*
X385083Y602333D01*
X385667Y602417D01*
X386167Y602833D01*
X386500Y603417D01*
Y607333D01*
G01Y606667D02*
X386167Y607000D01*
X385667Y607250D01*
X385083Y607333D01*
X384417Y607167D01*
X384000Y606833D01*
X383667Y606250D01*
X383500Y605667D01*
X383583Y605167D01*
X383917Y604583D01*
X384417Y604167D01*
X385083Y604000D01*
X385583Y604083D01*
X386167Y604417D01*
X386500Y604750D01*
G01X389350Y606250D02*
X392017D01*
X391767Y606833D01*
X391350Y607167D01*
X390767Y607333D01*
X390183Y607250D01*
X389683Y607000D01*
X389350Y606417D01*
X389183Y605917D01*
Y605417D01*
X389350Y604917D01*
X389767Y604417D01*
X390267Y604083D01*
X390850Y604000D01*
X391433Y604167D01*
X392017Y604667D01*
G01X401800Y607333D02*
Y604000D01*
G01Y608667D02*
X401633Y608750D01*
Y608917D01*
X401800Y609000D01*
X401967Y608917D01*
Y608750D01*
X401800Y608667D01*
G01X405983Y604000D02*
Y607333D01*
G01Y606500D02*
X406317Y606917D01*
X406817Y607250D01*
X407483Y607333D01*
X408067Y607250D01*
X408567Y606917D01*
X408817Y606333D01*
Y604000D01*
G01X413000Y609000D02*
Y604000D01*
G01X411833Y607333D02*
X414167D01*
G01X418600Y604000D02*
X418100Y604083D01*
X417600Y604417D01*
X417267Y605000D01*
X417100Y605667D01*
X417267Y606333D01*
X417600Y606917D01*
X418100Y607250D01*
X418600Y607333D01*
X419100Y607250D01*
X419600Y606917D01*
X419933Y606333D01*
X420017Y605667D01*
X419933Y605000D01*
X419600Y604417D01*
X419100Y604083D01*
X418600Y604000D01*
G01X429300D02*
Y608250D01*
X429467Y608667D01*
X429800Y608917D01*
X430300Y609000D01*
X430800Y608833D01*
X431050Y608417D01*
G01X430050Y607000D02*
X428383D01*
G01X433983Y607333D02*
Y605000D01*
X434317Y604417D01*
X434817Y604083D01*
X435400Y604000D01*
X435983Y604083D01*
X436483Y604417D01*
X436817Y605000D01*
G01Y604000D02*
Y607333D01*
G01X441000Y604000D02*
Y609000D01*
G01X446600Y604000D02*
Y609000D01*
G01X459133Y606917D02*
X458550Y607250D01*
X458050Y607333D01*
X457383Y607167D01*
X456883Y606833D01*
X456550Y606250D01*
X456467Y605667D01*
X456550Y605083D01*
X456883Y604583D01*
X457383Y604167D01*
X458050Y604000D01*
X458633Y604167D01*
X459133Y604500D01*
G01X463400Y604000D02*
X462900Y604083D01*
X462400Y604417D01*
X462067Y605000D01*
X461900Y605667D01*
X462067Y606333D01*
X462400Y606917D01*
X462900Y607250D01*
X463400Y607333D01*
X463900Y607250D01*
X464400Y606917D01*
X464733Y606333D01*
X464817Y605667D01*
X464733Y605000D01*
X464400Y604417D01*
X463900Y604083D01*
X463400Y604000D01*
G01X467583D02*
Y607333D01*
G01Y606500D02*
X467917Y606917D01*
X468417Y607250D01*
X469083Y607333D01*
X469667Y607250D01*
X470167Y606917D01*
X470417Y606333D01*
Y604000D01*
G01X474600Y609000D02*
Y604000D01*
G01X473433Y607333D02*
X475767D01*
G01X481700Y604000D02*
Y607333D01*
G01Y606750D02*
X481367Y607083D01*
X480867Y607250D01*
X480283Y607333D01*
X479700Y607167D01*
X479200Y606833D01*
X478867Y606333D01*
X478700Y605667D01*
X478867Y605000D01*
X479200Y604500D01*
X479700Y604167D01*
X480283Y604000D01*
X480867Y604083D01*
X481367Y604333D01*
X481700Y604667D01*
G01X487133Y606917D02*
X486550Y607250D01*
X486050Y607333D01*
X485383Y607167D01*
X484883Y606833D01*
X484550Y606250D01*
X484467Y605667D01*
X484550Y605083D01*
X484883Y604583D01*
X485383Y604167D01*
X486050Y604000D01*
X486633Y604167D01*
X487133Y604500D01*
G01X491400Y609000D02*
Y604000D01*
G01X490233Y607333D02*
X492567D01*
G01X270917Y619000D02*
X273000Y624000D01*
X275083Y619000D01*
G01X274333Y620750D02*
X271667D01*
G01X277183Y619000D02*
Y622333D01*
G01Y621500D02*
X277517Y621917D01*
X278017Y622250D01*
X278683Y622333D01*
X279267Y622250D01*
X279767Y621917D01*
X280017Y621333D01*
Y619000D01*
G01X284200Y624000D02*
Y619000D01*
G01X283033Y622333D02*
X285367D01*
G01X289800D02*
Y619000D01*
G01Y623667D02*
X289633Y623750D01*
Y623917D01*
X289800Y624000D01*
X289967Y623917D01*
Y623750D01*
X289800Y623667D01*
G01X294317Y620667D02*
X296483D01*
G01X299500Y617333D02*
Y622333D01*
G01Y621583D02*
X299917Y622000D01*
X300333Y622250D01*
X301000Y622333D01*
X301583Y622250D01*
X302167Y621833D01*
X302417Y621250D01*
X302500Y620667D01*
X302417Y620083D01*
X302167Y619500D01*
X301667Y619167D01*
X301000Y619000D01*
X300417Y619083D01*
X299833Y619333D01*
X299500Y619667D01*
G01X308100Y619000D02*
Y622333D01*
G01Y621750D02*
X307767Y622083D01*
X307267Y622250D01*
X306683Y622333D01*
X306100Y622167D01*
X305600Y621833D01*
X305267Y621333D01*
X305100Y620667D01*
X305267Y620000D01*
X305600Y619500D01*
X306100Y619167D01*
X306683Y619000D01*
X307267Y619083D01*
X307767Y619333D01*
X308100Y619667D01*
G01X313700Y624000D02*
Y619000D01*
G01Y619750D02*
X313367Y619333D01*
X312867Y619083D01*
X312283Y619000D01*
X311617Y619167D01*
X311117Y619583D01*
X310783Y620083D01*
X310700Y620667D01*
X310783Y621250D01*
X311117Y621750D01*
X311617Y622167D01*
X312283Y622333D01*
X312867Y622250D01*
X313283Y622083D01*
X313700Y621750D01*
G01X322150Y619583D02*
X322567Y619250D01*
X323150Y619000D01*
X323650D01*
X324150Y619167D01*
X324483Y619417D01*
X324650Y619750D01*
X324567Y620250D01*
X324233Y620500D01*
X322733Y621000D01*
X322400Y621583D01*
X322567Y622000D01*
X322900Y622250D01*
X323400Y622333D01*
X323900Y622250D01*
X324400Y622000D01*
G01X329000Y622333D02*
Y619000D01*
G01Y623667D02*
X328833Y623750D01*
Y623917D01*
X329000Y624000D01*
X329167Y623917D01*
Y623750D01*
X329000Y623667D01*
G01X333350Y622333D02*
X335850D01*
X333350Y619000D01*
X335850D01*
G01X338950Y621250D02*
X341617D01*
X341367Y621833D01*
X340950Y622167D01*
X340367Y622333D01*
X339783Y622250D01*
X339283Y622000D01*
X338950Y621417D01*
X338783Y620917D01*
Y620417D01*
X338950Y619917D01*
X339367Y619417D01*
X339867Y619083D01*
X340450Y619000D01*
X341033Y619167D01*
X341617Y619667D01*
G01X269717Y637573D02*
X270717Y634240D01*
X271800Y637573D01*
X272883Y634240D01*
X273883Y637573D01*
G01X277400D02*
Y634240D01*
G01Y638907D02*
X277233Y638990D01*
Y639157D01*
X277400Y639240D01*
X277567Y639157D01*
Y638990D01*
X277400Y638907D01*
G01X283000Y639240D02*
Y634240D01*
G01X281833Y637573D02*
X284167D01*
G01X287183Y634240D02*
Y639240D01*
G01Y636823D02*
X287600Y637240D01*
X288017Y637490D01*
X288683Y637573D01*
X289183Y637490D01*
X289767Y637157D01*
X290017Y636657D01*
Y634240D01*
G01X294200D02*
X293700Y634323D01*
X293200Y634657D01*
X292867Y635240D01*
X292700Y635907D01*
X292867Y636573D01*
X293200Y637157D01*
X293700Y637490D01*
X294200Y637573D01*
X294700Y637490D01*
X295200Y637157D01*
X295533Y636573D01*
X295617Y635907D01*
X295533Y635240D01*
X295200Y634657D01*
X294700Y634323D01*
X294200Y634240D01*
G01X298383Y637573D02*
Y635240D01*
X298717Y634657D01*
X299217Y634323D01*
X299800Y634240D01*
X300383Y634323D01*
X300883Y634657D01*
X301217Y635240D01*
G01Y634240D02*
Y637573D01*
G01X305400Y639240D02*
Y634240D01*
G01X304233Y637573D02*
X306567D01*
G01X317933Y637157D02*
X317350Y637490D01*
X316850Y637573D01*
X316183Y637407D01*
X315683Y637073D01*
X315350Y636490D01*
X315267Y635907D01*
X315350Y635323D01*
X315683Y634823D01*
X316183Y634407D01*
X316850Y634240D01*
X317433Y634407D01*
X317933Y634740D01*
G01X322200Y634240D02*
X321700Y634323D01*
X321200Y634657D01*
X320867Y635240D01*
X320700Y635907D01*
X320867Y636573D01*
X321200Y637157D01*
X321700Y637490D01*
X322200Y637573D01*
X322700Y637490D01*
X323200Y637157D01*
X323533Y636573D01*
X323617Y635907D01*
X323533Y635240D01*
X323200Y634657D01*
X322700Y634323D01*
X322200Y634240D01*
G01X326383D02*
Y637573D01*
G01Y636740D02*
X326717Y637157D01*
X327217Y637490D01*
X327883Y637573D01*
X328467Y637490D01*
X328967Y637157D01*
X329217Y636573D01*
Y634240D01*
G01X331983D02*
Y637573D01*
G01Y636740D02*
X332317Y637157D01*
X332817Y637490D01*
X333483Y637573D01*
X334067Y637490D01*
X334567Y637157D01*
X334817Y636573D01*
Y634240D01*
G01X337750Y636490D02*
X340417D01*
X340167Y637073D01*
X339750Y637407D01*
X339167Y637573D01*
X338583Y637490D01*
X338083Y637240D01*
X337750Y636657D01*
X337583Y636157D01*
Y635657D01*
X337750Y635157D01*
X338167Y634657D01*
X338667Y634323D01*
X339250Y634240D01*
X339833Y634407D01*
X340417Y634907D01*
G01X345933Y637157D02*
X345350Y637490D01*
X344850Y637573D01*
X344183Y637407D01*
X343683Y637073D01*
X343350Y636490D01*
X343267Y635907D01*
X343350Y635323D01*
X343683Y634823D01*
X344183Y634407D01*
X344850Y634240D01*
X345433Y634407D01*
X345933Y634740D01*
G01X350200Y639240D02*
Y634240D01*
G01X349033Y637573D02*
X351367D01*
G01X355800D02*
Y634240D01*
G01Y638907D02*
X355633Y638990D01*
Y639157D01*
X355800Y639240D01*
X355967Y639157D01*
Y638990D01*
X355800Y638907D01*
G01X359983Y634240D02*
Y637573D01*
G01Y636740D02*
X360317Y637157D01*
X360817Y637490D01*
X361483Y637573D01*
X362067Y637490D01*
X362567Y637157D01*
X362817Y636573D01*
Y634240D01*
G01X365833Y632990D02*
X366417Y632657D01*
X367083Y632573D01*
X367667Y632657D01*
X368167Y633073D01*
X368500Y633657D01*
Y637573D01*
G01Y636907D02*
X368167Y637240D01*
X367667Y637490D01*
X367083Y637573D01*
X366417Y637407D01*
X366000Y637073D01*
X365667Y636490D01*
X365500Y635907D01*
X365583Y635407D01*
X365917Y634823D01*
X366417Y634407D01*
X367083Y634240D01*
X367583Y634323D01*
X368167Y634657D01*
X368500Y634990D01*
G01X378200Y639240D02*
Y634240D01*
G01X377033Y637573D02*
X379367D01*
G01X383800Y634240D02*
X383300Y634323D01*
X382800Y634657D01*
X382467Y635240D01*
X382300Y635907D01*
X382467Y636573D01*
X382800Y637157D01*
X383300Y637490D01*
X383800Y637573D01*
X384300Y637490D01*
X384800Y637157D01*
X385133Y636573D01*
X385217Y635907D01*
X385133Y635240D01*
X384800Y634657D01*
X384300Y634323D01*
X383800Y634240D01*
G01X395000D02*
X394500Y634323D01*
X394000Y634657D01*
X393667Y635240D01*
X393500Y635907D01*
X393667Y636573D01*
X394000Y637157D01*
X394500Y637490D01*
X395000Y637573D01*
X395500Y637490D01*
X396000Y637157D01*
X396333Y636573D01*
X396417Y635907D01*
X396333Y635240D01*
X396000Y634657D01*
X395500Y634323D01*
X395000Y634240D01*
G01X400600Y639240D02*
Y634240D01*
G01X399433Y637573D02*
X401767D01*
G01X404783Y634240D02*
Y639240D01*
G01Y636823D02*
X405200Y637240D01*
X405617Y637490D01*
X406283Y637573D01*
X406783Y637490D01*
X407367Y637157D01*
X407617Y636657D01*
Y634240D01*
G01X410550Y636490D02*
X413217D01*
X412967Y637073D01*
X412550Y637407D01*
X411967Y637573D01*
X411383Y637490D01*
X410883Y637240D01*
X410550Y636657D01*
X410383Y636157D01*
Y635657D01*
X410550Y635157D01*
X410967Y634657D01*
X411467Y634323D01*
X412050Y634240D01*
X412633Y634407D01*
X413217Y634907D01*
G01X416233Y634240D02*
Y637573D01*
G01Y636907D02*
X416650Y637240D01*
X417067Y637490D01*
X417650Y637573D01*
X418067Y637490D01*
X418567Y637240D01*
G01X428600Y634240D02*
Y639240D01*
G01X435700Y634240D02*
Y637573D01*
G01Y636990D02*
X435367Y637323D01*
X434867Y637490D01*
X434283Y637573D01*
X433700Y637407D01*
X433200Y637073D01*
X432867Y636573D01*
X432700Y635907D01*
X432867Y635240D01*
X433200Y634740D01*
X433700Y634407D01*
X434283Y634240D01*
X434867Y634323D01*
X435367Y634573D01*
X435700Y634907D01*
G01X438050Y632740D02*
X438550Y632573D01*
X439217Y632740D01*
X439633Y633073D01*
X439967Y633490D01*
X440467Y634823D01*
X441550Y637573D01*
G01X438883D02*
X440467Y634823D01*
G01X444150Y636490D02*
X446817D01*
X446567Y637073D01*
X446150Y637407D01*
X445567Y637573D01*
X444983Y637490D01*
X444483Y637240D01*
X444150Y636657D01*
X443983Y636157D01*
Y635657D01*
X444150Y635157D01*
X444567Y634657D01*
X445067Y634323D01*
X445650Y634240D01*
X446233Y634407D01*
X446817Y634907D01*
G01X449833Y634240D02*
Y637573D01*
G01Y636907D02*
X450250Y637240D01*
X450667Y637490D01*
X451250Y637573D01*
X451667Y637490D01*
X452167Y637240D01*
G01X455350Y634823D02*
X455767Y634490D01*
X456350Y634240D01*
X456850D01*
X457350Y634407D01*
X457683Y634657D01*
X457850Y634990D01*
X457767Y635490D01*
X457433Y635740D01*
X455933Y636240D01*
X455600Y636823D01*
X455767Y637240D01*
X456100Y637490D01*
X456600Y637573D01*
X457100Y637490D01*
X457600Y637240D01*
G01X462617Y632573D02*
X463450Y633407D01*
X463867Y634240D01*
Y637573D01*
X463450Y638407D01*
X462617Y639240D01*
G01X270257Y644950D02*
Y649950D01*
X271923D01*
X272590Y649700D01*
X273090Y649367D01*
X273507Y648867D01*
X273840Y648283D01*
X273923Y647450D01*
X273840Y646617D01*
X273507Y646033D01*
X273090Y645533D01*
X272590Y645200D01*
X271923Y644950D01*
X270257D01*
G01X276440Y647200D02*
X279107D01*
X278857Y647783D01*
X278440Y648117D01*
X277857Y648283D01*
X277273Y648200D01*
X276773Y647950D01*
X276440Y647367D01*
X276273Y646867D01*
Y646367D01*
X276440Y645867D01*
X276857Y645367D01*
X277357Y645033D01*
X277940Y644950D01*
X278523Y645117D01*
X279107Y645617D01*
G01X283290Y644950D02*
Y649950D01*
G01X287640Y647200D02*
X290307D01*
X290057Y647783D01*
X289640Y648117D01*
X289057Y648283D01*
X288473Y648200D01*
X287973Y647950D01*
X287640Y647367D01*
X287473Y646867D01*
Y646367D01*
X287640Y645867D01*
X288057Y645367D01*
X288557Y645033D01*
X289140Y644950D01*
X289723Y645117D01*
X290307Y645617D01*
G01X294490Y649950D02*
Y644950D01*
G01X293323Y648283D02*
X295657D01*
G01X298840Y647200D02*
X301507D01*
X301257Y647783D01*
X300840Y648117D01*
X300257Y648283D01*
X299673Y648200D01*
X299173Y647950D01*
X298840Y647367D01*
X298673Y646867D01*
Y646367D01*
X298840Y645867D01*
X299257Y645367D01*
X299757Y645033D01*
X300340Y644950D01*
X300923Y645117D01*
X301507Y645617D01*
G01X309873Y644950D02*
Y648283D01*
G01Y647450D02*
X310207Y647867D01*
X310707Y648200D01*
X311373Y648283D01*
X311957Y648200D01*
X312457Y647867D01*
X312707Y647283D01*
Y644950D01*
G01X316890D02*
X316390Y645033D01*
X315890Y645367D01*
X315557Y645950D01*
X315390Y646617D01*
X315557Y647283D01*
X315890Y647867D01*
X316390Y648200D01*
X316890Y648283D01*
X317390Y648200D01*
X317890Y647867D01*
X318223Y647283D01*
X318307Y646617D01*
X318223Y645950D01*
X317890Y645367D01*
X317390Y645033D01*
X316890Y644950D01*
G01X321073D02*
Y648283D01*
G01Y647450D02*
X321407Y647867D01*
X321907Y648200D01*
X322573Y648283D01*
X323157Y648200D01*
X323657Y647867D01*
X323907Y647283D01*
Y644950D01*
G01X327007Y646617D02*
X329173D01*
G01X333190Y644950D02*
Y649200D01*
X333357Y649617D01*
X333690Y649867D01*
X334190Y649950D01*
X334690Y649783D01*
X334940Y649367D01*
G01X333940Y647950D02*
X332273D01*
G01X337873Y648283D02*
Y645950D01*
X338207Y645367D01*
X338707Y645033D01*
X339290Y644950D01*
X339873Y645033D01*
X340373Y645367D01*
X340707Y645950D01*
G01Y644950D02*
Y648283D01*
G01X343473Y644950D02*
Y648283D01*
G01Y647450D02*
X343807Y647867D01*
X344307Y648200D01*
X344973Y648283D01*
X345557Y648200D01*
X346057Y647867D01*
X346307Y647283D01*
Y644950D01*
G01X351823Y647867D02*
X351240Y648200D01*
X350740Y648283D01*
X350073Y648117D01*
X349573Y647783D01*
X349240Y647200D01*
X349157Y646617D01*
X349240Y646033D01*
X349573Y645533D01*
X350073Y645117D01*
X350740Y644950D01*
X351323Y645117D01*
X351823Y645450D01*
G01X356090Y649950D02*
Y644950D01*
G01X354923Y648283D02*
X357257D01*
G01X361690D02*
Y644950D01*
G01Y649617D02*
X361523Y649700D01*
Y649867D01*
X361690Y649950D01*
X361857Y649867D01*
Y649700D01*
X361690Y649617D01*
G01X367290Y644950D02*
X366790Y645033D01*
X366290Y645367D01*
X365957Y645950D01*
X365790Y646617D01*
X365957Y647283D01*
X366290Y647867D01*
X366790Y648200D01*
X367290Y648283D01*
X367790Y648200D01*
X368290Y647867D01*
X368623Y647283D01*
X368707Y646617D01*
X368623Y645950D01*
X368290Y645367D01*
X367790Y645033D01*
X367290Y644950D01*
G01X371473D02*
Y648283D01*
G01Y647450D02*
X371807Y647867D01*
X372307Y648200D01*
X372973Y648283D01*
X373557Y648200D01*
X374057Y647867D01*
X374307Y647283D01*
Y644950D01*
G01X379990D02*
Y648283D01*
G01Y647700D02*
X379657Y648033D01*
X379157Y648200D01*
X378573Y648283D01*
X377990Y648117D01*
X377490Y647783D01*
X377157Y647283D01*
X376990Y646617D01*
X377157Y645950D01*
X377490Y645450D01*
X377990Y645117D01*
X378573Y644950D01*
X379157Y645033D01*
X379657Y645283D01*
X379990Y645617D01*
G01X384090Y644950D02*
Y649950D01*
G01X393790Y643283D02*
Y648283D01*
G01Y647533D02*
X394207Y647950D01*
X394623Y648200D01*
X395290Y648283D01*
X395873Y648200D01*
X396457Y647783D01*
X396707Y647200D01*
X396790Y646617D01*
X396707Y646033D01*
X396457Y645450D01*
X395957Y645117D01*
X395290Y644950D01*
X394707Y645033D01*
X394123Y645283D01*
X393790Y645617D01*
G01X402390Y644950D02*
Y648283D01*
G01Y647700D02*
X402057Y648033D01*
X401557Y648200D01*
X400973Y648283D01*
X400390Y648117D01*
X399890Y647783D01*
X399557Y647283D01*
X399390Y646617D01*
X399557Y645950D01*
X399890Y645450D01*
X400390Y645117D01*
X400973Y644950D01*
X401557Y645033D01*
X402057Y645283D01*
X402390Y645617D01*
G01X407990Y649950D02*
Y644950D01*
G01Y645700D02*
X407657Y645283D01*
X407157Y645033D01*
X406573Y644950D01*
X405907Y645117D01*
X405407Y645533D01*
X405073Y646033D01*
X404990Y646617D01*
X405073Y647200D01*
X405407Y647700D01*
X405907Y648117D01*
X406573Y648283D01*
X407157Y648200D01*
X407573Y648033D01*
X407990Y647700D01*
G01X417690Y648283D02*
Y644950D01*
G01Y649617D02*
X417523Y649700D01*
Y649867D01*
X417690Y649950D01*
X417857Y649867D01*
Y649700D01*
X417690Y649617D01*
G01X421873Y644950D02*
Y648283D01*
G01Y647450D02*
X422207Y647867D01*
X422707Y648200D01*
X423373Y648283D01*
X423957Y648200D01*
X424457Y647867D01*
X424707Y647283D01*
Y644950D01*
G01X435990D02*
Y648283D01*
G01Y647700D02*
X435657Y648033D01*
X435157Y648200D01*
X434573Y648283D01*
X433990Y648117D01*
X433490Y647783D01*
X433157Y647283D01*
X432990Y646617D01*
X433157Y645950D01*
X433490Y645450D01*
X433990Y645117D01*
X434573Y644950D01*
X435157Y645033D01*
X435657Y645283D01*
X435990Y645617D01*
G01X440090Y644950D02*
Y649950D01*
G01X445690Y644950D02*
Y649950D01*
G01X455390Y643283D02*
Y648283D01*
G01Y647533D02*
X455807Y647950D01*
X456223Y648200D01*
X456890Y648283D01*
X457473Y648200D01*
X458057Y647783D01*
X458307Y647200D01*
X458390Y646617D01*
X458307Y646033D01*
X458057Y645450D01*
X457557Y645117D01*
X456890Y644950D01*
X456307Y645033D01*
X455723Y645283D01*
X455390Y645617D01*
G01X461323Y644950D02*
Y648283D01*
G01Y647617D02*
X461740Y647950D01*
X462157Y648200D01*
X462740Y648283D01*
X463157Y648200D01*
X463657Y647950D01*
G01X468090Y644950D02*
X467590Y645033D01*
X467090Y645367D01*
X466757Y645950D01*
X466590Y646617D01*
X466757Y647283D01*
X467090Y647867D01*
X467590Y648200D01*
X468090Y648283D01*
X468590Y648200D01*
X469090Y647867D01*
X469423Y647283D01*
X469507Y646617D01*
X469423Y645950D01*
X469090Y645367D01*
X468590Y645033D01*
X468090Y644950D01*
G01X475190Y649950D02*
Y644950D01*
G01Y645700D02*
X474857Y645283D01*
X474357Y645033D01*
X473773Y644950D01*
X473107Y645117D01*
X472607Y645533D01*
X472273Y646033D01*
X472190Y646617D01*
X472273Y647200D01*
X472607Y647700D01*
X473107Y648117D01*
X473773Y648283D01*
X474357Y648200D01*
X474773Y648033D01*
X475190Y647700D01*
G01X477873Y648283D02*
Y645950D01*
X478207Y645367D01*
X478707Y645033D01*
X479290Y644950D01*
X479873Y645033D01*
X480373Y645367D01*
X480707Y645950D01*
G01Y644950D02*
Y648283D01*
G01X486223Y647867D02*
X485640Y648200D01*
X485140Y648283D01*
X484473Y648117D01*
X483973Y647783D01*
X483640Y647200D01*
X483557Y646617D01*
X483640Y646033D01*
X483973Y645533D01*
X484473Y645117D01*
X485140Y644950D01*
X485723Y645117D01*
X486223Y645450D01*
G01X490490Y649950D02*
Y644950D01*
G01X489323Y648283D02*
X491657D01*
G01X494840Y645533D02*
X495257Y645200D01*
X495840Y644950D01*
X496340D01*
X496840Y645117D01*
X497173Y645367D01*
X497340Y645700D01*
X497257Y646200D01*
X496923Y646450D01*
X495423Y646950D01*
X495090Y647533D01*
X495257Y647950D01*
X495590Y648200D01*
X496090Y648283D01*
X496590Y648200D01*
X497090Y647950D01*
G01X501690Y644783D02*
X501523Y644867D01*
Y645033D01*
X501690Y645117D01*
X501857Y645033D01*
Y644867D01*
X501690Y644783D01*
G01X506873Y643283D02*
X506040Y644117D01*
X505623Y644950D01*
Y648283D01*
X506040Y649117D01*
X506873Y649950D01*
G01X511890D02*
X513890D01*
G01X512890D02*
Y644950D01*
G01X511890D02*
X513890D01*
G01X517240Y645533D02*
X517657Y645200D01*
X518240Y644950D01*
X518740D01*
X519240Y645117D01*
X519573Y645367D01*
X519740Y645700D01*
X519657Y646200D01*
X519323Y646450D01*
X517823Y646950D01*
X517490Y647533D01*
X517657Y647950D01*
X517990Y648200D01*
X518490Y648283D01*
X518990Y648200D01*
X519490Y647950D01*
G01X524090Y644950D02*
X523590Y645033D01*
X523090Y645367D01*
X522757Y645950D01*
X522590Y646617D01*
X522757Y647283D01*
X523090Y647867D01*
X523590Y648200D01*
X524090Y648283D01*
X524590Y648200D01*
X525090Y647867D01*
X525423Y647283D01*
X525507Y646617D01*
X525423Y645950D01*
X525090Y645367D01*
X524590Y645033D01*
X524090Y644950D01*
G01X529690D02*
Y649950D01*
G01X536790Y644950D02*
Y648283D01*
G01Y647700D02*
X536457Y648033D01*
X535957Y648200D01*
X535373Y648283D01*
X534790Y648117D01*
X534290Y647783D01*
X533957Y647283D01*
X533790Y646617D01*
X533957Y645950D01*
X534290Y645450D01*
X534790Y645117D01*
X535373Y644950D01*
X535957Y645033D01*
X536457Y645283D01*
X536790Y645617D01*
G01X540890Y649950D02*
Y644950D01*
G01X539723Y648283D02*
X542057D01*
G01X545240Y647200D02*
X547907D01*
X547657Y647783D01*
X547240Y648117D01*
X546657Y648283D01*
X546073Y648200D01*
X545573Y647950D01*
X545240Y647367D01*
X545073Y646867D01*
Y646367D01*
X545240Y645867D01*
X545657Y645367D01*
X546157Y645033D01*
X546740Y644950D01*
X547323Y645117D01*
X547907Y645617D01*
G01X556190Y643283D02*
Y648283D01*
G01Y647533D02*
X556607Y647950D01*
X557023Y648200D01*
X557690Y648283D01*
X558273Y648200D01*
X558857Y647783D01*
X559107Y647200D01*
X559190Y646617D01*
X559107Y646033D01*
X558857Y645450D01*
X558357Y645117D01*
X557690Y644950D01*
X557107Y645033D01*
X556523Y645283D01*
X556190Y645617D01*
G01X564790Y644950D02*
Y648283D01*
G01Y647700D02*
X564457Y648033D01*
X563957Y648200D01*
X563373Y648283D01*
X562790Y648117D01*
X562290Y647783D01*
X561957Y647283D01*
X561790Y646617D01*
X561957Y645950D01*
X562290Y645450D01*
X562790Y645117D01*
X563373Y644950D01*
X563957Y645033D01*
X564457Y645283D01*
X564790Y645617D01*
G01X570390Y649950D02*
Y644950D01*
G01Y645700D02*
X570057Y645283D01*
X569557Y645033D01*
X568973Y644950D01*
X568307Y645117D01*
X567807Y645533D01*
X567473Y646033D01*
X567390Y646617D01*
X567473Y647200D01*
X567807Y647700D01*
X568307Y648117D01*
X568973Y648283D01*
X569557Y648200D01*
X569973Y648033D01*
X570390Y647700D01*
G01X322623Y303963D02*
X322890Y304163D01*
X323090Y304497D01*
X323223Y304963D01*
X323090Y305363D01*
X322823Y305630D01*
X322357Y305830D01*
X320557D01*
Y301830D01*
X322757D01*
X323223Y302097D01*
X323490Y302497D01*
X323623Y302963D01*
X323490Y303430D01*
X323090Y303830D01*
X322623Y303963D01*
X320557D01*
G01X320423Y351330D02*
X322090Y355330D01*
X323757Y351330D01*
G01X323157Y352730D02*
X321023D01*
G01X361117Y328537D02*
X360717Y328737D01*
X360250Y328870D01*
X359717D01*
X359117Y328670D01*
X358650Y328337D01*
X358317Y327937D01*
X358050Y327270D01*
X357983Y326670D01*
X358117Y326070D01*
X358317Y325670D01*
X358717Y325270D01*
X359183Y325003D01*
X359650Y324870D01*
X360117D01*
X360583Y325003D01*
X360983Y325203D01*
X361317Y325470D01*
G01X395000Y364500D02*
Y175500D01*
G01X402977Y229887D02*
X403310Y230137D01*
X403560Y230553D01*
X403727Y231137D01*
X403560Y231637D01*
X403227Y231970D01*
X402643Y232220D01*
X400393D01*
Y227220D01*
X403143D01*
X403727Y227553D01*
X404060Y228053D01*
X404227Y228637D01*
X404060Y229220D01*
X403560Y229720D01*
X402977Y229887D01*
X400393D01*
G01X406493Y230553D02*
Y228220D01*
X406827Y227637D01*
X407327Y227303D01*
X407910Y227220D01*
X408493Y227303D01*
X408993Y227637D01*
X409327Y228220D01*
G01Y227220D02*
Y230553D01*
G01X411010Y227220D02*
Y230553D01*
G01Y229637D02*
X411260Y230053D01*
X411677Y230387D01*
X412260Y230553D01*
X412843Y230387D01*
X413260Y230053D01*
X413510Y229637D01*
Y227220D01*
G01Y229637D02*
X413760Y230053D01*
X414177Y230387D01*
X414760Y230553D01*
X415343Y230387D01*
X415760Y230053D01*
X416010Y229553D01*
Y227220D01*
G01X417610Y225553D02*
Y230553D01*
G01Y229803D02*
X418027Y230220D01*
X418443Y230470D01*
X419110Y230553D01*
X419693Y230470D01*
X420277Y230053D01*
X420527Y229470D01*
X420610Y228887D01*
X420527Y228303D01*
X420277Y227720D01*
X419777Y227387D01*
X419110Y227220D01*
X418527Y227303D01*
X417943Y227553D01*
X417610Y227887D01*
G01X401520Y268213D02*
X403020Y264880D01*
X404520Y268213D01*
G01X408620D02*
Y264880D01*
G01Y269547D02*
X408453Y269630D01*
Y269797D01*
X408620Y269880D01*
X408787Y269797D01*
Y269630D01*
X408620Y269547D01*
G01X415720Y264880D02*
Y268213D01*
G01Y267630D02*
X415387Y267963D01*
X414887Y268130D01*
X414303Y268213D01*
X413720Y268047D01*
X413220Y267713D01*
X412887Y267213D01*
X412720Y266547D01*
X412887Y265880D01*
X413220Y265380D01*
X413720Y265047D01*
X414303Y264880D01*
X414887Y264963D01*
X415387Y265213D01*
X415720Y265547D01*
G01X401067Y277360D02*
Y282360D01*
X402733D01*
X403400Y282110D01*
X403900Y281777D01*
X404317Y281277D01*
X404650Y280693D01*
X404733Y279860D01*
X404650Y279027D01*
X404317Y278443D01*
X403900Y277943D01*
X403400Y277610D01*
X402733Y277360D01*
X401067D01*
G01X408500Y280693D02*
Y277360D01*
G01Y282027D02*
X408333Y282110D01*
Y282277D01*
X408500Y282360D01*
X408667Y282277D01*
Y282110D01*
X408500Y282027D01*
G01X411600Y277360D02*
Y280693D01*
G01Y279777D02*
X411850Y280193D01*
X412267Y280527D01*
X412850Y280693D01*
X413433Y280527D01*
X413850Y280193D01*
X414100Y279777D01*
Y277360D01*
G01Y279777D02*
X414350Y280193D01*
X414767Y280527D01*
X415350Y280693D01*
X415933Y280527D01*
X416350Y280193D01*
X416600Y279693D01*
Y277360D01*
G01X418200Y275693D02*
Y280693D01*
G01Y279943D02*
X418617Y280360D01*
X419033Y280610D01*
X419700Y280693D01*
X420283Y280610D01*
X420867Y280193D01*
X421117Y279610D01*
X421200Y279027D01*
X421117Y278443D01*
X420867Y277860D01*
X420367Y277527D01*
X419700Y277360D01*
X419117Y277443D01*
X418533Y277693D01*
X418200Y278027D01*
G01X425300Y277360D02*
Y282360D01*
G01X429650Y279610D02*
X432317D01*
X432067Y280193D01*
X431650Y280527D01*
X431067Y280693D01*
X430483Y280610D01*
X429983Y280360D01*
X429650Y279777D01*
X429483Y279277D01*
Y278777D01*
X429650Y278277D01*
X430067Y277777D01*
X430567Y277443D01*
X431150Y277360D01*
X431733Y277527D01*
X432317Y278027D01*
G01X441600Y277360D02*
Y281610D01*
X441767Y282027D01*
X442100Y282277D01*
X442600Y282360D01*
X443100Y282193D01*
X443350Y281777D01*
G01X442350Y280360D02*
X440683D01*
G01X447700Y277360D02*
X447200Y277443D01*
X446700Y277777D01*
X446367Y278360D01*
X446200Y279027D01*
X446367Y279693D01*
X446700Y280277D01*
X447200Y280610D01*
X447700Y280693D01*
X448200Y280610D01*
X448700Y280277D01*
X449033Y279693D01*
X449117Y279027D01*
X449033Y278360D01*
X448700Y277777D01*
X448200Y277443D01*
X447700Y277360D01*
G01X452133D02*
Y280693D01*
G01Y280027D02*
X452550Y280360D01*
X452967Y280610D01*
X453550Y280693D01*
X453967Y280610D01*
X454467Y280360D01*
G01X464500Y277360D02*
X464000Y277443D01*
X463500Y277777D01*
X463167Y278360D01*
X463000Y279027D01*
X463167Y279693D01*
X463500Y280277D01*
X464000Y280610D01*
X464500Y280693D01*
X465000Y280610D01*
X465500Y280277D01*
X465833Y279693D01*
X465917Y279027D01*
X465833Y278360D01*
X465500Y277777D01*
X465000Y277443D01*
X464500Y277360D01*
G01X468683Y280693D02*
Y278360D01*
X469017Y277777D01*
X469517Y277443D01*
X470100Y277360D01*
X470683Y277443D01*
X471183Y277777D01*
X471517Y278360D01*
G01Y277360D02*
Y280693D01*
G01X475700Y282360D02*
Y277360D01*
G01X474533Y280693D02*
X476867D01*
G01X480050Y279610D02*
X482717D01*
X482467Y280193D01*
X482050Y280527D01*
X481467Y280693D01*
X480883Y280610D01*
X480383Y280360D01*
X480050Y279777D01*
X479883Y279277D01*
Y278777D01*
X480050Y278277D01*
X480467Y277777D01*
X480967Y277443D01*
X481550Y277360D01*
X482133Y277527D01*
X482717Y278027D01*
G01X485733Y277360D02*
Y280693D01*
G01Y280027D02*
X486150Y280360D01*
X486567Y280610D01*
X487150Y280693D01*
X487567Y280610D01*
X488067Y280360D01*
G01X499600Y277360D02*
Y280693D01*
G01Y280110D02*
X499267Y280443D01*
X498767Y280610D01*
X498183Y280693D01*
X497600Y280527D01*
X497100Y280193D01*
X496767Y279693D01*
X496600Y279027D01*
X496767Y278360D01*
X497100Y277860D01*
X497600Y277527D01*
X498183Y277360D01*
X498767Y277443D01*
X499267Y277693D01*
X499600Y278027D01*
G01X502283Y277360D02*
Y280693D01*
G01Y279860D02*
X502617Y280277D01*
X503117Y280610D01*
X503783Y280693D01*
X504367Y280610D01*
X504867Y280277D01*
X505117Y279693D01*
Y277360D01*
G01X510800Y282360D02*
Y277360D01*
G01Y278110D02*
X510467Y277693D01*
X509967Y277443D01*
X509383Y277360D01*
X508717Y277527D01*
X508217Y277943D01*
X507883Y278443D01*
X507800Y279027D01*
X507883Y279610D01*
X508217Y280110D01*
X508717Y280527D01*
X509383Y280693D01*
X509967Y280610D01*
X510383Y280443D01*
X510800Y280110D01*
G01X520500Y280693D02*
Y277360D01*
G01Y282027D02*
X520333Y282110D01*
Y282277D01*
X520500Y282360D01*
X520667Y282277D01*
Y282110D01*
X520500Y282027D01*
G01X524683Y277360D02*
Y280693D01*
G01Y279860D02*
X525017Y280277D01*
X525517Y280610D01*
X526183Y280693D01*
X526767Y280610D01*
X527267Y280277D01*
X527517Y279693D01*
Y277360D01*
G01X530283D02*
Y280693D01*
G01Y279860D02*
X530617Y280277D01*
X531117Y280610D01*
X531783Y280693D01*
X532367Y280610D01*
X532867Y280277D01*
X533117Y279693D01*
Y277360D01*
G01X536050Y279610D02*
X538717D01*
X538467Y280193D01*
X538050Y280527D01*
X537467Y280693D01*
X536883Y280610D01*
X536383Y280360D01*
X536050Y279777D01*
X535883Y279277D01*
Y278777D01*
X536050Y278277D01*
X536467Y277777D01*
X536967Y277443D01*
X537550Y277360D01*
X538133Y277527D01*
X538717Y278027D01*
G01X541733Y277360D02*
Y280693D01*
G01Y280027D02*
X542150Y280360D01*
X542567Y280610D01*
X543150Y280693D01*
X543567Y280610D01*
X544067Y280360D01*
G01X554100Y277360D02*
Y282360D01*
G01X561200Y277360D02*
Y280693D01*
G01Y280110D02*
X560867Y280443D01*
X560367Y280610D01*
X559783Y280693D01*
X559200Y280527D01*
X558700Y280193D01*
X558367Y279693D01*
X558200Y279027D01*
X558367Y278360D01*
X558700Y277860D01*
X559200Y277527D01*
X559783Y277360D01*
X560367Y277443D01*
X560867Y277693D01*
X561200Y278027D01*
G01X564050Y277943D02*
X564467Y277610D01*
X565050Y277360D01*
X565550D01*
X566050Y277527D01*
X566383Y277777D01*
X566550Y278110D01*
X566467Y278610D01*
X566133Y278860D01*
X564633Y279360D01*
X564300Y279943D01*
X564467Y280360D01*
X564800Y280610D01*
X565300Y280693D01*
X565800Y280610D01*
X566300Y280360D01*
G01X569650Y279610D02*
X572317D01*
X572067Y280193D01*
X571650Y280527D01*
X571067Y280693D01*
X570483Y280610D01*
X569983Y280360D01*
X569650Y279777D01*
X569483Y279277D01*
Y278777D01*
X569650Y278277D01*
X570067Y277777D01*
X570567Y277443D01*
X571150Y277360D01*
X571733Y277527D01*
X572317Y278027D01*
G01X575333Y277360D02*
Y280693D01*
G01Y280027D02*
X575750Y280360D01*
X576167Y280610D01*
X576750Y280693D01*
X577167Y280610D01*
X577667Y280360D01*
G01X401827Y295540D02*
X403910Y300540D01*
X405993Y295540D01*
G01X405243Y297290D02*
X402577D01*
G01X408093Y295540D02*
Y298873D01*
G01Y298040D02*
X408427Y298457D01*
X408927Y298790D01*
X409593Y298873D01*
X410177Y298790D01*
X410677Y298457D01*
X410927Y297873D01*
Y295540D01*
G01X413943Y294290D02*
X414527Y293957D01*
X415193Y293873D01*
X415777Y293957D01*
X416277Y294373D01*
X416610Y294957D01*
Y298873D01*
G01Y298207D02*
X416277Y298540D01*
X415777Y298790D01*
X415193Y298873D01*
X414527Y298707D01*
X414110Y298373D01*
X413777Y297790D01*
X413610Y297207D01*
X413693Y296707D01*
X414027Y296123D01*
X414527Y295707D01*
X415193Y295540D01*
X415693Y295623D01*
X416277Y295957D01*
X416610Y296290D01*
G01X420710Y295540D02*
Y300540D01*
G01X425060Y297790D02*
X427727D01*
X427477Y298373D01*
X427060Y298707D01*
X426477Y298873D01*
X425893Y298790D01*
X425393Y298540D01*
X425060Y297957D01*
X424893Y297457D01*
Y296957D01*
X425060Y296457D01*
X425477Y295957D01*
X425977Y295623D01*
X426560Y295540D01*
X427143Y295707D01*
X427727Y296207D01*
G01X431493Y293873D02*
X430660Y294707D01*
X430243Y295540D01*
Y298873D01*
X430660Y299707D01*
X431493Y300540D01*
G01X449127Y293873D02*
X449960Y294707D01*
X450377Y295540D01*
Y298873D01*
X449960Y299707D01*
X449127Y300540D01*
G01X395000Y305500D02*
X694500D01*
G01X401777Y331927D02*
X402110Y332177D01*
X402360Y332593D01*
X402527Y333177D01*
X402360Y333677D01*
X402027Y334010D01*
X401443Y334260D01*
X399193D01*
Y329260D01*
X401943D01*
X402527Y329593D01*
X402860Y330093D01*
X403027Y330677D01*
X402860Y331260D01*
X402360Y331760D01*
X401777Y331927D01*
X399193D01*
G01X405210Y329093D02*
X408210Y334260D01*
G01X410227Y329260D02*
X412310Y334260D01*
X414393Y329260D01*
G01X413643Y331010D02*
X410977D01*
G01X400633Y358960D02*
Y353960D01*
X403967D01*
G01X409400D02*
Y357293D01*
G01Y356710D02*
X409067Y357043D01*
X408567Y357210D01*
X407983Y357293D01*
X407400Y357127D01*
X406900Y356793D01*
X406567Y356293D01*
X406400Y355627D01*
X406567Y354960D01*
X406900Y354460D01*
X407400Y354127D01*
X407983Y353960D01*
X408567Y354043D01*
X409067Y354293D01*
X409400Y354627D01*
G01X412250Y354543D02*
X412667Y354210D01*
X413250Y353960D01*
X413750D01*
X414250Y354127D01*
X414583Y354377D01*
X414750Y354710D01*
X414667Y355210D01*
X414333Y355460D01*
X412833Y355960D01*
X412500Y356543D01*
X412667Y356960D01*
X413000Y357210D01*
X413500Y357293D01*
X414000Y357210D01*
X414500Y356960D01*
G01X417850Y356210D02*
X420517D01*
X420267Y356793D01*
X419850Y357127D01*
X419267Y357293D01*
X418683Y357210D01*
X418183Y356960D01*
X417850Y356377D01*
X417683Y355877D01*
Y355377D01*
X417850Y354877D01*
X418267Y354377D01*
X418767Y354043D01*
X419350Y353960D01*
X419933Y354127D01*
X420517Y354627D01*
G01X423533Y353960D02*
Y357293D01*
G01Y356627D02*
X423950Y356960D01*
X424367Y357210D01*
X424950Y357293D01*
X425367Y357210D01*
X425867Y356960D01*
G01X434400Y357293D02*
X435900Y353960D01*
X437400Y357293D01*
G01X441500D02*
Y353960D01*
G01Y358627D02*
X441333Y358710D01*
Y358877D01*
X441500Y358960D01*
X441667Y358877D01*
Y358710D01*
X441500Y358627D01*
G01X448600Y353960D02*
Y357293D01*
G01Y356710D02*
X448267Y357043D01*
X447767Y357210D01*
X447183Y357293D01*
X446600Y357127D01*
X446100Y356793D01*
X445767Y356293D01*
X445600Y355627D01*
X445767Y354960D01*
X446100Y354460D01*
X446600Y354127D01*
X447183Y353960D01*
X447767Y354043D01*
X448267Y354293D01*
X448600Y354627D01*
G01X457050Y354543D02*
X457467Y354210D01*
X458050Y353960D01*
X458550D01*
X459050Y354127D01*
X459383Y354377D01*
X459550Y354710D01*
X459467Y355210D01*
X459133Y355460D01*
X457633Y355960D01*
X457300Y356543D01*
X457467Y356960D01*
X457800Y357210D01*
X458300Y357293D01*
X458800Y357210D01*
X459300Y356960D01*
G01X463900Y357293D02*
Y353960D01*
G01Y358627D02*
X463733Y358710D01*
Y358877D01*
X463900Y358960D01*
X464067Y358877D01*
Y358710D01*
X463900Y358627D01*
G01X468250Y357293D02*
X470750D01*
X468250Y353960D01*
X470750D01*
G01X473850Y356210D02*
X476517D01*
X476267Y356793D01*
X475850Y357127D01*
X475267Y357293D01*
X474683Y357210D01*
X474183Y356960D01*
X473850Y356377D01*
X473683Y355877D01*
Y355377D01*
X473850Y354877D01*
X474267Y354377D01*
X474767Y354043D01*
X475350Y353960D01*
X475933Y354127D01*
X476517Y354627D01*
G01X484217Y357293D02*
X485217Y353960D01*
X486300Y357293D01*
X487383Y353960D01*
X488383Y357293D01*
G01X491900D02*
Y353960D01*
G01Y358627D02*
X491733Y358710D01*
Y358877D01*
X491900Y358960D01*
X492067Y358877D01*
Y358710D01*
X491900Y358627D01*
G01X497500Y358960D02*
Y353960D01*
G01X496333Y357293D02*
X498667D01*
G01X501683Y353960D02*
Y358960D01*
G01Y356543D02*
X502100Y356960D01*
X502517Y357210D01*
X503183Y357293D01*
X503683Y357210D01*
X504267Y356877D01*
X504517Y356377D01*
Y353960D01*
G01X508700D02*
X508200Y354043D01*
X507700Y354377D01*
X507367Y354960D01*
X507200Y355627D01*
X507367Y356293D01*
X507700Y356877D01*
X508200Y357210D01*
X508700Y357293D01*
X509200Y357210D01*
X509700Y356877D01*
X510033Y356293D01*
X510117Y355627D01*
X510033Y354960D01*
X509700Y354377D01*
X509200Y354043D01*
X508700Y353960D01*
G01X512883Y357293D02*
Y354960D01*
X513217Y354377D01*
X513717Y354043D01*
X514300Y353960D01*
X514883Y354043D01*
X515383Y354377D01*
X515717Y354960D01*
G01Y353960D02*
Y357293D01*
G01X519900Y358960D02*
Y353960D01*
G01X518733Y357293D02*
X521067D01*
G01X529600Y352293D02*
Y357293D01*
G01Y356543D02*
X530017Y356960D01*
X530433Y357210D01*
X531100Y357293D01*
X531683Y357210D01*
X532267Y356793D01*
X532517Y356210D01*
X532600Y355627D01*
X532517Y355043D01*
X532267Y354460D01*
X531767Y354127D01*
X531100Y353960D01*
X530517Y354043D01*
X529933Y354293D01*
X529600Y354627D01*
G01X536700Y353960D02*
Y358960D01*
G01X543800Y353960D02*
Y357293D01*
G01Y356710D02*
X543467Y357043D01*
X542967Y357210D01*
X542383Y357293D01*
X541800Y357127D01*
X541300Y356793D01*
X540967Y356293D01*
X540800Y355627D01*
X540967Y354960D01*
X541300Y354460D01*
X541800Y354127D01*
X542383Y353960D01*
X542967Y354043D01*
X543467Y354293D01*
X543800Y354627D01*
G01X547900Y358960D02*
Y353960D01*
G01X546733Y357293D02*
X549067D01*
G01X553500D02*
Y353960D01*
G01Y358627D02*
X553333Y358710D01*
Y358877D01*
X553500Y358960D01*
X553667Y358877D01*
Y358710D01*
X553500Y358627D01*
G01X557683Y353960D02*
Y357293D01*
G01Y356460D02*
X558017Y356877D01*
X558517Y357210D01*
X559183Y357293D01*
X559767Y357210D01*
X560267Y356877D01*
X560517Y356293D01*
Y353960D01*
G01X563533Y352710D02*
X564117Y352377D01*
X564783Y352293D01*
X565367Y352377D01*
X565867Y352793D01*
X566200Y353377D01*
Y357293D01*
G01Y356627D02*
X565867Y356960D01*
X565367Y357210D01*
X564783Y357293D01*
X564117Y357127D01*
X563700Y356793D01*
X563367Y356210D01*
X563200Y355627D01*
X563283Y355127D01*
X563617Y354543D01*
X564117Y354127D01*
X564783Y353960D01*
X565283Y354043D01*
X565867Y354377D01*
X566200Y354710D01*
G01X575483Y352293D02*
X574650Y353127D01*
X574233Y353960D01*
Y357293D01*
X574650Y358127D01*
X575483Y358960D01*
G01X582167Y356627D02*
X582500Y356877D01*
X582750Y357293D01*
X582917Y357877D01*
X582750Y358377D01*
X582417Y358710D01*
X581833Y358960D01*
X579583D01*
Y353960D01*
X582333D01*
X582917Y354293D01*
X583250Y354793D01*
X583417Y355377D01*
X583250Y355960D01*
X582750Y356460D01*
X582167Y356627D01*
X579583D01*
G01X587517Y352293D02*
X588350Y353127D01*
X588767Y353960D01*
Y357293D01*
X588350Y358127D01*
X587517Y358960D01*
G01X395000Y337500D02*
X694500D01*
G01X404500Y666833D02*
Y663500D01*
G01Y668167D02*
X404333Y668250D01*
Y668417D01*
X404500Y668500D01*
X404667Y668417D01*
Y668250D01*
X404500Y668167D01*
G01X410100Y668500D02*
Y663500D01*
G01X408933Y666833D02*
X411267D01*
G01X414450Y665750D02*
X417117D01*
X416867Y666333D01*
X416450Y666667D01*
X415867Y666833D01*
X415283Y666750D01*
X414783Y666500D01*
X414450Y665917D01*
X414283Y665417D01*
Y664917D01*
X414450Y664417D01*
X414867Y663917D01*
X415367Y663583D01*
X415950Y663500D01*
X416533Y663667D01*
X417117Y664167D01*
G01X418800Y663500D02*
Y666833D01*
G01Y665917D02*
X419050Y666333D01*
X419467Y666667D01*
X420050Y666833D01*
X420633Y666667D01*
X421050Y666333D01*
X421300Y665917D01*
Y663500D01*
G01Y665917D02*
X421550Y666333D01*
X421967Y666667D01*
X422550Y666833D01*
X423133Y666667D01*
X423550Y666333D01*
X423800Y665833D01*
Y663500D01*
G01X444197Y299927D02*
X443797Y300127D01*
X443330Y300260D01*
X442797D01*
X442197Y300060D01*
X441730Y299727D01*
X441397Y299327D01*
X441130Y298660D01*
X441063Y298060D01*
X441197Y297460D01*
X441397Y297060D01*
X441797Y296660D01*
X442263Y296393D01*
X442730Y296260D01*
X443197D01*
X443663Y296393D01*
X444063Y296593D01*
X444397Y296860D01*
G01X607500Y-28500D02*
X606833Y-28667D01*
X606333Y-29083D01*
X606000Y-29583D01*
X605750Y-30250D01*
X605667Y-31000D01*
X605750Y-31750D01*
X606000Y-32417D01*
X606333Y-32917D01*
X606833Y-33333D01*
X607500Y-33500D01*
X608167Y-33333D01*
X608667Y-32917D01*
X609000Y-32417D01*
X609250Y-31750D01*
X609333Y-31000D01*
X609250Y-30250D01*
X609000Y-29583D01*
X608667Y-29083D01*
X608167Y-28667D01*
X607500Y-28500D01*
G01X613100Y-33667D02*
X612933Y-33583D01*
Y-33417D01*
X613100Y-33333D01*
X613267Y-33417D01*
Y-33583D01*
X613100Y-33667D01*
G01X616867Y-32500D02*
X617367Y-33083D01*
X618033Y-33417D01*
X618783Y-33500D01*
X619450Y-33417D01*
X620117Y-33000D01*
X620533Y-32500D01*
X620617Y-32000D01*
X620450Y-31417D01*
X619867Y-31000D01*
X619283Y-30833D01*
X618533D01*
G01X619283D02*
X619783Y-30583D01*
X620200Y-30167D01*
X620367Y-29667D01*
X620200Y-29167D01*
X619783Y-28750D01*
X619033Y-28500D01*
X618283Y-28583D01*
X617533Y-28917D01*
G01X621800Y-31833D02*
X622633Y-30167D01*
X623467D01*
X625133Y-33500D01*
X625967D01*
X626800Y-31833D01*
G01X629900Y-28500D02*
X629233Y-28667D01*
X628733Y-29083D01*
X628400Y-29583D01*
X628150Y-30250D01*
X628067Y-31000D01*
X628150Y-31750D01*
X628400Y-32417D01*
X628733Y-32917D01*
X629233Y-33333D01*
X629900Y-33500D01*
X630567Y-33333D01*
X631067Y-32917D01*
X631400Y-32417D01*
X631650Y-31750D01*
X631733Y-31000D01*
X631650Y-30250D01*
X631400Y-29583D01*
X631067Y-29083D01*
X630567Y-28667D01*
X629900Y-28500D01*
G01X635500Y-33667D02*
X635333Y-33583D01*
Y-33417D01*
X635500Y-33333D01*
X635667Y-33417D01*
Y-33583D01*
X635500Y-33667D01*
G01X640933Y-33500D02*
X641100Y-32417D01*
X641350Y-31500D01*
X641683Y-30667D01*
X642100Y-29750D01*
X642767Y-28500D01*
X639433D01*
G01X644200Y-33500D02*
Y-30167D01*
G01Y-31083D02*
X644450Y-30667D01*
X644867Y-30333D01*
X645450Y-30167D01*
X646033Y-30333D01*
X646450Y-30667D01*
X646700Y-31083D01*
Y-33500D01*
G01Y-31083D02*
X646950Y-30667D01*
X647367Y-30333D01*
X647950Y-30167D01*
X648533Y-30333D01*
X648950Y-30667D01*
X649200Y-31167D01*
Y-33500D01*
G01X652300Y-30167D02*
Y-33500D01*
G01Y-28833D02*
X652133Y-28750D01*
Y-28583D01*
X652300Y-28500D01*
X652467Y-28583D01*
Y-28750D01*
X652300Y-28833D01*
G01X657900Y-33500D02*
Y-28500D01*
G01X609167Y-48500D02*
X605833Y-46833D01*
X609167Y-45167D01*
G01X612017Y-47583D02*
X614183D01*
G01Y-46083D02*
X612017D01*
G01X618700Y-48500D02*
Y-43500D01*
X617700Y-44500D01*
G01Y-48500D02*
X619700D01*
G01X624300Y-48667D02*
X624133Y-48583D01*
Y-48417D01*
X624300Y-48333D01*
X624467Y-48417D01*
Y-48583D01*
X624300Y-48667D01*
G01X630900Y-48500D02*
Y-43500D01*
X627817Y-47083D01*
X631983D01*
G01X633000Y-48500D02*
Y-45167D01*
G01Y-46083D02*
X633250Y-45667D01*
X633667Y-45333D01*
X634250Y-45167D01*
X634833Y-45333D01*
X635250Y-45667D01*
X635500Y-46083D01*
Y-48500D01*
G01Y-46083D02*
X635750Y-45667D01*
X636167Y-45333D01*
X636750Y-45167D01*
X637333Y-45333D01*
X637750Y-45667D01*
X638000Y-46167D01*
Y-48500D01*
G01X641100Y-45167D02*
Y-48500D01*
G01Y-43833D02*
X640933Y-43750D01*
Y-43583D01*
X641100Y-43500D01*
X641267Y-43583D01*
Y-43750D01*
X641100Y-43833D01*
G01X646700Y-48500D02*
Y-43500D01*
G01X605333Y-65000D02*
Y-60000D01*
X607500Y-64167D01*
X609667Y-60000D01*
Y-65000D01*
G01X611683Y-61667D02*
Y-64000D01*
X612017Y-64583D01*
X612517Y-64917D01*
X613100Y-65000D01*
X613683Y-64917D01*
X614183Y-64583D01*
X614517Y-64000D01*
G01Y-65000D02*
Y-61667D01*
G01X617450Y-64417D02*
X617867Y-64750D01*
X618450Y-65000D01*
X618950D01*
X619450Y-64833D01*
X619783Y-64583D01*
X619950Y-64250D01*
X619867Y-63750D01*
X619533Y-63500D01*
X618033Y-63000D01*
X617700Y-62417D01*
X617867Y-62000D01*
X618200Y-61750D01*
X618700Y-61667D01*
X619200Y-61750D01*
X619700Y-62000D01*
G01X624300Y-60000D02*
Y-65000D01*
G01X623133Y-61667D02*
X625467D01*
G01X635000Y-65000D02*
Y-60750D01*
X635167Y-60333D01*
X635500Y-60083D01*
X636000Y-60000D01*
X636500Y-60167D01*
X636750Y-60583D01*
G01X635750Y-62000D02*
X634083D01*
G01X641100Y-65000D02*
X640600Y-64917D01*
X640100Y-64583D01*
X639767Y-64000D01*
X639600Y-63333D01*
X639767Y-62667D01*
X640100Y-62083D01*
X640600Y-61750D01*
X641100Y-61667D01*
X641600Y-61750D01*
X642100Y-62083D01*
X642433Y-62667D01*
X642517Y-63333D01*
X642433Y-64000D01*
X642100Y-64583D01*
X641600Y-64917D01*
X641100Y-65000D01*
G01X646700D02*
Y-60000D01*
G01X652300Y-65000D02*
Y-60000D01*
G01X657900Y-65000D02*
X657400Y-64917D01*
X656900Y-64583D01*
X656567Y-64000D01*
X656400Y-63333D01*
X656567Y-62667D01*
X656900Y-62083D01*
X657400Y-61750D01*
X657900Y-61667D01*
X658400Y-61750D01*
X658900Y-62083D01*
X659233Y-62667D01*
X659317Y-63333D01*
X659233Y-64000D01*
X658900Y-64583D01*
X658400Y-64917D01*
X657900Y-65000D01*
G01X661417Y-61667D02*
X662417Y-65000D01*
X663500Y-61667D01*
X664583Y-65000D01*
X665583Y-61667D01*
G01X595500Y-69500D02*
Y438000D01*
G01X606583Y-1833D02*
X608583D01*
G01X607500Y-750D02*
Y-2917D01*
G01X611600Y-3667D02*
X614600Y1500D01*
G01X617617Y-1833D02*
X619783D01*
G01X624300Y-3500D02*
Y1500D01*
X623300Y500D01*
G01Y-3500D02*
X625300D01*
G01X627400D02*
Y-167D01*
G01Y-1083D02*
X627650Y-667D01*
X628067Y-333D01*
X628650Y-167D01*
X629233Y-333D01*
X629650Y-667D01*
X629900Y-1083D01*
Y-3500D01*
G01Y-1083D02*
X630150Y-667D01*
X630567Y-333D01*
X631150Y-167D01*
X631733Y-333D01*
X632150Y-667D01*
X632400Y-1167D01*
Y-3500D01*
G01X635500Y-167D02*
Y-3500D01*
G01Y1167D02*
X635333Y1250D01*
Y1417D01*
X635500Y1500D01*
X635667Y1417D01*
Y1250D01*
X635500Y1167D01*
G01X641100Y-3500D02*
Y1500D01*
G01X607500Y-15000D02*
X606833Y-15167D01*
X606333Y-15583D01*
X606000Y-16083D01*
X605750Y-16750D01*
X605667Y-17500D01*
X605750Y-18250D01*
X606000Y-18917D01*
X606333Y-19417D01*
X606833Y-19833D01*
X607500Y-20000D01*
X608167Y-19833D01*
X608667Y-19417D01*
X609000Y-18917D01*
X609250Y-18250D01*
X609333Y-17500D01*
X609250Y-16750D01*
X609000Y-16083D01*
X608667Y-15583D01*
X608167Y-15167D01*
X607500Y-15000D01*
G01X613100Y-20167D02*
X612933Y-20083D01*
Y-19917D01*
X613100Y-19833D01*
X613267Y-19917D01*
Y-20083D01*
X613100Y-20167D01*
G01X616867Y-19000D02*
X617367Y-19583D01*
X618033Y-19917D01*
X618783Y-20000D01*
X619450Y-19917D01*
X620117Y-19500D01*
X620533Y-19000D01*
X620617Y-18500D01*
X620450Y-17917D01*
X619867Y-17500D01*
X619283Y-17333D01*
X618533D01*
G01X619283D02*
X619783Y-17083D01*
X620200Y-16667D01*
X620367Y-16167D01*
X620200Y-15667D01*
X619783Y-15250D01*
X619033Y-15000D01*
X618283Y-15083D01*
X617533Y-15417D01*
G01X621800Y-18333D02*
X622633Y-16667D01*
X623467D01*
X625133Y-20000D01*
X625967D01*
X626800Y-18333D01*
G01X629900Y-15000D02*
X629233Y-15167D01*
X628733Y-15583D01*
X628400Y-16083D01*
X628150Y-16750D01*
X628067Y-17500D01*
X628150Y-18250D01*
X628400Y-18917D01*
X628733Y-19417D01*
X629233Y-19833D01*
X629900Y-20000D01*
X630567Y-19833D01*
X631067Y-19417D01*
X631400Y-18917D01*
X631650Y-18250D01*
X631733Y-17500D01*
X631650Y-16750D01*
X631400Y-16083D01*
X631067Y-15583D01*
X630567Y-15167D01*
X629900Y-15000D01*
G01X635500Y-20167D02*
X635333Y-20083D01*
Y-19917D01*
X635500Y-19833D01*
X635667Y-19917D01*
Y-20083D01*
X635500Y-20167D01*
G01X640933Y-20000D02*
X641100Y-18917D01*
X641350Y-18000D01*
X641683Y-17167D01*
X642100Y-16250D01*
X642767Y-15000D01*
X639433D01*
G01X644200Y-20000D02*
Y-16667D01*
G01Y-17583D02*
X644450Y-17167D01*
X644867Y-16833D01*
X645450Y-16667D01*
X646033Y-16833D01*
X646450Y-17167D01*
X646700Y-17583D01*
Y-20000D01*
G01Y-17583D02*
X646950Y-17167D01*
X647367Y-16833D01*
X647950Y-16667D01*
X648533Y-16833D01*
X648950Y-17167D01*
X649200Y-17667D01*
Y-20000D01*
G01X652300Y-16667D02*
Y-20000D01*
G01Y-15333D02*
X652133Y-15250D01*
Y-15083D01*
X652300Y-15000D01*
X652467Y-15083D01*
Y-15250D01*
X652300Y-15333D01*
G01X657900Y-20000D02*
Y-15000D01*
G01X606583Y24667D02*
X608583D01*
G01X607500Y25750D02*
Y23583D01*
G01X611600Y22833D02*
X614600Y28000D01*
G01X617617Y24667D02*
X619783D01*
G01X624300Y23000D02*
Y28000D01*
X623300Y27000D01*
G01Y23000D02*
X625300D01*
G01X627400D02*
Y26333D01*
G01Y25417D02*
X627650Y25833D01*
X628067Y26167D01*
X628650Y26333D01*
X629233Y26167D01*
X629650Y25833D01*
X629900Y25417D01*
Y23000D01*
G01Y25417D02*
X630150Y25833D01*
X630567Y26167D01*
X631150Y26333D01*
X631733Y26167D01*
X632150Y25833D01*
X632400Y25333D01*
Y23000D01*
G01X635500Y26333D02*
Y23000D01*
G01Y27667D02*
X635333Y27750D01*
Y27917D01*
X635500Y28000D01*
X635667Y27917D01*
Y27750D01*
X635500Y27667D01*
G01X641100Y23000D02*
Y28000D01*
G01X606583Y13167D02*
X608583D01*
G01X607500Y14250D02*
Y12083D01*
G01X611600Y11333D02*
X614600Y16500D01*
G01X617617Y13167D02*
X619783D01*
G01X622717Y15667D02*
X623217Y16167D01*
X623800Y16417D01*
X624467Y16500D01*
X625300Y16333D01*
X625883Y15917D01*
X626050Y15417D01*
X625967Y14917D01*
X625633Y14500D01*
X623967Y13667D01*
X623217Y13083D01*
X622717Y12250D01*
X622550Y11500D01*
X626050D01*
G01X627400D02*
Y14833D01*
G01Y13917D02*
X627650Y14333D01*
X628067Y14667D01*
X628650Y14833D01*
X629233Y14667D01*
X629650Y14333D01*
X629900Y13917D01*
Y11500D01*
G01Y13917D02*
X630150Y14333D01*
X630567Y14667D01*
X631150Y14833D01*
X631733Y14667D01*
X632150Y14333D01*
X632400Y13833D01*
Y11500D01*
G01X635500Y14833D02*
Y11500D01*
G01Y16167D02*
X635333Y16250D01*
Y16417D01*
X635500Y16500D01*
X635667Y16417D01*
Y16250D01*
X635500Y16167D01*
G01X641100Y11500D02*
Y16500D01*
G01X606583Y68167D02*
X608583D01*
G01X607500Y69250D02*
Y67083D01*
G01X611600Y66333D02*
X614600Y71500D01*
G01X617617Y68167D02*
X619783D01*
G01X624300Y66500D02*
Y71500D01*
X623300Y70500D01*
G01Y66500D02*
X625300D01*
G01X628067Y67250D02*
X628567Y66833D01*
X629150Y66583D01*
X629900Y66500D01*
X630650Y66667D01*
X631233Y67000D01*
X631650Y67583D01*
X631733Y68250D01*
X631567Y68917D01*
X631150Y69333D01*
X630567Y69667D01*
X629983Y69750D01*
X629400Y69667D01*
X628650Y69333D01*
X628900Y71500D01*
X631150D01*
G01X634000Y66333D02*
X637000Y71500D01*
G01X634000D02*
X633500Y71333D01*
X633250Y71083D01*
X633083Y70583D01*
X633250Y70083D01*
X633500Y69833D01*
X634000Y69667D01*
X634500Y69833D01*
X634750Y70083D01*
X634917Y70583D01*
X634750Y71083D01*
X634500Y71333D01*
X634000Y71500D01*
G01X637000Y68167D02*
X636500Y68000D01*
X636250Y67750D01*
X636083Y67250D01*
X636250Y66750D01*
X636500Y66500D01*
X637000Y66333D01*
X637500Y66500D01*
X637750Y66750D01*
X637917Y67250D01*
X637750Y67750D01*
X637500Y68000D01*
X637000Y68167D01*
G01X606583Y48667D02*
X608583D01*
G01X607500Y49750D02*
Y47583D01*
G01X611600Y46833D02*
X614600Y52000D01*
G01X617617Y48667D02*
X619783D01*
G01X622717Y51167D02*
X623217Y51667D01*
X623800Y51917D01*
X624467Y52000D01*
X625300Y51833D01*
X625883Y51417D01*
X626050Y50917D01*
X625967Y50417D01*
X625633Y50000D01*
X623967Y49167D01*
X623217Y48583D01*
X622717Y47750D01*
X622550Y47000D01*
X626050D01*
G01X627400D02*
Y50333D01*
G01Y49417D02*
X627650Y49833D01*
X628067Y50167D01*
X628650Y50333D01*
X629233Y50167D01*
X629650Y49833D01*
X629900Y49417D01*
Y47000D01*
G01Y49417D02*
X630150Y49833D01*
X630567Y50167D01*
X631150Y50333D01*
X631733Y50167D01*
X632150Y49833D01*
X632400Y49333D01*
Y47000D01*
G01X635500Y50333D02*
Y47000D01*
G01Y51667D02*
X635333Y51750D01*
Y51917D01*
X635500Y52000D01*
X635667Y51917D01*
Y51750D01*
X635500Y51667D01*
G01X641100Y47000D02*
Y52000D01*
G01X606583Y98167D02*
X608583D01*
G01X607500Y99250D02*
Y97083D01*
G01X611600Y96333D02*
X614600Y101500D01*
G01X617617Y98167D02*
X619783D01*
G01X622717Y100667D02*
X623217Y101167D01*
X623800Y101417D01*
X624467Y101500D01*
X625300Y101333D01*
X625883Y100917D01*
X626050Y100417D01*
X625967Y99917D01*
X625633Y99500D01*
X623967Y98667D01*
X623217Y98083D01*
X622717Y97250D01*
X622550Y96500D01*
X626050D01*
G01X629900Y101500D02*
X629233Y101333D01*
X628733Y100917D01*
X628400Y100417D01*
X628150Y99750D01*
X628067Y99000D01*
X628150Y98250D01*
X628400Y97583D01*
X628733Y97083D01*
X629233Y96667D01*
X629900Y96500D01*
X630567Y96667D01*
X631067Y97083D01*
X631400Y97583D01*
X631650Y98250D01*
X631733Y99000D01*
X631650Y99750D01*
X631400Y100417D01*
X631067Y100917D01*
X630567Y101333D01*
X629900Y101500D01*
G01X634000Y96333D02*
X637000Y101500D01*
G01X634000D02*
X633500Y101333D01*
X633250Y101083D01*
X633083Y100583D01*
X633250Y100083D01*
X633500Y99833D01*
X634000Y99667D01*
X634500Y99833D01*
X634750Y100083D01*
X634917Y100583D01*
X634750Y101083D01*
X634500Y101333D01*
X634000Y101500D01*
G01X637000Y98167D02*
X636500Y98000D01*
X636250Y97750D01*
X636083Y97250D01*
X636250Y96750D01*
X636500Y96500D01*
X637000Y96333D01*
X637500Y96500D01*
X637750Y96750D01*
X637917Y97250D01*
X637750Y97750D01*
X637500Y98000D01*
X637000Y98167D01*
G01X606583Y113167D02*
X608583D01*
G01X607500Y114250D02*
Y112083D01*
G01X611600Y111333D02*
X614600Y116500D01*
G01X617617Y113167D02*
X619783D01*
G01X622467Y112500D02*
X622967Y111917D01*
X623633Y111583D01*
X624383Y111500D01*
X625050Y111583D01*
X625717Y112000D01*
X626133Y112500D01*
X626217Y113000D01*
X626050Y113583D01*
X625467Y114000D01*
X624883Y114167D01*
X624133D01*
G01X624883D02*
X625383Y114417D01*
X625800Y114833D01*
X625967Y115333D01*
X625800Y115833D01*
X625383Y116250D01*
X624633Y116500D01*
X623883Y116417D01*
X623133Y116083D01*
G01X627400Y111500D02*
Y114833D01*
G01Y113917D02*
X627650Y114333D01*
X628067Y114667D01*
X628650Y114833D01*
X629233Y114667D01*
X629650Y114333D01*
X629900Y113917D01*
Y111500D01*
G01Y113917D02*
X630150Y114333D01*
X630567Y114667D01*
X631150Y114833D01*
X631733Y114667D01*
X632150Y114333D01*
X632400Y113833D01*
Y111500D01*
G01X635500Y114833D02*
Y111500D01*
G01Y116167D02*
X635333Y116250D01*
Y116417D01*
X635500Y116500D01*
X635667Y116417D01*
Y116250D01*
X635500Y116167D01*
G01X641100Y111500D02*
Y116500D01*
G01X606583Y83167D02*
X608583D01*
G01X607500Y84250D02*
Y82083D01*
G01X611600Y81333D02*
X614600Y86500D01*
G01X617617Y83167D02*
X619783D01*
G01X624300Y81500D02*
Y86500D01*
X623300Y85500D01*
G01Y81500D02*
X625300D01*
G01X627400D02*
Y84833D01*
G01Y83917D02*
X627650Y84333D01*
X628067Y84667D01*
X628650Y84833D01*
X629233Y84667D01*
X629650Y84333D01*
X629900Y83917D01*
Y81500D01*
G01Y83917D02*
X630150Y84333D01*
X630567Y84667D01*
X631150Y84833D01*
X631733Y84667D01*
X632150Y84333D01*
X632400Y83833D01*
Y81500D01*
G01X635500Y84833D02*
Y81500D01*
G01Y86167D02*
X635333Y86250D01*
Y86417D01*
X635500Y86500D01*
X635667Y86417D01*
Y86250D01*
X635500Y86167D01*
G01X641100Y81500D02*
Y86500D01*
G01X605833Y166500D02*
X609167Y168167D01*
X605833Y169833D01*
G01X612017Y167417D02*
X614183D01*
G01Y168917D02*
X612017D01*
G01X618700Y166500D02*
Y171500D01*
X617700Y170500D01*
G01Y166500D02*
X619700D01*
G01X624300Y166333D02*
X624133Y166417D01*
Y166583D01*
X624300Y166667D01*
X624467Y166583D01*
Y166417D01*
X624300Y166333D01*
G01X628067Y167500D02*
X628567Y166917D01*
X629233Y166583D01*
X629983Y166500D01*
X630650Y166583D01*
X631317Y167000D01*
X631733Y167500D01*
X631817Y168000D01*
X631650Y168583D01*
X631067Y169000D01*
X630483Y169167D01*
X629733D01*
G01X630483D02*
X630983Y169417D01*
X631400Y169833D01*
X631567Y170333D01*
X631400Y170833D01*
X630983Y171250D01*
X630233Y171500D01*
X629483Y171417D01*
X628733Y171083D01*
G01X633000Y166500D02*
Y169833D01*
G01Y168917D02*
X633250Y169333D01*
X633667Y169667D01*
X634250Y169833D01*
X634833Y169667D01*
X635250Y169333D01*
X635500Y168917D01*
Y166500D01*
G01Y168917D02*
X635750Y169333D01*
X636167Y169667D01*
X636750Y169833D01*
X637333Y169667D01*
X637750Y169333D01*
X638000Y168833D01*
Y166500D01*
G01X641100Y169833D02*
Y166500D01*
G01Y171167D02*
X640933Y171250D01*
Y171417D01*
X641100Y171500D01*
X641267Y171417D01*
Y171250D01*
X641100Y171167D01*
G01X646700Y166500D02*
Y171500D01*
G01X605833Y144000D02*
X609167Y145667D01*
X605833Y147333D01*
G01X612017Y144917D02*
X614183D01*
G01Y146417D02*
X612017D01*
G01X618700Y144000D02*
Y149000D01*
X617700Y148000D01*
G01Y144000D02*
X619700D01*
G01X624300Y143833D02*
X624133Y143917D01*
Y144083D01*
X624300Y144167D01*
X624467Y144083D01*
Y143917D01*
X624300Y143833D01*
G01X628067Y144750D02*
X628567Y144333D01*
X629150Y144083D01*
X629900Y144000D01*
X630650Y144167D01*
X631233Y144500D01*
X631650Y145083D01*
X631733Y145750D01*
X631567Y146417D01*
X631150Y146833D01*
X630567Y147167D01*
X629983Y147250D01*
X629400Y147167D01*
X628650Y146833D01*
X628900Y149000D01*
X631150D01*
G01X633000Y144000D02*
Y147333D01*
G01Y146417D02*
X633250Y146833D01*
X633667Y147167D01*
X634250Y147333D01*
X634833Y147167D01*
X635250Y146833D01*
X635500Y146417D01*
Y144000D01*
G01Y146417D02*
X635750Y146833D01*
X636167Y147167D01*
X636750Y147333D01*
X637333Y147167D01*
X637750Y146833D01*
X638000Y146333D01*
Y144000D01*
G01X641100Y147333D02*
Y144000D01*
G01Y148667D02*
X640933Y148750D01*
Y148917D01*
X641100Y149000D01*
X641267Y148917D01*
Y148750D01*
X641100Y148667D01*
G01X646700Y144000D02*
Y149000D01*
G01X605833Y126500D02*
X609167Y128167D01*
X605833Y129833D01*
G01X612017Y127417D02*
X614183D01*
G01Y128917D02*
X612017D01*
G01X618700Y126500D02*
Y131500D01*
X617700Y130500D01*
G01Y126500D02*
X619700D01*
G01X624300Y126333D02*
X624133Y126417D01*
Y126583D01*
X624300Y126667D01*
X624467Y126583D01*
Y126417D01*
X624300Y126333D01*
G01X629900Y131500D02*
X629233Y131333D01*
X628733Y130917D01*
X628400Y130417D01*
X628150Y129750D01*
X628067Y129000D01*
X628150Y128250D01*
X628400Y127583D01*
X628733Y127083D01*
X629233Y126667D01*
X629900Y126500D01*
X630567Y126667D01*
X631067Y127083D01*
X631400Y127583D01*
X631650Y128250D01*
X631733Y129000D01*
X631650Y129750D01*
X631400Y130417D01*
X631067Y130917D01*
X630567Y131333D01*
X629900Y131500D01*
G01X633000Y126500D02*
Y129833D01*
G01Y128917D02*
X633250Y129333D01*
X633667Y129667D01*
X634250Y129833D01*
X634833Y129667D01*
X635250Y129333D01*
X635500Y128917D01*
Y126500D01*
G01Y128917D02*
X635750Y129333D01*
X636167Y129667D01*
X636750Y129833D01*
X637333Y129667D01*
X637750Y129333D01*
X638000Y128833D01*
Y126500D01*
G01X641100Y129833D02*
Y126500D01*
G01Y131167D02*
X640933Y131250D01*
Y131417D01*
X641100Y131500D01*
X641267Y131417D01*
Y131250D01*
X641100Y131167D01*
G01X646700Y126500D02*
Y131500D01*
G01X612977Y200490D02*
X609643Y202157D01*
X612977Y203823D01*
G01X616910Y205490D02*
X616243Y205323D01*
X615743Y204907D01*
X615410Y204407D01*
X615160Y203740D01*
X615077Y202990D01*
X615160Y202240D01*
X615410Y201573D01*
X615743Y201073D01*
X616243Y200657D01*
X616910Y200490D01*
X617577Y200657D01*
X618077Y201073D01*
X618410Y201573D01*
X618660Y202240D01*
X618743Y202990D01*
X618660Y203740D01*
X618410Y204407D01*
X618077Y204907D01*
X617577Y205323D01*
X616910Y205490D01*
G01X622510Y200323D02*
X622343Y200407D01*
Y200573D01*
X622510Y200657D01*
X622677Y200573D01*
Y200407D01*
X622510Y200323D01*
G01X626277Y201490D02*
X626777Y200907D01*
X627443Y200573D01*
X628193Y200490D01*
X628860Y200573D01*
X629527Y200990D01*
X629943Y201490D01*
X630027Y201990D01*
X629860Y202573D01*
X629277Y202990D01*
X628693Y203157D01*
X627943D01*
G01X628693D02*
X629193Y203407D01*
X629610Y203823D01*
X629777Y204323D01*
X629610Y204823D01*
X629193Y205240D01*
X628443Y205490D01*
X627693Y205407D01*
X626943Y205073D01*
G01X631210Y200490D02*
Y203823D01*
G01Y202907D02*
X631460Y203323D01*
X631877Y203657D01*
X632460Y203823D01*
X633043Y203657D01*
X633460Y203323D01*
X633710Y202907D01*
Y200490D01*
G01Y202907D02*
X633960Y203323D01*
X634377Y203657D01*
X634960Y203823D01*
X635543Y203657D01*
X635960Y203323D01*
X636210Y202823D01*
Y200490D01*
G01X639310Y203823D02*
Y200490D01*
G01Y205157D02*
X639143Y205240D01*
Y205407D01*
X639310Y205490D01*
X639477Y205407D01*
Y205240D01*
X639310Y205157D01*
G01X644910Y200490D02*
Y205490D01*
G01X612377Y255680D02*
X609043Y257347D01*
X612377Y259013D01*
G01X616310Y255680D02*
Y260680D01*
X615310Y259680D01*
G01Y255680D02*
X617310D01*
G01X619410D02*
Y259013D01*
G01Y258097D02*
X619660Y258513D01*
X620077Y258847D01*
X620660Y259013D01*
X621243Y258847D01*
X621660Y258513D01*
X621910Y258097D01*
Y255680D01*
G01Y258097D02*
X622160Y258513D01*
X622577Y258847D01*
X623160Y259013D01*
X623743Y258847D01*
X624160Y258513D01*
X624410Y258013D01*
Y255680D01*
G01X627510Y259013D02*
Y255680D01*
G01Y260347D02*
X627343Y260430D01*
Y260597D01*
X627510Y260680D01*
X627677Y260597D01*
Y260430D01*
X627510Y260347D01*
G01X633110Y255680D02*
Y260680D01*
G01X602120Y310470D02*
Y313803D01*
G01Y312887D02*
X602370Y313303D01*
X602787Y313637D01*
X603370Y313803D01*
X603953Y313637D01*
X604370Y313303D01*
X604620Y312887D01*
Y310470D01*
G01Y312887D02*
X604870Y313303D01*
X605287Y313637D01*
X605870Y313803D01*
X606453Y313637D01*
X606870Y313303D01*
X607120Y312803D01*
Y310470D01*
G01X608803Y313803D02*
Y311470D01*
X609137Y310887D01*
X609637Y310553D01*
X610220Y310470D01*
X610803Y310553D01*
X611303Y310887D01*
X611637Y311470D01*
G01Y310470D02*
Y313803D01*
G01X614570Y311053D02*
X614987Y310720D01*
X615570Y310470D01*
X616070D01*
X616570Y310637D01*
X616903Y310887D01*
X617070Y311220D01*
X616987Y311720D01*
X616653Y311970D01*
X615153Y312470D01*
X614820Y313053D01*
X614987Y313470D01*
X615320Y313720D01*
X615820Y313803D01*
X616320Y313720D01*
X616820Y313470D01*
G01X621420Y315470D02*
Y310470D01*
G01X620253Y313803D02*
X622587D01*
G01X628687Y310470D02*
X625353Y312137D01*
X628687Y313803D01*
G01X630537Y310470D02*
X632620Y315470D01*
X634703Y310470D01*
G01X633953Y312220D02*
X631287D01*
G01X645320Y315470D02*
Y310470D01*
G01Y311220D02*
X644987Y310803D01*
X644487Y310553D01*
X643903Y310470D01*
X643237Y310637D01*
X642737Y311053D01*
X642403Y311553D01*
X642320Y312137D01*
X642403Y312720D01*
X642737Y313220D01*
X643237Y313637D01*
X643903Y313803D01*
X644487Y313720D01*
X644903Y313553D01*
X645320Y313220D01*
G01X649420Y313803D02*
Y310470D01*
G01Y315137D02*
X649253Y315220D01*
Y315387D01*
X649420Y315470D01*
X649587Y315387D01*
Y315220D01*
X649420Y315137D01*
G01X656520Y310470D02*
Y313803D01*
G01Y313220D02*
X656187Y313553D01*
X655687Y313720D01*
X655103Y313803D01*
X654520Y313637D01*
X654020Y313303D01*
X653687Y312803D01*
X653520Y312137D01*
X653687Y311470D01*
X654020Y310970D01*
X654520Y310637D01*
X655103Y310470D01*
X655687Y310553D01*
X656187Y310803D01*
X656520Y311137D01*
G01X658120Y310470D02*
Y313803D01*
G01Y312887D02*
X658370Y313303D01*
X658787Y313637D01*
X659370Y313803D01*
X659953Y313637D01*
X660370Y313303D01*
X660620Y312887D01*
Y310470D01*
G01Y312887D02*
X660870Y313303D01*
X661287Y313637D01*
X661870Y313803D01*
X662453Y313637D01*
X662870Y313303D01*
X663120Y312803D01*
Y310470D01*
G01X664970Y312720D02*
X667637D01*
X667387Y313303D01*
X666970Y313637D01*
X666387Y313803D01*
X665803Y313720D01*
X665303Y313470D01*
X664970Y312887D01*
X664803Y312387D01*
Y311887D01*
X664970Y311387D01*
X665387Y310887D01*
X665887Y310553D01*
X666470Y310470D01*
X667053Y310637D01*
X667637Y311137D01*
G01X671820Y315470D02*
Y310470D01*
G01X670653Y313803D02*
X672987D01*
G01X676170Y312720D02*
X678837D01*
X678587Y313303D01*
X678170Y313637D01*
X677587Y313803D01*
X677003Y313720D01*
X676503Y313470D01*
X676170Y312887D01*
X676003Y312387D01*
Y311887D01*
X676170Y311387D01*
X676587Y310887D01*
X677087Y310553D01*
X677670Y310470D01*
X678253Y310637D01*
X678837Y311137D01*
G01X681853Y310470D02*
Y313803D01*
G01Y313137D02*
X682270Y313470D01*
X682687Y313720D01*
X683270Y313803D01*
X683687Y313720D01*
X684187Y313470D01*
G01X608397Y295230D02*
X605063Y296897D01*
X608397Y298563D01*
G01X610913Y295813D02*
X611497Y295397D01*
X612163Y295230D01*
X612830Y295397D01*
X613413Y295897D01*
X613830Y296647D01*
X613997Y297397D01*
Y298313D01*
X613830Y299063D01*
X613413Y299730D01*
X612913Y300063D01*
X612330Y300230D01*
X611663Y300063D01*
X611163Y299730D01*
X610830Y299230D01*
X610663Y298563D01*
X610830Y297980D01*
X611247Y297397D01*
X611747Y297063D01*
X612330Y296980D01*
X612997Y297147D01*
X613497Y297563D01*
X613997Y298313D01*
G01X617930Y300230D02*
X617263Y300063D01*
X616763Y299647D01*
X616430Y299147D01*
X616180Y298480D01*
X616097Y297730D01*
X616180Y296980D01*
X616430Y296313D01*
X616763Y295813D01*
X617263Y295397D01*
X617930Y295230D01*
X618597Y295397D01*
X619097Y295813D01*
X619430Y296313D01*
X619680Y296980D01*
X619763Y297730D01*
X619680Y298480D01*
X619430Y299147D01*
X619097Y299647D01*
X618597Y300063D01*
X617930Y300230D01*
G01X630630D02*
Y295230D01*
G01Y295980D02*
X630297Y295563D01*
X629797Y295313D01*
X629213Y295230D01*
X628547Y295397D01*
X628047Y295813D01*
X627713Y296313D01*
X627630Y296897D01*
X627713Y297480D01*
X628047Y297980D01*
X628547Y298397D01*
X629213Y298563D01*
X629797Y298480D01*
X630213Y298313D01*
X630630Y297980D01*
G01X633480Y297480D02*
X636147D01*
X635897Y298063D01*
X635480Y298397D01*
X634897Y298563D01*
X634313Y298480D01*
X633813Y298230D01*
X633480Y297647D01*
X633313Y297147D01*
Y296647D01*
X633480Y296147D01*
X633897Y295647D01*
X634397Y295313D01*
X634980Y295230D01*
X635563Y295397D01*
X636147Y295897D01*
G01X639163Y293980D02*
X639747Y293647D01*
X640413Y293563D01*
X640997Y293647D01*
X641497Y294063D01*
X641830Y294647D01*
Y298563D01*
G01Y297897D02*
X641497Y298230D01*
X640997Y298480D01*
X640413Y298563D01*
X639747Y298397D01*
X639330Y298063D01*
X638997Y297480D01*
X638830Y296897D01*
X638913Y296397D01*
X639247Y295813D01*
X639747Y295397D01*
X640413Y295230D01*
X640913Y295313D01*
X641497Y295647D01*
X641830Y295980D01*
G01X644763Y295230D02*
Y298563D01*
G01Y297897D02*
X645180Y298230D01*
X645597Y298480D01*
X646180Y298563D01*
X646597Y298480D01*
X647097Y298230D01*
G01X650280Y297480D02*
X652947D01*
X652697Y298063D01*
X652280Y298397D01*
X651697Y298563D01*
X651113Y298480D01*
X650613Y298230D01*
X650280Y297647D01*
X650113Y297147D01*
Y296647D01*
X650280Y296147D01*
X650697Y295647D01*
X651197Y295313D01*
X651780Y295230D01*
X652363Y295397D01*
X652947Y295897D01*
G01X655880Y297480D02*
X658547D01*
X658297Y298063D01*
X657880Y298397D01*
X657297Y298563D01*
X656713Y298480D01*
X656213Y298230D01*
X655880Y297647D01*
X655713Y297147D01*
Y296647D01*
X655880Y296147D01*
X656297Y295647D01*
X656797Y295313D01*
X657380Y295230D01*
X657963Y295397D01*
X658547Y295897D01*
G01X602700Y319240D02*
Y324240D01*
G01Y321740D02*
X603117Y322240D01*
X603617Y322490D01*
X604117Y322573D01*
X604867Y322407D01*
X605367Y322073D01*
X605700Y321490D01*
Y320823D01*
X605533Y320157D01*
X605200Y319657D01*
X604617Y319323D01*
X604117Y319240D01*
X603617Y319323D01*
X603117Y319573D01*
X602700Y319990D01*
G01X608383Y322573D02*
Y320240D01*
X608717Y319657D01*
X609217Y319323D01*
X609800Y319240D01*
X610383Y319323D01*
X610883Y319657D01*
X611217Y320240D01*
G01Y319240D02*
Y322573D01*
G01X615400Y324240D02*
Y319240D01*
G01X614233Y322573D02*
X616567D01*
G01X627267Y321907D02*
X627600Y322157D01*
X627850Y322573D01*
X628017Y323157D01*
X627850Y323657D01*
X627517Y323990D01*
X626933Y324240D01*
X624683D01*
Y319240D01*
X627433D01*
X628017Y319573D01*
X628350Y320073D01*
X628517Y320657D01*
X628350Y321240D01*
X627850Y321740D01*
X627267Y321907D01*
X624683D01*
G01X639300Y324240D02*
Y319240D01*
G01Y319990D02*
X638967Y319573D01*
X638467Y319323D01*
X637883Y319240D01*
X637217Y319407D01*
X636717Y319823D01*
X636383Y320323D01*
X636300Y320907D01*
X636383Y321490D01*
X636717Y321990D01*
X637217Y322407D01*
X637883Y322573D01*
X638467Y322490D01*
X638883Y322323D01*
X639300Y321990D01*
G01X643400Y322573D02*
Y319240D01*
G01Y323907D02*
X643233Y323990D01*
Y324157D01*
X643400Y324240D01*
X643567Y324157D01*
Y323990D01*
X643400Y323907D01*
G01X650500Y319240D02*
Y322573D01*
G01Y321990D02*
X650167Y322323D01*
X649667Y322490D01*
X649083Y322573D01*
X648500Y322407D01*
X648000Y322073D01*
X647667Y321573D01*
X647500Y320907D01*
X647667Y320240D01*
X648000Y319740D01*
X648500Y319407D01*
X649083Y319240D01*
X649667Y319323D01*
X650167Y319573D01*
X650500Y319907D01*
G01X652100Y319240D02*
Y322573D01*
G01Y321657D02*
X652350Y322073D01*
X652767Y322407D01*
X653350Y322573D01*
X653933Y322407D01*
X654350Y322073D01*
X654600Y321657D01*
Y319240D01*
G01Y321657D02*
X654850Y322073D01*
X655267Y322407D01*
X655850Y322573D01*
X656433Y322407D01*
X656850Y322073D01*
X657100Y321573D01*
Y319240D01*
G01X658950Y321490D02*
X661617D01*
X661367Y322073D01*
X660950Y322407D01*
X660367Y322573D01*
X659783Y322490D01*
X659283Y322240D01*
X658950Y321657D01*
X658783Y321157D01*
Y320657D01*
X658950Y320157D01*
X659367Y319657D01*
X659867Y319323D01*
X660450Y319240D01*
X661033Y319407D01*
X661617Y319907D01*
G01X665800Y324240D02*
Y319240D01*
G01X664633Y322573D02*
X666967D01*
G01X670150Y321490D02*
X672817D01*
X672567Y322073D01*
X672150Y322407D01*
X671567Y322573D01*
X670983Y322490D01*
X670483Y322240D01*
X670150Y321657D01*
X669983Y321157D01*
Y320657D01*
X670150Y320157D01*
X670567Y319657D01*
X671067Y319323D01*
X671650Y319240D01*
X672233Y319407D01*
X672817Y319907D01*
G01X675833Y319240D02*
Y322573D01*
G01Y321907D02*
X676250Y322240D01*
X676667Y322490D01*
X677250Y322573D01*
X677667Y322490D01*
X678167Y322240D01*
G01X603783Y329260D02*
X607117Y330927D01*
X603783Y332593D01*
G01X609967Y330177D02*
X612133D01*
G01Y331677D02*
X609967D01*
G01X616483Y329260D02*
X616650Y330343D01*
X616900Y331260D01*
X617233Y332093D01*
X617650Y333010D01*
X618317Y334260D01*
X614983D01*
G01X622250D02*
X621583Y334093D01*
X621083Y333677D01*
X620750Y333177D01*
X620500Y332510D01*
X620417Y331760D01*
X620500Y331010D01*
X620750Y330343D01*
X621083Y329843D01*
X621583Y329427D01*
X622250Y329260D01*
X622917Y329427D01*
X623417Y329843D01*
X623750Y330343D01*
X624000Y331010D01*
X624083Y331760D01*
X624000Y332510D01*
X623750Y333177D01*
X623417Y333677D01*
X622917Y334093D01*
X622250Y334260D01*
G01X626350Y329093D02*
X629350Y334260D01*
G01X626350D02*
X625850Y334093D01*
X625600Y333843D01*
X625433Y333343D01*
X625600Y332843D01*
X625850Y332593D01*
X626350Y332427D01*
X626850Y332593D01*
X627100Y332843D01*
X627267Y333343D01*
X627100Y333843D01*
X626850Y334093D01*
X626350Y334260D01*
G01X629350Y330927D02*
X628850Y330760D01*
X628600Y330510D01*
X628433Y330010D01*
X628600Y329510D01*
X628850Y329260D01*
X629350Y329093D01*
X629850Y329260D01*
X630100Y329510D01*
X630267Y330010D01*
X630100Y330510D01*
X629850Y330760D01*
X629350Y330927D01*
G01X633283Y328343D02*
X633617Y329427D01*
G01X605763Y349687D02*
X607763D01*
G01X606680Y350770D02*
Y348603D01*
G01X610780Y347853D02*
X613780Y353020D01*
G01X616797Y349687D02*
X618963D01*
G01X623480Y348020D02*
Y353020D01*
X622480Y352020D01*
G01Y348020D02*
X624480D01*
G01X626580D02*
Y351353D01*
G01Y350437D02*
X626830Y350853D01*
X627247Y351187D01*
X627830Y351353D01*
X628413Y351187D01*
X628830Y350853D01*
X629080Y350437D01*
Y348020D01*
G01Y350437D02*
X629330Y350853D01*
X629747Y351187D01*
X630330Y351353D01*
X630913Y351187D01*
X631330Y350853D01*
X631580Y350353D01*
Y348020D01*
G01X634680Y351353D02*
Y348020D01*
G01Y352687D02*
X634513Y352770D01*
Y352937D01*
X634680Y353020D01*
X634847Y352937D01*
Y352770D01*
X634680Y352687D01*
G01X640280Y348020D02*
Y353020D01*
G01X608333Y393000D02*
Y398000D01*
X610500Y393833D01*
X612667Y398000D01*
Y393000D01*
G01X614683Y396333D02*
Y394000D01*
X615017Y393417D01*
X615517Y393083D01*
X616100Y393000D01*
X616683Y393083D01*
X617183Y393417D01*
X617517Y394000D01*
G01Y393000D02*
Y396333D01*
G01X620450Y393583D02*
X620867Y393250D01*
X621450Y393000D01*
X621950D01*
X622450Y393167D01*
X622783Y393417D01*
X622950Y393750D01*
X622867Y394250D01*
X622533Y394500D01*
X621033Y395000D01*
X620700Y395583D01*
X620867Y396000D01*
X621200Y396250D01*
X621700Y396333D01*
X622200Y396250D01*
X622700Y396000D01*
G01X627300Y398000D02*
Y393000D01*
G01X626133Y396333D02*
X628467D01*
G01X638000Y393000D02*
Y397250D01*
X638167Y397667D01*
X638500Y397917D01*
X639000Y398000D01*
X639500Y397833D01*
X639750Y397417D01*
G01X638750Y396000D02*
X637083D01*
G01X644100Y393000D02*
X643600Y393083D01*
X643100Y393417D01*
X642767Y394000D01*
X642600Y394667D01*
X642767Y395333D01*
X643100Y395917D01*
X643600Y396250D01*
X644100Y396333D01*
X644600Y396250D01*
X645100Y395917D01*
X645433Y395333D01*
X645517Y394667D01*
X645433Y394000D01*
X645100Y393417D01*
X644600Y393083D01*
X644100Y393000D01*
G01X649700D02*
Y398000D01*
G01X655300Y393000D02*
Y398000D01*
G01X660900Y393000D02*
X660400Y393083D01*
X659900Y393417D01*
X659567Y394000D01*
X659400Y394667D01*
X659567Y395333D01*
X659900Y395917D01*
X660400Y396250D01*
X660900Y396333D01*
X661400Y396250D01*
X661900Y395917D01*
X662233Y395333D01*
X662317Y394667D01*
X662233Y394000D01*
X661900Y393417D01*
X661400Y393083D01*
X660900Y393000D01*
G01X664417Y396333D02*
X665417Y393000D01*
X666500Y396333D01*
X667583Y393000D01*
X668583Y396333D01*
G01X595500Y679000D02*
Y396000D01*
G01X605810Y429990D02*
Y434240D01*
X605977Y434657D01*
X606310Y434907D01*
X606810Y434990D01*
X607310Y434823D01*
X607560Y434407D01*
G01X606560Y432990D02*
X604893D01*
G01X611910Y429990D02*
X611410Y430073D01*
X610910Y430407D01*
X610577Y430990D01*
X610410Y431657D01*
X610577Y432323D01*
X610910Y432907D01*
X611410Y433240D01*
X611910Y433323D01*
X612410Y433240D01*
X612910Y432907D01*
X613243Y432323D01*
X613327Y431657D01*
X613243Y430990D01*
X612910Y430407D01*
X612410Y430073D01*
X611910Y429990D01*
G01X617510D02*
Y434990D01*
G01X623110Y429990D02*
Y434990D01*
G01X628710Y429990D02*
X628210Y430073D01*
X627710Y430407D01*
X627377Y430990D01*
X627210Y431657D01*
X627377Y432323D01*
X627710Y432907D01*
X628210Y433240D01*
X628710Y433323D01*
X629210Y433240D01*
X629710Y432907D01*
X630043Y432323D01*
X630127Y431657D01*
X630043Y430990D01*
X629710Y430407D01*
X629210Y430073D01*
X628710Y429990D01*
G01X632227Y433323D02*
X633227Y429990D01*
X634310Y433323D01*
X635393Y429990D01*
X636393Y433323D01*
G01X647010Y434990D02*
Y429990D01*
G01Y430740D02*
X646677Y430323D01*
X646177Y430073D01*
X645593Y429990D01*
X644927Y430157D01*
X644427Y430573D01*
X644093Y431073D01*
X644010Y431657D01*
X644093Y432240D01*
X644427Y432740D01*
X644927Y433157D01*
X645593Y433323D01*
X646177Y433240D01*
X646593Y433073D01*
X647010Y432740D01*
G01X649943Y429990D02*
Y433323D01*
G01Y432657D02*
X650360Y432990D01*
X650777Y433240D01*
X651360Y433323D01*
X651777Y433240D01*
X652277Y432990D01*
G01X658210Y429990D02*
Y433323D01*
G01Y432740D02*
X657877Y433073D01*
X657377Y433240D01*
X656793Y433323D01*
X656210Y433157D01*
X655710Y432823D01*
X655377Y432323D01*
X655210Y431657D01*
X655377Y430990D01*
X655710Y430490D01*
X656210Y430157D01*
X656793Y429990D01*
X657377Y430073D01*
X657877Y430323D01*
X658210Y430657D01*
G01X660227Y433323D02*
X661227Y429990D01*
X662310Y433323D01*
X663393Y429990D01*
X664393Y433323D01*
G01X667910D02*
Y429990D01*
G01Y434657D02*
X667743Y434740D01*
Y434907D01*
X667910Y434990D01*
X668077Y434907D01*
Y434740D01*
X667910Y434657D01*
G01X672093Y429990D02*
Y433323D01*
G01Y432490D02*
X672427Y432907D01*
X672927Y433240D01*
X673593Y433323D01*
X674177Y433240D01*
X674677Y432907D01*
X674927Y432323D01*
Y429990D01*
G01X677943Y428740D02*
X678527Y428407D01*
X679193Y428323D01*
X679777Y428407D01*
X680277Y428823D01*
X680610Y429407D01*
Y433323D01*
G01Y432657D02*
X680277Y432990D01*
X679777Y433240D01*
X679193Y433323D01*
X678527Y433157D01*
X678110Y432823D01*
X677777Y432240D01*
X677610Y431657D01*
X677693Y431157D01*
X678027Y430573D01*
X678527Y430157D01*
X679193Y429990D01*
X679693Y430073D01*
X680277Y430407D01*
X680610Y430740D01*
G01X685127Y428323D02*
X685960Y429157D01*
X686377Y429990D01*
Y433323D01*
X685960Y434157D01*
X685127Y434990D01*
G01X606903Y440587D02*
X608903D01*
G01X607820Y441670D02*
Y439503D01*
G01X611920Y438753D02*
X614920Y443920D01*
G01X617937Y440587D02*
X620103D01*
G01X622787Y439670D02*
X623287Y439253D01*
X623870Y439003D01*
X624620Y438920D01*
X625370Y439087D01*
X625953Y439420D01*
X626370Y440003D01*
X626453Y440670D01*
X626287Y441337D01*
X625870Y441753D01*
X625287Y442087D01*
X624703Y442170D01*
X624120Y442087D01*
X623370Y441753D01*
X623620Y443920D01*
X625870D01*
G01X627720Y438920D02*
Y442253D01*
G01Y441337D02*
X627970Y441753D01*
X628387Y442087D01*
X628970Y442253D01*
X629553Y442087D01*
X629970Y441753D01*
X630220Y441337D01*
Y438920D01*
G01Y441337D02*
X630470Y441753D01*
X630887Y442087D01*
X631470Y442253D01*
X632053Y442087D01*
X632470Y441753D01*
X632720Y441253D01*
Y438920D01*
G01X635820Y442253D02*
Y438920D01*
G01Y443587D02*
X635653Y443670D01*
Y443837D01*
X635820Y443920D01*
X635987Y443837D01*
Y443670D01*
X635820Y443587D01*
G01X641420Y438920D02*
Y443920D01*
G01X607500Y452000D02*
Y457000D01*
X606500Y456000D01*
G01Y452000D02*
X608500D01*
G01X613100Y451833D02*
X612933Y451917D01*
Y452083D01*
X613100Y452167D01*
X613267Y452083D01*
Y451917D01*
X613100Y451833D01*
G01X618700Y457000D02*
X618033Y456833D01*
X617533Y456417D01*
X617200Y455917D01*
X616950Y455250D01*
X616867Y454500D01*
X616950Y453750D01*
X617200Y453083D01*
X617533Y452583D01*
X618033Y452167D01*
X618700Y452000D01*
X619367Y452167D01*
X619867Y452583D01*
X620200Y453083D01*
X620450Y453750D01*
X620533Y454500D01*
X620450Y455250D01*
X620200Y455917D01*
X619867Y456417D01*
X619367Y456833D01*
X618700Y457000D01*
G01X621800Y452000D02*
Y455333D01*
G01Y454417D02*
X622050Y454833D01*
X622467Y455167D01*
X623050Y455333D01*
X623633Y455167D01*
X624050Y454833D01*
X624300Y454417D01*
Y452000D01*
G01Y454417D02*
X624550Y454833D01*
X624967Y455167D01*
X625550Y455333D01*
X626133Y455167D01*
X626550Y454833D01*
X626800Y454333D01*
Y452000D01*
G01X629900Y455333D02*
Y452000D01*
G01Y456667D02*
X629733Y456750D01*
Y456917D01*
X629900Y457000D01*
X630067Y456917D01*
Y456750D01*
X629900Y456667D01*
G01X635500Y452000D02*
Y457000D01*
G01X644200Y452000D02*
Y455333D01*
G01Y454417D02*
X644450Y454833D01*
X644867Y455167D01*
X645450Y455333D01*
X646033Y455167D01*
X646450Y454833D01*
X646700Y454417D01*
Y452000D01*
G01Y454417D02*
X646950Y454833D01*
X647367Y455167D01*
X647950Y455333D01*
X648533Y455167D01*
X648950Y454833D01*
X649200Y454333D01*
Y452000D01*
G01X653800D02*
Y455333D01*
G01Y454750D02*
X653467Y455083D01*
X652967Y455250D01*
X652383Y455333D01*
X651800Y455167D01*
X651300Y454833D01*
X650967Y454333D01*
X650800Y453667D01*
X650967Y453000D01*
X651300Y452500D01*
X651800Y452167D01*
X652383Y452000D01*
X652967Y452083D01*
X653467Y452333D01*
X653800Y452667D01*
G01X656650Y455333D02*
X659150Y452000D01*
G01Y455333D02*
X656650Y452000D01*
G01X606583Y471667D02*
X608583D01*
G01X607500Y472750D02*
Y470583D01*
G01X611600Y469833D02*
X614600Y475000D01*
G01X617617Y471667D02*
X619783D01*
G01X622467Y470750D02*
X622967Y470333D01*
X623550Y470083D01*
X624300Y470000D01*
X625050Y470167D01*
X625633Y470500D01*
X626050Y471083D01*
X626133Y471750D01*
X625967Y472417D01*
X625550Y472833D01*
X624967Y473167D01*
X624383Y473250D01*
X623800Y473167D01*
X623050Y472833D01*
X623300Y475000D01*
X625550D01*
G01X627400Y470000D02*
Y473333D01*
G01Y472417D02*
X627650Y472833D01*
X628067Y473167D01*
X628650Y473333D01*
X629233Y473167D01*
X629650Y472833D01*
X629900Y472417D01*
Y470000D01*
G01Y472417D02*
X630150Y472833D01*
X630567Y473167D01*
X631150Y473333D01*
X631733Y473167D01*
X632150Y472833D01*
X632400Y472333D01*
Y470000D01*
G01X635500Y473333D02*
Y470000D01*
G01Y474667D02*
X635333Y474750D01*
Y474917D01*
X635500Y475000D01*
X635667Y474917D01*
Y474750D01*
X635500Y474667D01*
G01X641100Y470000D02*
Y475000D01*
G01X606583Y486667D02*
X608583D01*
G01X607500Y487750D02*
Y485583D01*
G01X611600Y484833D02*
X614600Y490000D01*
G01X617617Y486667D02*
X619783D01*
G01X622467Y485750D02*
X622967Y485333D01*
X623550Y485083D01*
X624300Y485000D01*
X625050Y485167D01*
X625633Y485500D01*
X626050Y486083D01*
X626133Y486750D01*
X625967Y487417D01*
X625550Y487833D01*
X624967Y488167D01*
X624383Y488250D01*
X623800Y488167D01*
X623050Y487833D01*
X623300Y490000D01*
X625550D01*
G01X627400Y485000D02*
Y488333D01*
G01Y487417D02*
X627650Y487833D01*
X628067Y488167D01*
X628650Y488333D01*
X629233Y488167D01*
X629650Y487833D01*
X629900Y487417D01*
Y485000D01*
G01Y487417D02*
X630150Y487833D01*
X630567Y488167D01*
X631150Y488333D01*
X631733Y488167D01*
X632150Y487833D01*
X632400Y487333D01*
Y485000D01*
G01X635500Y488333D02*
Y485000D01*
G01Y489667D02*
X635333Y489750D01*
Y489917D01*
X635500Y490000D01*
X635667Y489917D01*
Y489750D01*
X635500Y489667D01*
G01X641100Y485000D02*
Y490000D01*
G01X606583Y501667D02*
X608583D01*
G01X607500Y502750D02*
Y500583D01*
G01X611267Y501000D02*
X611767Y500417D01*
X612433Y500083D01*
X613183Y500000D01*
X613850Y500083D01*
X614517Y500500D01*
X614933Y501000D01*
X615017Y501500D01*
X614850Y502083D01*
X614267Y502500D01*
X613683Y502667D01*
X612933D01*
G01X613683D02*
X614183Y502917D01*
X614600Y503333D01*
X614767Y503833D01*
X614600Y504333D01*
X614183Y504750D01*
X613433Y505000D01*
X612683Y504917D01*
X611933Y504583D01*
G01X617200Y499833D02*
X620200Y505000D01*
G01X623217Y501667D02*
X625383D01*
G01X629900Y505000D02*
X629233Y504833D01*
X628733Y504417D01*
X628400Y503917D01*
X628150Y503250D01*
X628067Y502500D01*
X628150Y501750D01*
X628400Y501083D01*
X628733Y500583D01*
X629233Y500167D01*
X629900Y500000D01*
X630567Y500167D01*
X631067Y500583D01*
X631400Y501083D01*
X631650Y501750D01*
X631733Y502500D01*
X631650Y503250D01*
X631400Y503917D01*
X631067Y504417D01*
X630567Y504833D01*
X629900Y505000D01*
G01X633000Y500000D02*
Y503333D01*
G01Y502417D02*
X633250Y502833D01*
X633667Y503167D01*
X634250Y503333D01*
X634833Y503167D01*
X635250Y502833D01*
X635500Y502417D01*
Y500000D01*
G01Y502417D02*
X635750Y502833D01*
X636167Y503167D01*
X636750Y503333D01*
X637333Y503167D01*
X637750Y502833D01*
X638000Y502333D01*
Y500000D01*
G01X641100Y503333D02*
Y500000D01*
G01Y504667D02*
X640933Y504750D01*
Y504917D01*
X641100Y505000D01*
X641267Y504917D01*
Y504750D01*
X641100Y504667D01*
G01X646700Y500000D02*
Y505000D01*
G01X606583Y546667D02*
X608583D01*
G01X607500Y547750D02*
Y545583D01*
G01X611600Y544833D02*
X614600Y550000D01*
G01X617617Y546667D02*
X619783D01*
G01X622717Y549167D02*
X623217Y549667D01*
X623800Y549917D01*
X624467Y550000D01*
X625300Y549833D01*
X625883Y549417D01*
X626050Y548917D01*
X625967Y548417D01*
X625633Y548000D01*
X623967Y547167D01*
X623217Y546583D01*
X622717Y545750D01*
X622550Y545000D01*
X626050D01*
G01X627400D02*
Y548333D01*
G01Y547417D02*
X627650Y547833D01*
X628067Y548167D01*
X628650Y548333D01*
X629233Y548167D01*
X629650Y547833D01*
X629900Y547417D01*
Y545000D01*
G01Y547417D02*
X630150Y547833D01*
X630567Y548167D01*
X631150Y548333D01*
X631733Y548167D01*
X632150Y547833D01*
X632400Y547333D01*
Y545000D01*
G01X635500Y548333D02*
Y545000D01*
G01Y549667D02*
X635333Y549750D01*
Y549917D01*
X635500Y550000D01*
X635667Y549917D01*
Y549750D01*
X635500Y549667D01*
G01X641100Y545000D02*
Y550000D01*
G01X606583Y516667D02*
X608583D01*
G01X607500Y517750D02*
Y515583D01*
G01X611600Y514833D02*
X614600Y520000D01*
G01X617617Y516667D02*
X619783D01*
G01X622717Y519167D02*
X623217Y519667D01*
X623800Y519917D01*
X624467Y520000D01*
X625300Y519833D01*
X625883Y519417D01*
X626050Y518917D01*
X625967Y518417D01*
X625633Y518000D01*
X623967Y517167D01*
X623217Y516583D01*
X622717Y515750D01*
X622550Y515000D01*
X626050D01*
G01X627400D02*
Y518333D01*
G01Y517417D02*
X627650Y517833D01*
X628067Y518167D01*
X628650Y518333D01*
X629233Y518167D01*
X629650Y517833D01*
X629900Y517417D01*
Y515000D01*
G01Y517417D02*
X630150Y517833D01*
X630567Y518167D01*
X631150Y518333D01*
X631733Y518167D01*
X632150Y517833D01*
X632400Y517333D01*
Y515000D01*
G01X635500Y518333D02*
Y515000D01*
G01Y519667D02*
X635333Y519750D01*
Y519917D01*
X635500Y520000D01*
X635667Y519917D01*
Y519750D01*
X635500Y519667D01*
G01X641100Y515000D02*
Y520000D01*
G01X606583Y530167D02*
X608583D01*
G01X607500Y531250D02*
Y529083D01*
G01X611600Y528333D02*
X614600Y533500D01*
G01X617617Y530167D02*
X619783D01*
G01X622467Y529500D02*
X622967Y528917D01*
X623633Y528583D01*
X624383Y528500D01*
X625050Y528583D01*
X625717Y529000D01*
X626133Y529500D01*
X626217Y530000D01*
X626050Y530583D01*
X625467Y531000D01*
X624883Y531167D01*
X624133D01*
G01X624883D02*
X625383Y531417D01*
X625800Y531833D01*
X625967Y532333D01*
X625800Y532833D01*
X625383Y533250D01*
X624633Y533500D01*
X623883Y533417D01*
X623133Y533083D01*
G01X627400Y528500D02*
Y531833D01*
G01Y530917D02*
X627650Y531333D01*
X628067Y531667D01*
X628650Y531833D01*
X629233Y531667D01*
X629650Y531333D01*
X629900Y530917D01*
Y528500D01*
G01Y530917D02*
X630150Y531333D01*
X630567Y531667D01*
X631150Y531833D01*
X631733Y531667D01*
X632150Y531333D01*
X632400Y530833D01*
Y528500D01*
G01X635500Y531833D02*
Y528500D01*
G01Y533167D02*
X635333Y533250D01*
Y533417D01*
X635500Y533500D01*
X635667Y533417D01*
Y533250D01*
X635500Y533167D01*
G01X641100Y528500D02*
Y533500D01*
G01X606583Y591667D02*
X608583D01*
G01X607500Y592750D02*
Y590583D01*
G01X611600Y589833D02*
X614600Y595000D01*
G01X617617Y591667D02*
X619783D01*
G01X622467Y591000D02*
X622967Y590417D01*
X623633Y590083D01*
X624383Y590000D01*
X625050Y590083D01*
X625717Y590500D01*
X626133Y591000D01*
X626217Y591500D01*
X626050Y592083D01*
X625467Y592500D01*
X624883Y592667D01*
X624133D01*
G01X624883D02*
X625383Y592917D01*
X625800Y593333D01*
X625967Y593833D01*
X625800Y594333D01*
X625383Y594750D01*
X624633Y595000D01*
X623883Y594917D01*
X623133Y594583D01*
G01X627400Y590000D02*
Y593333D01*
G01Y592417D02*
X627650Y592833D01*
X628067Y593167D01*
X628650Y593333D01*
X629233Y593167D01*
X629650Y592833D01*
X629900Y592417D01*
Y590000D01*
G01Y592417D02*
X630150Y592833D01*
X630567Y593167D01*
X631150Y593333D01*
X631733Y593167D01*
X632150Y592833D01*
X632400Y592333D01*
Y590000D01*
G01X635500Y593333D02*
Y590000D01*
G01Y594667D02*
X635333Y594750D01*
Y594917D01*
X635500Y595000D01*
X635667Y594917D01*
Y594750D01*
X635500Y594667D01*
G01X641100Y590000D02*
Y595000D01*
G01X606583Y575167D02*
X608583D01*
G01X607500Y576250D02*
Y574083D01*
G01X611517Y577667D02*
X612017Y578167D01*
X612600Y578417D01*
X613267Y578500D01*
X614100Y578333D01*
X614683Y577917D01*
X614850Y577417D01*
X614767Y576917D01*
X614433Y576500D01*
X612767Y575667D01*
X612017Y575083D01*
X611517Y574250D01*
X611350Y573500D01*
X614850D01*
G01X617200Y573333D02*
X620200Y578500D01*
G01X623217Y575167D02*
X625383D01*
G01X630900Y573500D02*
Y578500D01*
X627817Y574917D01*
X631983D01*
G01X633000Y573500D02*
Y576833D01*
G01Y575917D02*
X633250Y576333D01*
X633667Y576667D01*
X634250Y576833D01*
X634833Y576667D01*
X635250Y576333D01*
X635500Y575917D01*
Y573500D01*
G01Y575917D02*
X635750Y576333D01*
X636167Y576667D01*
X636750Y576833D01*
X637333Y576667D01*
X637750Y576333D01*
X638000Y575833D01*
Y573500D01*
G01X641100Y576833D02*
Y573500D01*
G01Y578167D02*
X640933Y578250D01*
Y578417D01*
X641100Y578500D01*
X641267Y578417D01*
Y578250D01*
X641100Y578167D01*
G01X646700Y573500D02*
Y578500D01*
G01X606583Y561667D02*
X608583D01*
G01X607500Y562750D02*
Y560583D01*
G01X611600Y559833D02*
X614600Y565000D01*
G01X617617Y561667D02*
X619783D01*
G01X622717Y564167D02*
X623217Y564667D01*
X623800Y564917D01*
X624467Y565000D01*
X625300Y564833D01*
X625883Y564417D01*
X626050Y563917D01*
X625967Y563417D01*
X625633Y563000D01*
X623967Y562167D01*
X623217Y561583D01*
X622717Y560750D01*
X622550Y560000D01*
X626050D01*
G01X627400D02*
Y563333D01*
G01Y562417D02*
X627650Y562833D01*
X628067Y563167D01*
X628650Y563333D01*
X629233Y563167D01*
X629650Y562833D01*
X629900Y562417D01*
Y560000D01*
G01Y562417D02*
X630150Y562833D01*
X630567Y563167D01*
X631150Y563333D01*
X631733Y563167D01*
X632150Y562833D01*
X632400Y562333D01*
Y560000D01*
G01X635500Y563333D02*
Y560000D01*
G01Y564667D02*
X635333Y564750D01*
Y564917D01*
X635500Y565000D01*
X635667Y564917D01*
Y564750D01*
X635500Y564667D01*
G01X641100Y560000D02*
Y565000D01*
G01X606583Y620167D02*
X608583D01*
G01X607500Y621250D02*
Y619083D01*
G01X611600Y618333D02*
X614600Y623500D01*
G01X617617Y620167D02*
X619783D01*
G01X622717Y622667D02*
X623217Y623167D01*
X623800Y623417D01*
X624467Y623500D01*
X625300Y623333D01*
X625883Y622917D01*
X626050Y622417D01*
X625967Y621917D01*
X625633Y621500D01*
X623967Y620667D01*
X623217Y620083D01*
X622717Y619250D01*
X622550Y618500D01*
X626050D01*
G01X627400D02*
Y621833D01*
G01Y620917D02*
X627650Y621333D01*
X628067Y621667D01*
X628650Y621833D01*
X629233Y621667D01*
X629650Y621333D01*
X629900Y620917D01*
Y618500D01*
G01Y620917D02*
X630150Y621333D01*
X630567Y621667D01*
X631150Y621833D01*
X631733Y621667D01*
X632150Y621333D01*
X632400Y620833D01*
Y618500D01*
G01X635500Y621833D02*
Y618500D01*
G01Y623167D02*
X635333Y623250D01*
Y623417D01*
X635500Y623500D01*
X635667Y623417D01*
Y623250D01*
X635500Y623167D01*
G01X641100Y618500D02*
Y623500D01*
G01X605417Y603500D02*
X607500Y608500D01*
X609583Y603500D01*
G01X608833Y605250D02*
X606167D01*
G01X613100Y603500D02*
Y608500D01*
G01X618700Y603500D02*
Y608500D01*
G01X624300Y603500D02*
X623800Y603583D01*
X623300Y603917D01*
X622967Y604500D01*
X622800Y605167D01*
X622967Y605833D01*
X623300Y606417D01*
X623800Y606750D01*
X624300Y606833D01*
X624800Y606750D01*
X625300Y606417D01*
X625633Y605833D01*
X625717Y605167D01*
X625633Y604500D01*
X625300Y603917D01*
X624800Y603583D01*
X624300Y603500D01*
G01X627817Y606833D02*
X628817Y603500D01*
X629900Y606833D01*
X630983Y603500D01*
X631983Y606833D01*
G01X605353Y638700D02*
Y643700D01*
X607520Y639533D01*
X609687Y643700D01*
Y638700D01*
G01X611703Y642033D02*
Y639700D01*
X612037Y639117D01*
X612537Y638783D01*
X613120Y638700D01*
X613703Y638783D01*
X614203Y639117D01*
X614537Y639700D01*
G01Y638700D02*
Y642033D01*
G01X617470Y639283D02*
X617887Y638950D01*
X618470Y638700D01*
X618970D01*
X619470Y638867D01*
X619803Y639117D01*
X619970Y639450D01*
X619887Y639950D01*
X619553Y640200D01*
X618053Y640700D01*
X617720Y641283D01*
X617887Y641700D01*
X618220Y641950D01*
X618720Y642033D01*
X619220Y641950D01*
X619720Y641700D01*
G01X624320Y643700D02*
Y638700D01*
G01X623153Y642033D02*
X625487D01*
G01X635020Y638700D02*
Y642950D01*
X635187Y643367D01*
X635520Y643617D01*
X636020Y643700D01*
X636520Y643533D01*
X636770Y643117D01*
G01X635770Y641700D02*
X634103D01*
G01X641120Y638700D02*
X640620Y638783D01*
X640120Y639117D01*
X639787Y639700D01*
X639620Y640367D01*
X639787Y641033D01*
X640120Y641617D01*
X640620Y641950D01*
X641120Y642033D01*
X641620Y641950D01*
X642120Y641617D01*
X642453Y641033D01*
X642537Y640367D01*
X642453Y639700D01*
X642120Y639117D01*
X641620Y638783D01*
X641120Y638700D01*
G01X646720D02*
Y643700D01*
G01X652320Y638700D02*
Y643700D01*
G01X657920Y638700D02*
X657420Y638783D01*
X656920Y639117D01*
X656587Y639700D01*
X656420Y640367D01*
X656587Y641033D01*
X656920Y641617D01*
X657420Y641950D01*
X657920Y642033D01*
X658420Y641950D01*
X658920Y641617D01*
X659253Y641033D01*
X659337Y640367D01*
X659253Y639700D01*
X658920Y639117D01*
X658420Y638783D01*
X657920Y638700D01*
G01X661437Y642033D02*
X662437Y638700D01*
X663520Y642033D01*
X664603Y638700D01*
X665603Y642033D01*
G01X590417Y860000D02*
X592500Y855000D01*
X594583Y860000D01*
G01X596267Y856000D02*
X596767Y855417D01*
X597433Y855083D01*
X598183Y855000D01*
X598850Y855083D01*
X599517Y855500D01*
X599933Y856000D01*
X600017Y856500D01*
X599850Y857083D01*
X599267Y857500D01*
X598683Y857667D01*
X597933D01*
G01X598683D02*
X599183Y857917D01*
X599600Y858333D01*
X599767Y858833D01*
X599600Y859333D01*
X599183Y859750D01*
X598433Y860000D01*
X597683Y859917D01*
X596933Y859583D01*
G01X603700Y854833D02*
X603533Y854917D01*
Y855083D01*
X603700Y855167D01*
X603867Y855083D01*
Y854917D01*
X603700Y854833D01*
G01X610300Y855000D02*
Y860000D01*
X607217Y856417D01*
X611383D01*
G01X614900Y854833D02*
X614733Y854917D01*
Y855083D01*
X614900Y855167D01*
X615067Y855083D01*
Y854917D01*
X614900Y854833D01*
G01X620500Y855000D02*
Y860000D01*
X619500Y859000D01*
G01Y855000D02*
X621500D01*
G01X641317Y859167D02*
X641817Y859667D01*
X642400Y859917D01*
X643067Y860000D01*
X643900Y859833D01*
X644483Y859417D01*
X644650Y858917D01*
X644567Y858417D01*
X644233Y858000D01*
X642567Y857167D01*
X641817Y856583D01*
X641317Y855750D01*
X641150Y855000D01*
X644650D01*
G01X648500Y860000D02*
X647833Y859833D01*
X647333Y859417D01*
X647000Y858917D01*
X646750Y858250D01*
X646667Y857500D01*
X646750Y856750D01*
X647000Y856083D01*
X647333Y855583D01*
X647833Y855167D01*
X648500Y855000D01*
X649167Y855167D01*
X649667Y855583D01*
X650000Y856083D01*
X650250Y856750D01*
X650333Y857500D01*
X650250Y858250D01*
X650000Y858917D01*
X649667Y859417D01*
X649167Y859833D01*
X648500Y860000D01*
G01X654100Y855000D02*
Y860000D01*
X653100Y859000D01*
G01Y855000D02*
X655100D01*
G01X657867Y855750D02*
X658367Y855333D01*
X658950Y855083D01*
X659700Y855000D01*
X660450Y855167D01*
X661033Y855500D01*
X661450Y856083D01*
X661533Y856750D01*
X661367Y857417D01*
X660950Y857833D01*
X660367Y858167D01*
X659783Y858250D01*
X659200Y858167D01*
X658450Y857833D01*
X658700Y860000D01*
X660950D01*
G01X663800Y854833D02*
X666800Y860000D01*
G01X670900D02*
X670233Y859833D01*
X669733Y859417D01*
X669400Y858917D01*
X669150Y858250D01*
X669067Y857500D01*
X669150Y856750D01*
X669400Y856083D01*
X669733Y855583D01*
X670233Y855167D01*
X670900Y855000D01*
X671567Y855167D01*
X672067Y855583D01*
X672400Y856083D01*
X672650Y856750D01*
X672733Y857500D01*
X672650Y858250D01*
X672400Y858917D01*
X672067Y859417D01*
X671567Y859833D01*
X670900Y860000D01*
G01X674917Y857083D02*
X675500Y857667D01*
X676000Y858000D01*
X676667Y858167D01*
X677250Y858000D01*
X677667Y857667D01*
X678000Y857167D01*
X678083Y856583D01*
X678000Y856083D01*
X677667Y855583D01*
X677167Y855167D01*
X676583Y855000D01*
X675917Y855167D01*
X675333Y855667D01*
X675000Y856417D01*
X674917Y857250D01*
X675083Y858333D01*
X675333Y858917D01*
X675750Y859500D01*
X676333Y859917D01*
X676917Y860000D01*
X677500Y859833D01*
X677917Y859417D01*
G01X650853Y438153D02*
X650020Y438987D01*
X649603Y439820D01*
Y443153D01*
X650020Y443987D01*
X650853Y444820D01*
G01X656870Y439820D02*
X656370Y439903D01*
X655870Y440237D01*
X655537Y440820D01*
X655370Y441487D01*
X655537Y442153D01*
X655870Y442737D01*
X656370Y443070D01*
X656870Y443153D01*
X657370Y443070D01*
X657870Y442737D01*
X658203Y442153D01*
X658287Y441487D01*
X658203Y440820D01*
X657870Y440237D01*
X657370Y439903D01*
X656870Y439820D01*
G01X661303D02*
Y443153D01*
G01Y442487D02*
X661720Y442820D01*
X662137Y443070D01*
X662720Y443153D01*
X663137Y443070D01*
X663637Y442820D01*
G01X617500Y668500D02*
Y663500D01*
G01X615583Y668500D02*
X619417D01*
G01X623100Y663500D02*
X622600Y663583D01*
X622100Y663917D01*
X621767Y664500D01*
X621600Y665167D01*
X621767Y665833D01*
X622100Y666417D01*
X622600Y666750D01*
X623100Y666833D01*
X623600Y666750D01*
X624100Y666417D01*
X624433Y665833D01*
X624517Y665167D01*
X624433Y664500D01*
X624100Y663917D01*
X623600Y663583D01*
X623100Y663500D01*
G01X628700D02*
Y668500D01*
G01X633050Y665750D02*
X635717D01*
X635467Y666333D01*
X635050Y666667D01*
X634467Y666833D01*
X633883Y666750D01*
X633383Y666500D01*
X633050Y665917D01*
X632883Y665417D01*
Y664917D01*
X633050Y664417D01*
X633467Y663917D01*
X633967Y663583D01*
X634550Y663500D01*
X635133Y663667D01*
X635717Y664167D01*
G01X638733Y663500D02*
Y666833D01*
G01Y666167D02*
X639150Y666500D01*
X639567Y666750D01*
X640150Y666833D01*
X640567Y666750D01*
X641067Y666500D01*
G01X647000Y663500D02*
Y666833D01*
G01Y666250D02*
X646667Y666583D01*
X646167Y666750D01*
X645583Y666833D01*
X645000Y666667D01*
X644500Y666333D01*
X644167Y665833D01*
X644000Y665167D01*
X644167Y664500D01*
X644500Y664000D01*
X645000Y663667D01*
X645583Y663500D01*
X646167Y663583D01*
X646667Y663833D01*
X647000Y664167D01*
G01X649683Y663500D02*
Y666833D01*
G01Y666000D02*
X650017Y666417D01*
X650517Y666750D01*
X651183Y666833D01*
X651767Y666750D01*
X652267Y666417D01*
X652517Y665833D01*
Y663500D01*
G01X658033Y666417D02*
X657450Y666750D01*
X656950Y666833D01*
X656283Y666667D01*
X655783Y666333D01*
X655450Y665750D01*
X655367Y665167D01*
X655450Y664583D01*
X655783Y664083D01*
X656283Y663667D01*
X656950Y663500D01*
X657533Y663667D01*
X658033Y664000D01*
G01X661050Y665750D02*
X663717D01*
X663467Y666333D01*
X663050Y666667D01*
X662467Y666833D01*
X661883Y666750D01*
X661383Y666500D01*
X661050Y665917D01*
X660883Y665417D01*
Y664917D01*
X661050Y664417D01*
X661467Y663917D01*
X661967Y663583D01*
X662550Y663500D01*
X663133Y663667D01*
X663717Y664167D01*
G01X694500Y716000D02*
Y-69500D01*
G01X713000Y850500D02*
Y-73000D01*
X1343000D01*
Y782000D01*
X713000D01*
G01X736937Y-65320D02*
X737437Y-65737D01*
X738020Y-65987D01*
X738770Y-66070D01*
X739520Y-65903D01*
X740103Y-65570D01*
X740520Y-64987D01*
X740603Y-64320D01*
X740437Y-63653D01*
X740020Y-63237D01*
X739437Y-62903D01*
X738853Y-62820D01*
X738270Y-62903D01*
X737520Y-63237D01*
X737770Y-61070D01*
X740020D01*
G01X744370Y-66237D02*
X744203Y-66153D01*
Y-65987D01*
X744370Y-65903D01*
X744537Y-65987D01*
Y-66153D01*
X744370Y-66237D01*
G01X749970Y-66070D02*
Y-61070D01*
X748970Y-62070D01*
G01Y-66070D02*
X750970D01*
G01X760170Y-61070D02*
X762170D01*
G01X761170D02*
Y-66070D01*
G01X760170D02*
X762170D01*
G01X766270D02*
Y-61820D01*
X766437Y-61403D01*
X766770Y-61153D01*
X767270Y-61070D01*
X767770Y-61237D01*
X768020Y-61653D01*
G01X767020Y-63070D02*
X765353D01*
G01X778470Y-63570D02*
X780137D01*
Y-65070D01*
X779637Y-65570D01*
X779053Y-65903D01*
X778220Y-66070D01*
X777387Y-65903D01*
X776803Y-65570D01*
X776303Y-65070D01*
X775970Y-64487D01*
X775803Y-63820D01*
Y-63237D01*
X775970Y-62737D01*
X776303Y-62153D01*
X776803Y-61653D01*
X777303Y-61320D01*
X777970Y-61070D01*
X778553D01*
X779220Y-61237D01*
X779720Y-61570D01*
G01X782320Y-63820D02*
X784987D01*
X784737Y-63237D01*
X784320Y-62903D01*
X783737Y-62737D01*
X783153Y-62820D01*
X782653Y-63070D01*
X782320Y-63653D01*
X782153Y-64153D01*
Y-64653D01*
X782320Y-65153D01*
X782737Y-65653D01*
X783237Y-65987D01*
X783820Y-66070D01*
X784403Y-65903D01*
X784987Y-65403D01*
G01X788003Y-66070D02*
Y-62737D01*
G01Y-63403D02*
X788420Y-63070D01*
X788837Y-62820D01*
X789420Y-62737D01*
X789837Y-62820D01*
X790337Y-63070D01*
G01X793270Y-66070D02*
Y-61070D01*
G01Y-63570D02*
X793687Y-63070D01*
X794187Y-62820D01*
X794687Y-62737D01*
X795437Y-62903D01*
X795937Y-63237D01*
X796270Y-63820D01*
Y-64487D01*
X796103Y-65153D01*
X795770Y-65653D01*
X795187Y-65987D01*
X794687Y-66070D01*
X794187Y-65987D01*
X793687Y-65737D01*
X793270Y-65320D01*
G01X799120Y-63820D02*
X801787D01*
X801537Y-63237D01*
X801120Y-62903D01*
X800537Y-62737D01*
X799953Y-62820D01*
X799453Y-63070D01*
X799120Y-63653D01*
X798953Y-64153D01*
Y-64653D01*
X799120Y-65153D01*
X799537Y-65653D01*
X800037Y-65987D01*
X800620Y-66070D01*
X801203Y-65903D01*
X801787Y-65403D01*
G01X804803Y-66070D02*
Y-62737D01*
G01Y-63403D02*
X805220Y-63070D01*
X805637Y-62820D01*
X806220Y-62737D01*
X806637Y-62820D01*
X807137Y-63070D01*
G01X815753Y-66070D02*
Y-61070D01*
G01Y-63487D02*
X816170Y-63070D01*
X816587Y-62820D01*
X817253Y-62737D01*
X817753Y-62820D01*
X818337Y-63153D01*
X818587Y-63653D01*
Y-66070D01*
G01X824270D02*
Y-62737D01*
G01Y-63320D02*
X823937Y-62987D01*
X823437Y-62820D01*
X822853Y-62737D01*
X822270Y-62903D01*
X821770Y-63237D01*
X821437Y-63737D01*
X821270Y-64403D01*
X821437Y-65070D01*
X821770Y-65570D01*
X822270Y-65903D01*
X822853Y-66070D01*
X823437Y-65987D01*
X823937Y-65737D01*
X824270Y-65403D01*
G01X827120Y-65487D02*
X827537Y-65820D01*
X828120Y-66070D01*
X828620D01*
X829120Y-65903D01*
X829453Y-65653D01*
X829620Y-65320D01*
X829537Y-64820D01*
X829203Y-64570D01*
X827703Y-64070D01*
X827370Y-63487D01*
X827537Y-63070D01*
X827870Y-62820D01*
X828370Y-62737D01*
X828870Y-62820D01*
X829370Y-63070D01*
G01X839570Y-61070D02*
Y-66070D01*
G01X838403Y-62737D02*
X840737D01*
G01X843753Y-66070D02*
Y-61070D01*
G01Y-63487D02*
X844170Y-63070D01*
X844587Y-62820D01*
X845253Y-62737D01*
X845753Y-62820D01*
X846337Y-63153D01*
X846587Y-63653D01*
Y-66070D01*
G01X850770Y-62737D02*
Y-66070D01*
G01Y-61403D02*
X850603Y-61320D01*
Y-61153D01*
X850770Y-61070D01*
X850937Y-61153D01*
Y-61320D01*
X850770Y-61403D01*
G01X855120Y-65487D02*
X855537Y-65820D01*
X856120Y-66070D01*
X856620D01*
X857120Y-65903D01*
X857453Y-65653D01*
X857620Y-65320D01*
X857537Y-64820D01*
X857203Y-64570D01*
X855703Y-64070D01*
X855370Y-63487D01*
X855537Y-63070D01*
X855870Y-62820D01*
X856370Y-62737D01*
X856870Y-62820D01*
X857370Y-63070D01*
G01X866153Y-66070D02*
Y-61070D01*
G01X868820Y-62737D02*
X866153Y-64653D01*
G01X867237Y-63903D02*
X868987Y-66070D01*
G01X873170Y-62737D02*
Y-66070D01*
G01Y-61403D02*
X873003Y-61320D01*
Y-61153D01*
X873170Y-61070D01*
X873337Y-61153D01*
Y-61320D01*
X873170Y-61403D01*
G01X877353Y-66070D02*
Y-62737D01*
G01Y-63570D02*
X877687Y-63153D01*
X878187Y-62820D01*
X878853Y-62737D01*
X879437Y-62820D01*
X879937Y-63153D01*
X880187Y-63737D01*
Y-66070D01*
G01X885870Y-61070D02*
Y-66070D01*
G01Y-65320D02*
X885537Y-65737D01*
X885037Y-65987D01*
X884453Y-66070D01*
X883787Y-65903D01*
X883287Y-65487D01*
X882953Y-64987D01*
X882870Y-64403D01*
X882953Y-63820D01*
X883287Y-63320D01*
X883787Y-62903D01*
X884453Y-62737D01*
X885037Y-62820D01*
X885453Y-62987D01*
X885870Y-63320D01*
G01X895570Y-66070D02*
X895070Y-65987D01*
X894570Y-65653D01*
X894237Y-65070D01*
X894070Y-64403D01*
X894237Y-63737D01*
X894570Y-63153D01*
X895070Y-62820D01*
X895570Y-62737D01*
X896070Y-62820D01*
X896570Y-63153D01*
X896903Y-63737D01*
X896987Y-64403D01*
X896903Y-65070D01*
X896570Y-65653D01*
X896070Y-65987D01*
X895570Y-66070D01*
G01X900670D02*
Y-61820D01*
X900837Y-61403D01*
X901170Y-61153D01*
X901670Y-61070D01*
X902170Y-61237D01*
X902420Y-61653D01*
G01X901420Y-63070D02*
X899753D01*
G01X913870Y-61070D02*
Y-66070D01*
G01Y-65320D02*
X913537Y-65737D01*
X913037Y-65987D01*
X912453Y-66070D01*
X911787Y-65903D01*
X911287Y-65487D01*
X910953Y-64987D01*
X910870Y-64403D01*
X910953Y-63820D01*
X911287Y-63320D01*
X911787Y-62903D01*
X912453Y-62737D01*
X913037Y-62820D01*
X913453Y-62987D01*
X913870Y-63320D01*
G01X916720Y-63820D02*
X919387D01*
X919137Y-63237D01*
X918720Y-62903D01*
X918137Y-62737D01*
X917553Y-62820D01*
X917053Y-63070D01*
X916720Y-63653D01*
X916553Y-64153D01*
Y-64653D01*
X916720Y-65153D01*
X917137Y-65653D01*
X917637Y-65987D01*
X918220Y-66070D01*
X918803Y-65903D01*
X919387Y-65403D01*
G01X922320Y-65487D02*
X922737Y-65820D01*
X923320Y-66070D01*
X923820D01*
X924320Y-65903D01*
X924653Y-65653D01*
X924820Y-65320D01*
X924737Y-64820D01*
X924403Y-64570D01*
X922903Y-64070D01*
X922570Y-63487D01*
X922737Y-63070D01*
X923070Y-62820D01*
X923570Y-62737D01*
X924070Y-62820D01*
X924570Y-63070D01*
G01X929170Y-62737D02*
Y-66070D01*
G01Y-61403D02*
X929003Y-61320D01*
Y-61153D01*
X929170Y-61070D01*
X929337Y-61153D01*
Y-61320D01*
X929170Y-61403D01*
G01X933603Y-67320D02*
X934187Y-67653D01*
X934853Y-67737D01*
X935437Y-67653D01*
X935937Y-67237D01*
X936270Y-66653D01*
Y-62737D01*
G01Y-63403D02*
X935937Y-63070D01*
X935437Y-62820D01*
X934853Y-62737D01*
X934187Y-62903D01*
X933770Y-63237D01*
X933437Y-63820D01*
X933270Y-64403D01*
X933353Y-64903D01*
X933687Y-65487D01*
X934187Y-65903D01*
X934853Y-66070D01*
X935353Y-65987D01*
X935937Y-65653D01*
X936270Y-65320D01*
G01X938953Y-66070D02*
Y-62737D01*
G01Y-63570D02*
X939287Y-63153D01*
X939787Y-62820D01*
X940453Y-62737D01*
X941037Y-62820D01*
X941537Y-63153D01*
X941787Y-63737D01*
Y-66070D01*
G01X945803Y-66987D02*
X946137Y-65903D01*
G01X955670Y-67737D02*
Y-62737D01*
G01Y-63487D02*
X956087Y-63070D01*
X956503Y-62820D01*
X957170Y-62737D01*
X957753Y-62820D01*
X958337Y-63237D01*
X958587Y-63820D01*
X958670Y-64403D01*
X958587Y-64987D01*
X958337Y-65570D01*
X957837Y-65903D01*
X957170Y-66070D01*
X956587Y-65987D01*
X956003Y-65737D01*
X955670Y-65403D01*
G01X962770Y-66070D02*
Y-61070D01*
G01X967120Y-63820D02*
X969787D01*
X969537Y-63237D01*
X969120Y-62903D01*
X968537Y-62737D01*
X967953Y-62820D01*
X967453Y-63070D01*
X967120Y-63653D01*
X966953Y-64153D01*
Y-64653D01*
X967120Y-65153D01*
X967537Y-65653D01*
X968037Y-65987D01*
X968620Y-66070D01*
X969203Y-65903D01*
X969787Y-65403D01*
G01X975470Y-66070D02*
Y-62737D01*
G01Y-63320D02*
X975137Y-62987D01*
X974637Y-62820D01*
X974053Y-62737D01*
X973470Y-62903D01*
X972970Y-63237D01*
X972637Y-63737D01*
X972470Y-64403D01*
X972637Y-65070D01*
X972970Y-65570D01*
X973470Y-65903D01*
X974053Y-66070D01*
X974637Y-65987D01*
X975137Y-65737D01*
X975470Y-65403D01*
G01X978320Y-65487D02*
X978737Y-65820D01*
X979320Y-66070D01*
X979820D01*
X980320Y-65903D01*
X980653Y-65653D01*
X980820Y-65320D01*
X980737Y-64820D01*
X980403Y-64570D01*
X978903Y-64070D01*
X978570Y-63487D01*
X978737Y-63070D01*
X979070Y-62820D01*
X979570Y-62737D01*
X980070Y-62820D01*
X980570Y-63070D01*
G01X983920Y-63820D02*
X986587D01*
X986337Y-63237D01*
X985920Y-62903D01*
X985337Y-62737D01*
X984753Y-62820D01*
X984253Y-63070D01*
X983920Y-63653D01*
X983753Y-64153D01*
Y-64653D01*
X983920Y-65153D01*
X984337Y-65653D01*
X984837Y-65987D01*
X985420Y-66070D01*
X986003Y-65903D01*
X986587Y-65403D01*
G01X995870Y-66070D02*
Y-61820D01*
X996037Y-61403D01*
X996370Y-61153D01*
X996870Y-61070D01*
X997370Y-61237D01*
X997620Y-61653D01*
G01X996620Y-63070D02*
X994953D01*
G01X1001970Y-66070D02*
X1001470Y-65987D01*
X1000970Y-65653D01*
X1000637Y-65070D01*
X1000470Y-64403D01*
X1000637Y-63737D01*
X1000970Y-63153D01*
X1001470Y-62820D01*
X1001970Y-62737D01*
X1002470Y-62820D01*
X1002970Y-63153D01*
X1003303Y-63737D01*
X1003387Y-64403D01*
X1003303Y-65070D01*
X1002970Y-65653D01*
X1002470Y-65987D01*
X1001970Y-66070D01*
G01X1007570D02*
Y-61070D01*
G01X1013170Y-66070D02*
Y-61070D01*
G01X1018770Y-66070D02*
X1018270Y-65987D01*
X1017770Y-65653D01*
X1017437Y-65070D01*
X1017270Y-64403D01*
X1017437Y-63737D01*
X1017770Y-63153D01*
X1018270Y-62820D01*
X1018770Y-62737D01*
X1019270Y-62820D01*
X1019770Y-63153D01*
X1020103Y-63737D01*
X1020187Y-64403D01*
X1020103Y-65070D01*
X1019770Y-65653D01*
X1019270Y-65987D01*
X1018770Y-66070D01*
G01X1022287Y-62737D02*
X1023287Y-66070D01*
X1024370Y-62737D01*
X1025453Y-66070D01*
X1026453Y-62737D01*
G01X1029970Y-66237D02*
X1029803Y-66153D01*
Y-65987D01*
X1029970Y-65903D01*
X1030137Y-65987D01*
Y-66153D01*
X1029970Y-66237D01*
G01X1040170Y-61070D02*
X1042170D01*
G01X1041170D02*
Y-66070D01*
G01X1040170D02*
X1042170D01*
G01X1046270D02*
Y-61820D01*
X1046437Y-61403D01*
X1046770Y-61153D01*
X1047270Y-61070D01*
X1047770Y-61237D01*
X1048020Y-61653D01*
G01X1047020Y-63070D02*
X1045353D01*
G01X1056553Y-66070D02*
Y-62737D01*
G01Y-63570D02*
X1056887Y-63153D01*
X1057387Y-62820D01*
X1058053Y-62737D01*
X1058637Y-62820D01*
X1059137Y-63153D01*
X1059387Y-63737D01*
Y-66070D01*
G01X1063570D02*
X1063070Y-65987D01*
X1062570Y-65653D01*
X1062237Y-65070D01*
X1062070Y-64403D01*
X1062237Y-63737D01*
X1062570Y-63153D01*
X1063070Y-62820D01*
X1063570Y-62737D01*
X1064070Y-62820D01*
X1064570Y-63153D01*
X1064903Y-63737D01*
X1064987Y-64403D01*
X1064903Y-65070D01*
X1064570Y-65653D01*
X1064070Y-65987D01*
X1063570Y-66070D01*
G01X1069170Y-61070D02*
Y-66070D01*
G01X1068003Y-62737D02*
X1070337D01*
G01X1074603Y-66987D02*
X1074937Y-65903D01*
G01X1084470Y-67737D02*
Y-62737D01*
G01Y-63487D02*
X1084887Y-63070D01*
X1085303Y-62820D01*
X1085970Y-62737D01*
X1086553Y-62820D01*
X1087137Y-63237D01*
X1087387Y-63820D01*
X1087470Y-64403D01*
X1087387Y-64987D01*
X1087137Y-65570D01*
X1086637Y-65903D01*
X1085970Y-66070D01*
X1085387Y-65987D01*
X1084803Y-65737D01*
X1084470Y-65403D01*
G01X1091570Y-66070D02*
Y-61070D01*
G01X1095920Y-63820D02*
X1098587D01*
X1098337Y-63237D01*
X1097920Y-62903D01*
X1097337Y-62737D01*
X1096753Y-62820D01*
X1096253Y-63070D01*
X1095920Y-63653D01*
X1095753Y-64153D01*
Y-64653D01*
X1095920Y-65153D01*
X1096337Y-65653D01*
X1096837Y-65987D01*
X1097420Y-66070D01*
X1098003Y-65903D01*
X1098587Y-65403D01*
G01X1104270Y-66070D02*
Y-62737D01*
G01Y-63320D02*
X1103937Y-62987D01*
X1103437Y-62820D01*
X1102853Y-62737D01*
X1102270Y-62903D01*
X1101770Y-63237D01*
X1101437Y-63737D01*
X1101270Y-64403D01*
X1101437Y-65070D01*
X1101770Y-65570D01*
X1102270Y-65903D01*
X1102853Y-66070D01*
X1103437Y-65987D01*
X1103937Y-65737D01*
X1104270Y-65403D01*
G01X1107120Y-65487D02*
X1107537Y-65820D01*
X1108120Y-66070D01*
X1108620D01*
X1109120Y-65903D01*
X1109453Y-65653D01*
X1109620Y-65320D01*
X1109537Y-64820D01*
X1109203Y-64570D01*
X1107703Y-64070D01*
X1107370Y-63487D01*
X1107537Y-63070D01*
X1107870Y-62820D01*
X1108370Y-62737D01*
X1108870Y-62820D01*
X1109370Y-63070D01*
G01X1112720Y-63820D02*
X1115387D01*
X1115137Y-63237D01*
X1114720Y-62903D01*
X1114137Y-62737D01*
X1113553Y-62820D01*
X1113053Y-63070D01*
X1112720Y-63653D01*
X1112553Y-64153D01*
Y-64653D01*
X1112720Y-65153D01*
X1113137Y-65653D01*
X1113637Y-65987D01*
X1114220Y-66070D01*
X1114803Y-65903D01*
X1115387Y-65403D01*
G01X1125170Y-62737D02*
Y-66070D01*
G01Y-61403D02*
X1125003Y-61320D01*
Y-61153D01*
X1125170Y-61070D01*
X1125337Y-61153D01*
Y-61320D01*
X1125170Y-61403D01*
G01X1132270Y-67737D02*
Y-62737D01*
G01Y-63487D02*
X1131853Y-63070D01*
X1131353Y-62820D01*
X1130770Y-62737D01*
X1130270Y-62820D01*
X1129687Y-63237D01*
X1129353Y-63820D01*
X1129270Y-64403D01*
X1129353Y-64987D01*
X1129687Y-65570D01*
X1130270Y-65987D01*
X1130770Y-66070D01*
X1131353Y-65987D01*
X1131853Y-65737D01*
X1132270Y-65320D01*
G01X1134953Y-66070D02*
Y-62737D01*
G01Y-63570D02*
X1135287Y-63153D01*
X1135787Y-62820D01*
X1136453Y-62737D01*
X1137037Y-62820D01*
X1137537Y-63153D01*
X1137787Y-63737D01*
Y-66070D01*
G01X1141970D02*
X1141470Y-65987D01*
X1140970Y-65653D01*
X1140637Y-65070D01*
X1140470Y-64403D01*
X1140637Y-63737D01*
X1140970Y-63153D01*
X1141470Y-62820D01*
X1141970Y-62737D01*
X1142470Y-62820D01*
X1142970Y-63153D01*
X1143303Y-63737D01*
X1143387Y-64403D01*
X1143303Y-65070D01*
X1142970Y-65653D01*
X1142470Y-65987D01*
X1141970Y-66070D01*
G01X1146403D02*
Y-62737D01*
G01Y-63403D02*
X1146820Y-63070D01*
X1147237Y-62820D01*
X1147820Y-62737D01*
X1148237Y-62820D01*
X1148737Y-63070D01*
G01X1151920Y-63820D02*
X1154587D01*
X1154337Y-63237D01*
X1153920Y-62903D01*
X1153337Y-62737D01*
X1152753Y-62820D01*
X1152253Y-63070D01*
X1151920Y-63653D01*
X1151753Y-64153D01*
Y-64653D01*
X1151920Y-65153D01*
X1152337Y-65653D01*
X1152837Y-65987D01*
X1153420Y-66070D01*
X1154003Y-65903D01*
X1154587Y-65403D01*
G01X1164370Y-61070D02*
Y-66070D01*
G01X1163203Y-62737D02*
X1165537D01*
G01X1168553Y-66070D02*
Y-61070D01*
G01Y-63487D02*
X1168970Y-63070D01*
X1169387Y-62820D01*
X1170053Y-62737D01*
X1170553Y-62820D01*
X1171137Y-63153D01*
X1171387Y-63653D01*
Y-66070D01*
G01X1175570Y-62737D02*
Y-66070D01*
G01Y-61403D02*
X1175403Y-61320D01*
Y-61153D01*
X1175570Y-61070D01*
X1175737Y-61153D01*
Y-61320D01*
X1175570Y-61403D01*
G01X1179920Y-65487D02*
X1180337Y-65820D01*
X1180920Y-66070D01*
X1181420D01*
X1181920Y-65903D01*
X1182253Y-65653D01*
X1182420Y-65320D01*
X1182337Y-64820D01*
X1182003Y-64570D01*
X1180503Y-64070D01*
X1180170Y-63487D01*
X1180337Y-63070D01*
X1180670Y-62820D01*
X1181170Y-62737D01*
X1181670Y-62820D01*
X1182170Y-63070D01*
G01X1191203Y-66070D02*
Y-62737D01*
G01Y-63403D02*
X1191620Y-63070D01*
X1192037Y-62820D01*
X1192620Y-62737D01*
X1193037Y-62820D01*
X1193537Y-63070D01*
G01X1196720Y-63820D02*
X1199387D01*
X1199137Y-63237D01*
X1198720Y-62903D01*
X1198137Y-62737D01*
X1197553Y-62820D01*
X1197053Y-63070D01*
X1196720Y-63653D01*
X1196553Y-64153D01*
Y-64653D01*
X1196720Y-65153D01*
X1197137Y-65653D01*
X1197637Y-65987D01*
X1198220Y-66070D01*
X1198803Y-65903D01*
X1199387Y-65403D01*
G01X1205070Y-67737D02*
Y-62737D01*
G01Y-63487D02*
X1204653Y-63070D01*
X1204153Y-62820D01*
X1203570Y-62737D01*
X1203070Y-62820D01*
X1202487Y-63237D01*
X1202153Y-63820D01*
X1202070Y-64403D01*
X1202153Y-64987D01*
X1202487Y-65570D01*
X1203070Y-65987D01*
X1203570Y-66070D01*
X1204153Y-65987D01*
X1204653Y-65737D01*
X1205070Y-65320D01*
G01X1207753Y-62737D02*
Y-65070D01*
X1208087Y-65653D01*
X1208587Y-65987D01*
X1209170Y-66070D01*
X1209753Y-65987D01*
X1210253Y-65653D01*
X1210587Y-65070D01*
G01Y-66070D02*
Y-62737D01*
G01X1213520Y-63820D02*
X1216187D01*
X1215937Y-63237D01*
X1215520Y-62903D01*
X1214937Y-62737D01*
X1214353Y-62820D01*
X1213853Y-63070D01*
X1213520Y-63653D01*
X1213353Y-64153D01*
Y-64653D01*
X1213520Y-65153D01*
X1213937Y-65653D01*
X1214437Y-65987D01*
X1215020Y-66070D01*
X1215603Y-65903D01*
X1216187Y-65403D01*
G01X1219120Y-65487D02*
X1219537Y-65820D01*
X1220120Y-66070D01*
X1220620D01*
X1221120Y-65903D01*
X1221453Y-65653D01*
X1221620Y-65320D01*
X1221537Y-64820D01*
X1221203Y-64570D01*
X1219703Y-64070D01*
X1219370Y-63487D01*
X1219537Y-63070D01*
X1219870Y-62820D01*
X1220370Y-62737D01*
X1220870Y-62820D01*
X1221370Y-63070D01*
G01X1225970Y-61070D02*
Y-66070D01*
G01X1224803Y-62737D02*
X1227137D01*
G01X1231570Y-66237D02*
X1231403Y-66153D01*
Y-65987D01*
X1231570Y-65903D01*
X1231737Y-65987D01*
Y-66153D01*
X1231570Y-66237D01*
G01X722667Y-38250D02*
X723167Y-38667D01*
X723750Y-38917D01*
X724500Y-39000D01*
X725250Y-38833D01*
X725833Y-38500D01*
X726250Y-37917D01*
X726333Y-37250D01*
X726167Y-36583D01*
X725750Y-36167D01*
X725167Y-35833D01*
X724583Y-35750D01*
X724000Y-35833D01*
X723250Y-36167D01*
X723500Y-34000D01*
X725750D01*
G01X730100Y-39167D02*
X729933Y-39083D01*
Y-38917D01*
X730100Y-38833D01*
X730267Y-38917D01*
Y-39083D01*
X730100Y-39167D01*
G01X739633Y-39000D02*
Y-34000D01*
X741717D01*
X742383Y-34250D01*
X742800Y-34583D01*
X742967Y-35250D01*
X742800Y-35917D01*
X742300Y-36333D01*
X741717Y-36583D01*
X739633D01*
G01X741717D02*
X742967Y-39000D01*
G01X745650Y-36750D02*
X748317D01*
X748067Y-36167D01*
X747650Y-35833D01*
X747067Y-35667D01*
X746483Y-35750D01*
X745983Y-36000D01*
X745650Y-36583D01*
X745483Y-37083D01*
Y-37583D01*
X745650Y-38083D01*
X746067Y-38583D01*
X746567Y-38917D01*
X747150Y-39000D01*
X747733Y-38833D01*
X748317Y-38333D01*
G01X750000Y-39000D02*
Y-35667D01*
G01Y-36583D02*
X750250Y-36167D01*
X750667Y-35833D01*
X751250Y-35667D01*
X751833Y-35833D01*
X752250Y-36167D01*
X752500Y-36583D01*
Y-39000D01*
G01Y-36583D02*
X752750Y-36167D01*
X753167Y-35833D01*
X753750Y-35667D01*
X754333Y-35833D01*
X754750Y-36167D01*
X755000Y-36667D01*
Y-39000D01*
G01X759600D02*
Y-35667D01*
G01Y-36250D02*
X759267Y-35917D01*
X758767Y-35750D01*
X758183Y-35667D01*
X757600Y-35833D01*
X757100Y-36167D01*
X756767Y-36667D01*
X756600Y-37333D01*
X756767Y-38000D01*
X757100Y-38500D01*
X757600Y-38833D01*
X758183Y-39000D01*
X758767Y-38917D01*
X759267Y-38667D01*
X759600Y-38333D01*
G01X762533Y-39000D02*
Y-35667D01*
G01Y-36333D02*
X762950Y-36000D01*
X763367Y-35750D01*
X763950Y-35667D01*
X764367Y-35750D01*
X764867Y-36000D01*
G01X767883Y-39000D02*
Y-34000D01*
G01X770550Y-35667D02*
X767883Y-37583D01*
G01X768967Y-36833D02*
X770717Y-39000D01*
G01X773067Y-39167D02*
X776733Y-35500D01*
G01X774900Y-34833D02*
Y-39833D01*
G01X776733Y-39167D02*
X773067Y-35500D01*
G01X772400Y-37333D02*
X777400D01*
G01X713000Y-53000D02*
X1343000D01*
G01X713000Y-23000D02*
X1343000D01*
G01X713000Y85500D02*
X1343000D01*
G01X725500Y349500D02*
Y354500D01*
X722417Y350917D01*
X726583D01*
G01X730100Y349333D02*
X729933Y349417D01*
Y349583D01*
X730100Y349667D01*
X730267Y349583D01*
Y349417D01*
X730100Y349333D01*
G01X739800Y349500D02*
Y354500D01*
G01Y352000D02*
X740217Y352500D01*
X740717Y352750D01*
X741217Y352833D01*
X741967Y352667D01*
X742467Y352333D01*
X742800Y351750D01*
Y351083D01*
X742633Y350417D01*
X742300Y349917D01*
X741717Y349583D01*
X741217Y349500D01*
X740717Y349583D01*
X740217Y349833D01*
X739800Y350250D01*
G01X748400Y349500D02*
Y352833D01*
G01Y352250D02*
X748067Y352583D01*
X747567Y352750D01*
X746983Y352833D01*
X746400Y352667D01*
X745900Y352333D01*
X745567Y351833D01*
X745400Y351167D01*
X745567Y350500D01*
X745900Y350000D01*
X746400Y349667D01*
X746983Y349500D01*
X747567Y349583D01*
X748067Y349833D01*
X748400Y350167D01*
G01X753833Y352417D02*
X753250Y352750D01*
X752750Y352833D01*
X752083Y352667D01*
X751583Y352333D01*
X751250Y351750D01*
X751167Y351167D01*
X751250Y350583D01*
X751583Y350083D01*
X752083Y349667D01*
X752750Y349500D01*
X753333Y349667D01*
X753833Y350000D01*
G01X756683Y349500D02*
Y354500D01*
G01X759350Y352833D02*
X756683Y350917D01*
G01X757767Y351667D02*
X759517Y349500D01*
G01X765200Y354500D02*
Y349500D01*
G01Y350250D02*
X764867Y349833D01*
X764367Y349583D01*
X763783Y349500D01*
X763117Y349667D01*
X762617Y350083D01*
X762283Y350583D01*
X762200Y351167D01*
X762283Y351750D01*
X762617Y352250D01*
X763117Y352667D01*
X763783Y352833D01*
X764367Y352750D01*
X764783Y352583D01*
X765200Y352250D01*
G01X768133Y349500D02*
Y352833D01*
G01Y352167D02*
X768550Y352500D01*
X768967Y352750D01*
X769550Y352833D01*
X769967Y352750D01*
X770467Y352500D01*
G01X774900Y352833D02*
Y349500D01*
G01Y354167D02*
X774733Y354250D01*
Y354417D01*
X774900Y354500D01*
X775067Y354417D01*
Y354250D01*
X774900Y354167D01*
G01X780500Y349500D02*
Y354500D01*
G01X786100Y349500D02*
Y354500D01*
G01X798800Y349500D02*
Y352833D01*
G01Y352250D02*
X798467Y352583D01*
X797967Y352750D01*
X797383Y352833D01*
X796800Y352667D01*
X796300Y352333D01*
X795967Y351833D01*
X795800Y351167D01*
X795967Y350500D01*
X796300Y350000D01*
X796800Y349667D01*
X797383Y349500D01*
X797967Y349583D01*
X798467Y349833D01*
X798800Y350167D01*
G01X801483Y349500D02*
Y352833D01*
G01Y352000D02*
X801817Y352417D01*
X802317Y352750D01*
X802983Y352833D01*
X803567Y352750D01*
X804067Y352417D01*
X804317Y351833D01*
Y349500D01*
G01X810000Y354500D02*
Y349500D01*
G01Y350250D02*
X809667Y349833D01*
X809167Y349583D01*
X808583Y349500D01*
X807917Y349667D01*
X807417Y350083D01*
X807083Y350583D01*
X807000Y351167D01*
X807083Y351750D01*
X807417Y352250D01*
X807917Y352667D01*
X808583Y352833D01*
X809167Y352750D01*
X809583Y352583D01*
X810000Y352250D01*
G01X818450Y350083D02*
X818867Y349750D01*
X819450Y349500D01*
X819950D01*
X820450Y349667D01*
X820783Y349917D01*
X820950Y350250D01*
X820867Y350750D01*
X820533Y351000D01*
X819033Y351500D01*
X818700Y352083D01*
X818867Y352500D01*
X819200Y352750D01*
X819700Y352833D01*
X820200Y352750D01*
X820700Y352500D01*
G01X826800Y347833D02*
Y352833D01*
G01Y352083D02*
X826383Y352500D01*
X825883Y352750D01*
X825300Y352833D01*
X824800Y352750D01*
X824217Y352333D01*
X823883Y351750D01*
X823800Y351167D01*
X823883Y350583D01*
X824217Y350000D01*
X824800Y349583D01*
X825300Y349500D01*
X825883Y349583D01*
X826383Y349833D01*
X826800Y350250D01*
G01X829483Y352833D02*
Y350500D01*
X829817Y349917D01*
X830317Y349583D01*
X830900Y349500D01*
X831483Y349583D01*
X831983Y349917D01*
X832317Y350500D01*
G01Y349500D02*
Y352833D01*
G01X838000Y349500D02*
Y352833D01*
G01Y352250D02*
X837667Y352583D01*
X837167Y352750D01*
X836583Y352833D01*
X836000Y352667D01*
X835500Y352333D01*
X835167Y351833D01*
X835000Y351167D01*
X835167Y350500D01*
X835500Y350000D01*
X836000Y349667D01*
X836583Y349500D01*
X837167Y349583D01*
X837667Y349833D01*
X838000Y350167D01*
G01X840933Y349500D02*
Y352833D01*
G01Y352167D02*
X841350Y352500D01*
X841767Y352750D01*
X842350Y352833D01*
X842767Y352750D01*
X843267Y352500D01*
G01X846450Y351750D02*
X849117D01*
X848867Y352333D01*
X848450Y352667D01*
X847867Y352833D01*
X847283Y352750D01*
X846783Y352500D01*
X846450Y351917D01*
X846283Y351417D01*
Y350917D01*
X846450Y350417D01*
X846867Y349917D01*
X847367Y349583D01*
X847950Y349500D01*
X848533Y349667D01*
X849117Y350167D01*
G01X857483Y349500D02*
Y354500D01*
G01Y352083D02*
X857900Y352500D01*
X858317Y352750D01*
X858983Y352833D01*
X859483Y352750D01*
X860067Y352417D01*
X860317Y351917D01*
Y349500D01*
G01X864500D02*
X864000Y349583D01*
X863500Y349917D01*
X863167Y350500D01*
X863000Y351167D01*
X863167Y351833D01*
X863500Y352417D01*
X864000Y352750D01*
X864500Y352833D01*
X865000Y352750D01*
X865500Y352417D01*
X865833Y351833D01*
X865917Y351167D01*
X865833Y350500D01*
X865500Y349917D01*
X865000Y349583D01*
X864500Y349500D01*
G01X870100D02*
Y354500D01*
G01X874450Y351750D02*
X877117D01*
X876867Y352333D01*
X876450Y352667D01*
X875867Y352833D01*
X875283Y352750D01*
X874783Y352500D01*
X874450Y351917D01*
X874283Y351417D01*
Y350917D01*
X874450Y350417D01*
X874867Y349917D01*
X875367Y349583D01*
X875950Y349500D01*
X876533Y349667D01*
X877117Y350167D01*
G01X881300Y349333D02*
X881133Y349417D01*
Y349583D01*
X881300Y349667D01*
X881467Y349583D01*
Y349417D01*
X881300Y349333D01*
G01Y351583D02*
X881133Y351667D01*
Y351833D01*
X881300Y351917D01*
X881467Y351833D01*
Y351667D01*
X881300Y351583D01*
G01X713000Y335500D02*
X1343000D01*
G01X721407Y374673D02*
X725073Y378340D01*
G01X723240Y379007D02*
Y374007D01*
G01X725073Y374673D02*
X721407Y378340D01*
G01X720740Y376507D02*
X725740D01*
G01X728423Y373173D02*
X727590Y374007D01*
X727173Y374840D01*
Y378173D01*
X727590Y379007D01*
X728423Y379840D01*
G01X732607Y375590D02*
X733107Y375173D01*
X733690Y374923D01*
X734440Y374840D01*
X735190Y375007D01*
X735773Y375340D01*
X736190Y375923D01*
X736273Y376590D01*
X736107Y377257D01*
X735690Y377673D01*
X735107Y378007D01*
X734523Y378090D01*
X733940Y378007D01*
X733190Y377673D01*
X733440Y379840D01*
X735690D01*
G01X740040Y374673D02*
X739873Y374757D01*
Y374923D01*
X740040Y375007D01*
X740207Y374923D01*
Y374757D01*
X740040Y374673D01*
G01X745640Y374840D02*
Y379840D01*
X744640Y378840D01*
G01Y374840D02*
X746640D01*
G01X751657Y373173D02*
X752490Y374007D01*
X752907Y374840D01*
Y378173D01*
X752490Y379007D01*
X751657Y379840D01*
G01X721217Y391740D02*
X723300Y386740D01*
X725383Y391740D01*
G01X728900Y390073D02*
Y386740D01*
G01Y391407D02*
X728733Y391490D01*
Y391657D01*
X728900Y391740D01*
X729067Y391657D01*
Y391490D01*
X728900Y391407D01*
G01X736000Y386740D02*
Y390073D01*
G01Y389490D02*
X735667Y389823D01*
X735167Y389990D01*
X734583Y390073D01*
X734000Y389907D01*
X733500Y389573D01*
X733167Y389073D01*
X733000Y388407D01*
X733167Y387740D01*
X733500Y387240D01*
X734000Y386907D01*
X734583Y386740D01*
X735167Y386823D01*
X735667Y387073D01*
X736000Y387407D01*
G01X744700Y391740D02*
X746700D01*
G01X745700D02*
Y386740D01*
G01X744700D02*
X746700D01*
G01X749883D02*
Y390073D01*
G01Y389240D02*
X750217Y389657D01*
X750717Y389990D01*
X751383Y390073D01*
X751967Y389990D01*
X752467Y389657D01*
X752717Y389073D01*
Y386740D01*
G01X760833D02*
Y391740D01*
X762833D01*
X763500Y391490D01*
X764000Y390907D01*
X764167Y390240D01*
X764000Y389573D01*
X763583Y389073D01*
X762833Y388823D01*
X760833D01*
G01X769600Y386740D02*
Y390073D01*
G01Y389490D02*
X769267Y389823D01*
X768767Y389990D01*
X768183Y390073D01*
X767600Y389907D01*
X767100Y389573D01*
X766767Y389073D01*
X766600Y388407D01*
X766767Y387740D01*
X767100Y387240D01*
X767600Y386907D01*
X768183Y386740D01*
X768767Y386823D01*
X769267Y387073D01*
X769600Y387407D01*
G01X775200Y391740D02*
Y386740D01*
G01Y387490D02*
X774867Y387073D01*
X774367Y386823D01*
X773783Y386740D01*
X773117Y386907D01*
X772617Y387323D01*
X772283Y387823D01*
X772200Y388407D01*
X772283Y388990D01*
X772617Y389490D01*
X773117Y389907D01*
X773783Y390073D01*
X774367Y389990D01*
X774783Y389823D01*
X775200Y389490D01*
G01X778883Y385073D02*
X778050Y385907D01*
X777633Y386740D01*
Y390073D01*
X778050Y390907D01*
X778883Y391740D01*
G01X782817D02*
X784900Y386740D01*
X786983Y391740D01*
G01X789500D02*
X791500D01*
G01X790500D02*
Y386740D01*
G01X789500D02*
X791500D01*
G01X794433D02*
Y391740D01*
X796433D01*
X797100Y391490D01*
X797600Y390907D01*
X797767Y390240D01*
X797600Y389573D01*
X797183Y389073D01*
X796433Y388823D01*
X794433D01*
G01X802117Y385073D02*
X802950Y385907D01*
X803367Y386740D01*
Y390073D01*
X802950Y390907D01*
X802117Y391740D01*
G01X713000Y365500D02*
X1343000D01*
G01X713000Y400500D02*
X1343000D01*
G01X721107Y408303D02*
X724773Y411970D01*
G01X722940Y412637D02*
Y407637D01*
G01X724773Y408303D02*
X721107Y411970D01*
G01X720440Y410137D02*
X725440D01*
G01X728123Y406803D02*
X727290Y407637D01*
X726873Y408470D01*
Y411803D01*
X727290Y412637D01*
X728123Y413470D01*
G01X732307Y409220D02*
X732807Y408803D01*
X733390Y408553D01*
X734140Y408470D01*
X734890Y408637D01*
X735473Y408970D01*
X735890Y409553D01*
X735973Y410220D01*
X735807Y410887D01*
X735390Y411303D01*
X734807Y411637D01*
X734223Y411720D01*
X733640Y411637D01*
X732890Y411303D01*
X733140Y413470D01*
X735390D01*
G01X739740Y408303D02*
X739573Y408387D01*
Y408553D01*
X739740Y408637D01*
X739907Y408553D01*
Y408387D01*
X739740Y408303D01*
G01X745340Y408470D02*
Y413470D01*
X744340Y412470D01*
G01Y408470D02*
X746340D01*
G01X751357Y406803D02*
X752190Y407637D01*
X752607Y408470D01*
Y411803D01*
X752190Y412637D01*
X751357Y413470D01*
G01X720917Y424500D02*
X723000Y419500D01*
X725083Y424500D01*
G01X728600Y422833D02*
Y419500D01*
G01Y424167D02*
X728433Y424250D01*
Y424417D01*
X728600Y424500D01*
X728767Y424417D01*
Y424250D01*
X728600Y424167D01*
G01X735700Y419500D02*
Y422833D01*
G01Y422250D02*
X735367Y422583D01*
X734867Y422750D01*
X734283Y422833D01*
X733700Y422667D01*
X733200Y422333D01*
X732867Y421833D01*
X732700Y421167D01*
X732867Y420500D01*
X733200Y420000D01*
X733700Y419667D01*
X734283Y419500D01*
X734867Y419583D01*
X735367Y419833D01*
X735700Y420167D01*
G01X745400Y419500D02*
X744733Y419583D01*
X744150Y419917D01*
X743650Y420417D01*
X743317Y421000D01*
X743150Y421667D01*
Y422333D01*
X743317Y423000D01*
X743650Y423583D01*
X744150Y424083D01*
X744733Y424417D01*
X745400Y424500D01*
X746067Y424417D01*
X746650Y424083D01*
X747150Y423583D01*
X747483Y423000D01*
X747650Y422333D01*
Y421667D01*
X747483Y421000D01*
X747150Y420417D01*
X746650Y419917D01*
X746067Y419583D01*
X745400Y419500D01*
G01X749583D02*
Y422833D01*
G01Y422000D02*
X749917Y422417D01*
X750417Y422750D01*
X751083Y422833D01*
X751667Y422750D01*
X752167Y422417D01*
X752417Y421833D01*
Y419500D01*
G01X760533D02*
Y424500D01*
X762533D01*
X763200Y424250D01*
X763700Y423667D01*
X763867Y423000D01*
X763700Y422333D01*
X763283Y421833D01*
X762533Y421583D01*
X760533D01*
G01X769300Y419500D02*
Y422833D01*
G01Y422250D02*
X768967Y422583D01*
X768467Y422750D01*
X767883Y422833D01*
X767300Y422667D01*
X766800Y422333D01*
X766467Y421833D01*
X766300Y421167D01*
X766467Y420500D01*
X766800Y420000D01*
X767300Y419667D01*
X767883Y419500D01*
X768467Y419583D01*
X768967Y419833D01*
X769300Y420167D01*
G01X774900Y424500D02*
Y419500D01*
G01Y420250D02*
X774567Y419833D01*
X774067Y419583D01*
X773483Y419500D01*
X772817Y419667D01*
X772317Y420083D01*
X771983Y420583D01*
X771900Y421167D01*
X771983Y421750D01*
X772317Y422250D01*
X772817Y422667D01*
X773483Y422833D01*
X774067Y422750D01*
X774483Y422583D01*
X774900Y422250D01*
G01X778583Y417833D02*
X777750Y418667D01*
X777333Y419500D01*
Y422833D01*
X777750Y423667D01*
X778583Y424500D01*
G01X782517D02*
X784600Y419500D01*
X786683Y424500D01*
G01X790200Y419500D02*
X789533Y419583D01*
X788950Y419917D01*
X788450Y420417D01*
X788117Y421000D01*
X787950Y421667D01*
Y422333D01*
X788117Y423000D01*
X788450Y423583D01*
X788950Y424083D01*
X789533Y424417D01*
X790200Y424500D01*
X790867Y424417D01*
X791450Y424083D01*
X791950Y423583D01*
X792283Y423000D01*
X792450Y422333D01*
Y421667D01*
X792283Y421000D01*
X791950Y420417D01*
X791450Y419917D01*
X790867Y419583D01*
X790200Y419500D01*
G01X794133D02*
Y424500D01*
X796133D01*
X796800Y424250D01*
X797300Y423667D01*
X797467Y423000D01*
X797300Y422333D01*
X796883Y421833D01*
X796133Y421583D01*
X794133D01*
G01X801817Y417833D02*
X802650Y418667D01*
X803067Y419500D01*
Y422833D01*
X802650Y423667D01*
X801817Y424500D01*
G01X723667Y443167D02*
X724000Y443417D01*
X724250Y443833D01*
X724417Y444417D01*
X724250Y444917D01*
X723917Y445250D01*
X723333Y445500D01*
X721083D01*
Y440500D01*
X723833D01*
X724417Y440833D01*
X724750Y441333D01*
X724917Y441917D01*
X724750Y442500D01*
X724250Y443000D01*
X723667Y443167D01*
X721083D01*
G01X727183Y443833D02*
Y441500D01*
X727517Y440917D01*
X728017Y440583D01*
X728600Y440500D01*
X729183Y440583D01*
X729683Y440917D01*
X730017Y441500D01*
G01Y440500D02*
Y443833D01*
G01X733033Y440500D02*
Y443833D01*
G01Y443167D02*
X733450Y443500D01*
X733867Y443750D01*
X734450Y443833D01*
X734867Y443750D01*
X735367Y443500D01*
G01X739800Y443833D02*
Y440500D01*
G01Y445167D02*
X739633Y445250D01*
Y445417D01*
X739800Y445500D01*
X739967Y445417D01*
Y445250D01*
X739800Y445167D01*
G01X744150Y442750D02*
X746817D01*
X746567Y443333D01*
X746150Y443667D01*
X745567Y443833D01*
X744983Y443750D01*
X744483Y443500D01*
X744150Y442917D01*
X743983Y442417D01*
Y441917D01*
X744150Y441417D01*
X744567Y440917D01*
X745067Y440583D01*
X745650Y440500D01*
X746233Y440667D01*
X746817Y441167D01*
G01X752500Y445500D02*
Y440500D01*
G01Y441250D02*
X752167Y440833D01*
X751667Y440583D01*
X751083Y440500D01*
X750417Y440667D01*
X749917Y441083D01*
X749583Y441583D01*
X749500Y442167D01*
X749583Y442750D01*
X749917Y443250D01*
X750417Y443667D01*
X751083Y443833D01*
X751667Y443750D01*
X752083Y443583D01*
X752500Y443250D01*
G01X760783Y440500D02*
Y445500D01*
G01Y443083D02*
X761200Y443500D01*
X761617Y443750D01*
X762283Y443833D01*
X762783Y443750D01*
X763367Y443417D01*
X763617Y442917D01*
Y440500D01*
G01X767800D02*
X767300Y440583D01*
X766800Y440917D01*
X766467Y441500D01*
X766300Y442167D01*
X766467Y442833D01*
X766800Y443417D01*
X767300Y443750D01*
X767800Y443833D01*
X768300Y443750D01*
X768800Y443417D01*
X769133Y442833D01*
X769217Y442167D01*
X769133Y441500D01*
X768800Y440917D01*
X768300Y440583D01*
X767800Y440500D01*
G01X773400D02*
Y445500D01*
G01X777750Y442750D02*
X780417D01*
X780167Y443333D01*
X779750Y443667D01*
X779167Y443833D01*
X778583Y443750D01*
X778083Y443500D01*
X777750Y442917D01*
X777583Y442417D01*
Y441917D01*
X777750Y441417D01*
X778167Y440917D01*
X778667Y440583D01*
X779250Y440500D01*
X779833Y440667D01*
X780417Y441167D01*
G01X713000Y435500D02*
X1343000D01*
G01X713000Y450500D02*
X1343000D01*
G01X721417Y461500D02*
Y466500D01*
X724583D01*
G01X723417Y464083D02*
X721417D01*
G01X727183Y464833D02*
Y462500D01*
X727517Y461917D01*
X728017Y461583D01*
X728600Y461500D01*
X729183Y461583D01*
X729683Y461917D01*
X730017Y462500D01*
G01Y461500D02*
Y464833D01*
G01X734200Y461500D02*
Y466500D01*
G01X739800Y461500D02*
Y466500D01*
G01X749500Y459833D02*
Y464833D01*
G01Y464083D02*
X749917Y464500D01*
X750333Y464750D01*
X751000Y464833D01*
X751583Y464750D01*
X752167Y464333D01*
X752417Y463750D01*
X752500Y463167D01*
X752417Y462583D01*
X752167Y462000D01*
X751667Y461667D01*
X751000Y461500D01*
X750417Y461583D01*
X749833Y461833D01*
X749500Y462167D01*
G01X756600Y461500D02*
Y466500D01*
G01X760783Y464833D02*
Y462500D01*
X761117Y461917D01*
X761617Y461583D01*
X762200Y461500D01*
X762783Y461583D01*
X763283Y461917D01*
X763617Y462500D01*
G01Y461500D02*
Y464833D01*
G01X766633Y460250D02*
X767217Y459917D01*
X767883Y459833D01*
X768467Y459917D01*
X768967Y460333D01*
X769300Y460917D01*
Y464833D01*
G01Y464167D02*
X768967Y464500D01*
X768467Y464750D01*
X767883Y464833D01*
X767217Y464667D01*
X766800Y464333D01*
X766467Y463750D01*
X766300Y463167D01*
X766383Y462667D01*
X766717Y462083D01*
X767217Y461667D01*
X767883Y461500D01*
X768383Y461583D01*
X768967Y461917D01*
X769300Y462250D01*
G01X772233Y460250D02*
X772817Y459917D01*
X773483Y459833D01*
X774067Y459917D01*
X774567Y460333D01*
X774900Y460917D01*
Y464833D01*
G01Y464167D02*
X774567Y464500D01*
X774067Y464750D01*
X773483Y464833D01*
X772817Y464667D01*
X772400Y464333D01*
X772067Y463750D01*
X771900Y463167D01*
X771983Y462667D01*
X772317Y462083D01*
X772817Y461667D01*
X773483Y461500D01*
X773983Y461583D01*
X774567Y461917D01*
X774900Y462250D01*
G01X779000Y464833D02*
Y461500D01*
G01Y466167D02*
X778833Y466250D01*
Y466417D01*
X779000Y466500D01*
X779167Y466417D01*
Y466250D01*
X779000Y466167D01*
G01X783183Y461500D02*
Y464833D01*
G01Y464000D02*
X783517Y464417D01*
X784017Y464750D01*
X784683Y464833D01*
X785267Y464750D01*
X785767Y464417D01*
X786017Y463833D01*
Y461500D01*
G01X789033Y460250D02*
X789617Y459917D01*
X790283Y459833D01*
X790867Y459917D01*
X791367Y460333D01*
X791700Y460917D01*
Y464833D01*
G01Y464167D02*
X791367Y464500D01*
X790867Y464750D01*
X790283Y464833D01*
X789617Y464667D01*
X789200Y464333D01*
X788867Y463750D01*
X788700Y463167D01*
X788783Y462667D01*
X789117Y462083D01*
X789617Y461667D01*
X790283Y461500D01*
X790783Y461583D01*
X791367Y461917D01*
X791700Y462250D01*
G01X713000Y477500D02*
X1343000D01*
G01X721250Y530000D02*
Y535000D01*
G01X724750D02*
Y530000D01*
G01Y532500D02*
X721250D01*
G01X730100Y530000D02*
Y533333D01*
G01Y532750D02*
X729767Y533083D01*
X729267Y533250D01*
X728683Y533333D01*
X728100Y533167D01*
X727600Y532833D01*
X727267Y532333D01*
X727100Y531667D01*
X727267Y531000D01*
X727600Y530500D01*
X728100Y530167D01*
X728683Y530000D01*
X729267Y530083D01*
X729767Y530333D01*
X730100Y530667D01*
G01X734200Y530000D02*
Y535000D01*
G01X739300Y530000D02*
Y534250D01*
X739467Y534667D01*
X739800Y534917D01*
X740300Y535000D01*
X740800Y534833D01*
X741050Y534417D01*
G01X740050Y533000D02*
X738383D01*
G01X749333Y530000D02*
Y535000D01*
X751333D01*
X752000Y534750D01*
X752500Y534167D01*
X752667Y533500D01*
X752500Y532833D01*
X752083Y532333D01*
X751333Y532083D01*
X749333D01*
G01X756600Y530000D02*
Y535000D01*
G01X760783Y533333D02*
Y531000D01*
X761117Y530417D01*
X761617Y530083D01*
X762200Y530000D01*
X762783Y530083D01*
X763283Y530417D01*
X763617Y531000D01*
G01Y530000D02*
Y533333D01*
G01X766633Y528750D02*
X767217Y528417D01*
X767883Y528333D01*
X768467Y528417D01*
X768967Y528833D01*
X769300Y529417D01*
Y533333D01*
G01Y532667D02*
X768967Y533000D01*
X768467Y533250D01*
X767883Y533333D01*
X767217Y533167D01*
X766800Y532833D01*
X766467Y532250D01*
X766300Y531667D01*
X766383Y531167D01*
X766717Y530583D01*
X767217Y530167D01*
X767883Y530000D01*
X768383Y530083D01*
X768967Y530417D01*
X769300Y530750D01*
G01X772233Y528750D02*
X772817Y528417D01*
X773483Y528333D01*
X774067Y528417D01*
X774567Y528833D01*
X774900Y529417D01*
Y533333D01*
G01Y532667D02*
X774567Y533000D01*
X774067Y533250D01*
X773483Y533333D01*
X772817Y533167D01*
X772400Y532833D01*
X772067Y532250D01*
X771900Y531667D01*
X771983Y531167D01*
X772317Y530583D01*
X772817Y530167D01*
X773483Y530000D01*
X773983Y530083D01*
X774567Y530417D01*
X774900Y530750D01*
G01X779000Y533333D02*
Y530000D01*
G01Y534667D02*
X778833Y534750D01*
Y534917D01*
X779000Y535000D01*
X779167Y534917D01*
Y534750D01*
X779000Y534667D01*
G01X783183Y530000D02*
Y533333D01*
G01Y532500D02*
X783517Y532917D01*
X784017Y533250D01*
X784683Y533333D01*
X785267Y533250D01*
X785767Y532917D01*
X786017Y532333D01*
Y530000D01*
G01X789033Y528750D02*
X789617Y528417D01*
X790283Y528333D01*
X790867Y528417D01*
X791367Y528833D01*
X791700Y529417D01*
Y533333D01*
G01Y532667D02*
X791367Y533000D01*
X790867Y533250D01*
X790283Y533333D01*
X789617Y533167D01*
X789200Y532833D01*
X788867Y532250D01*
X788700Y531667D01*
X788783Y531167D01*
X789117Y530583D01*
X789617Y530167D01*
X790283Y530000D01*
X790783Y530083D01*
X791367Y530417D01*
X791700Y530750D01*
G01X722833Y589000D02*
Y594000D01*
X724833D01*
X725500Y593750D01*
X726000Y593167D01*
X726167Y592500D01*
X726000Y591833D01*
X725583Y591333D01*
X724833Y591083D01*
X722833D01*
G01X730100Y589000D02*
Y594000D01*
G01X734283Y592333D02*
Y590000D01*
X734617Y589417D01*
X735117Y589083D01*
X735700Y589000D01*
X736283Y589083D01*
X736783Y589417D01*
X737117Y590000D01*
G01Y589000D02*
Y592333D01*
G01X740133Y587750D02*
X740717Y587417D01*
X741383Y587333D01*
X741967Y587417D01*
X742467Y587833D01*
X742800Y588417D01*
Y592333D01*
G01Y591667D02*
X742467Y592000D01*
X741967Y592250D01*
X741383Y592333D01*
X740717Y592167D01*
X740300Y591833D01*
X739967Y591250D01*
X739800Y590667D01*
X739883Y590167D01*
X740217Y589583D01*
X740717Y589167D01*
X741383Y589000D01*
X741883Y589083D01*
X742467Y589417D01*
X742800Y589750D01*
G01X745733Y587750D02*
X746317Y587417D01*
X746983Y587333D01*
X747567Y587417D01*
X748067Y587833D01*
X748400Y588417D01*
Y592333D01*
G01Y591667D02*
X748067Y592000D01*
X747567Y592250D01*
X746983Y592333D01*
X746317Y592167D01*
X745900Y591833D01*
X745567Y591250D01*
X745400Y590667D01*
X745483Y590167D01*
X745817Y589583D01*
X746317Y589167D01*
X746983Y589000D01*
X747483Y589083D01*
X748067Y589417D01*
X748400Y589750D01*
G01X752500Y592333D02*
Y589000D01*
G01Y593667D02*
X752333Y593750D01*
Y593917D01*
X752500Y594000D01*
X752667Y593917D01*
Y593750D01*
X752500Y593667D01*
G01X756683Y589000D02*
Y592333D01*
G01Y591500D02*
X757017Y591917D01*
X757517Y592250D01*
X758183Y592333D01*
X758767Y592250D01*
X759267Y591917D01*
X759517Y591333D01*
Y589000D01*
G01X762533Y587750D02*
X763117Y587417D01*
X763783Y587333D01*
X764367Y587417D01*
X764867Y587833D01*
X765200Y588417D01*
Y592333D01*
G01Y591667D02*
X764867Y592000D01*
X764367Y592250D01*
X763783Y592333D01*
X763117Y592167D01*
X762700Y591833D01*
X762367Y591250D01*
X762200Y590667D01*
X762283Y590167D01*
X762617Y589583D01*
X763117Y589167D01*
X763783Y589000D01*
X764283Y589083D01*
X764867Y589417D01*
X765200Y589750D01*
G01X776400Y594000D02*
Y589000D01*
G01Y589750D02*
X776067Y589333D01*
X775567Y589083D01*
X774983Y589000D01*
X774317Y589167D01*
X773817Y589583D01*
X773483Y590083D01*
X773400Y590667D01*
X773483Y591250D01*
X773817Y591750D01*
X774317Y592167D01*
X774983Y592333D01*
X775567Y592250D01*
X775983Y592083D01*
X776400Y591750D01*
G01X779250Y591250D02*
X781917D01*
X781667Y591833D01*
X781250Y592167D01*
X780667Y592333D01*
X780083Y592250D01*
X779583Y592000D01*
X779250Y591417D01*
X779083Y590917D01*
Y590417D01*
X779250Y589917D01*
X779667Y589417D01*
X780167Y589083D01*
X780750Y589000D01*
X781333Y589167D01*
X781917Y589667D01*
G01X785600Y589000D02*
Y593250D01*
X785767Y593667D01*
X786100Y593917D01*
X786600Y594000D01*
X787100Y593833D01*
X787350Y593417D01*
G01X786350Y592000D02*
X784683D01*
G01X791700Y592333D02*
Y589000D01*
G01Y593667D02*
X791533Y593750D01*
Y593917D01*
X791700Y594000D01*
X791867Y593917D01*
Y593750D01*
X791700Y593667D01*
G01X795883Y589000D02*
Y592333D01*
G01Y591500D02*
X796217Y591917D01*
X796717Y592250D01*
X797383Y592333D01*
X797967Y592250D01*
X798467Y591917D01*
X798717Y591333D01*
Y589000D01*
G01X801650Y591250D02*
X804317D01*
X804067Y591833D01*
X803650Y592167D01*
X803067Y592333D01*
X802483Y592250D01*
X801983Y592000D01*
X801650Y591417D01*
X801483Y590917D01*
Y590417D01*
X801650Y589917D01*
X802067Y589417D01*
X802567Y589083D01*
X803150Y589000D01*
X803733Y589167D01*
X804317Y589667D01*
G01X713000Y579500D02*
X1343000D01*
G01X713000Y604500D02*
X1343000D01*
G01X722667Y765000D02*
X723167Y764417D01*
X723833Y764083D01*
X724583Y764000D01*
X725250Y764083D01*
X725917Y764500D01*
X726333Y765000D01*
X726417Y765500D01*
X726250Y766083D01*
X725667Y766500D01*
X725083Y766667D01*
X724333D01*
G01X725083D02*
X725583Y766917D01*
X726000Y767333D01*
X726167Y767833D01*
X726000Y768333D01*
X725583Y768750D01*
X724833Y769000D01*
X724083Y768917D01*
X723333Y768583D01*
G01X730100Y763833D02*
X729933Y763917D01*
Y764083D01*
X730100Y764167D01*
X730267Y764083D01*
Y763917D01*
X730100Y763833D01*
G01X739633Y764000D02*
Y769000D01*
X741633D01*
X742300Y768750D01*
X742800Y768167D01*
X742967Y767500D01*
X742800Y766833D01*
X742383Y766333D01*
X741633Y766083D01*
X739633D01*
G01X746900Y764000D02*
Y769000D01*
G01X751083Y767333D02*
Y765000D01*
X751417Y764417D01*
X751917Y764083D01*
X752500Y764000D01*
X753083Y764083D01*
X753583Y764417D01*
X753917Y765000D01*
G01Y764000D02*
Y767333D01*
G01X756933Y762750D02*
X757517Y762417D01*
X758183Y762333D01*
X758767Y762417D01*
X759267Y762833D01*
X759600Y763417D01*
Y767333D01*
G01Y766667D02*
X759267Y767000D01*
X758767Y767250D01*
X758183Y767333D01*
X757517Y767167D01*
X757100Y766833D01*
X756767Y766250D01*
X756600Y765667D01*
X756683Y765167D01*
X757017Y764583D01*
X757517Y764167D01*
X758183Y764000D01*
X758683Y764083D01*
X759267Y764417D01*
X759600Y764750D01*
G01X767800Y767333D02*
X769300Y764000D01*
X770800Y767333D01*
G01X774900D02*
Y764000D01*
G01Y768667D02*
X774733Y768750D01*
Y768917D01*
X774900Y769000D01*
X775067Y768917D01*
Y768750D01*
X774900Y768667D01*
G01X782000Y764000D02*
Y767333D01*
G01Y766750D02*
X781667Y767083D01*
X781167Y767250D01*
X780583Y767333D01*
X780000Y767167D01*
X779500Y766833D01*
X779167Y766333D01*
X779000Y765667D01*
X779167Y765000D01*
X779500Y764500D01*
X780000Y764167D01*
X780583Y764000D01*
X781167Y764083D01*
X781667Y764333D01*
X782000Y764667D01*
G01X790200Y763833D02*
X793200Y769000D01*
G01X795217D02*
X797300Y764000D01*
X799383Y769000D01*
G01X802900Y764000D02*
X802233Y764083D01*
X801650Y764417D01*
X801150Y764917D01*
X800817Y765500D01*
X800650Y766167D01*
Y766833D01*
X800817Y767500D01*
X801150Y768083D01*
X801650Y768583D01*
X802233Y768917D01*
X802900Y769000D01*
X803567Y768917D01*
X804150Y768583D01*
X804650Y768083D01*
X804983Y767500D01*
X805150Y766833D01*
Y766167D01*
X804983Y765500D01*
X804650Y764917D01*
X804150Y764417D01*
X803567Y764083D01*
X802900Y764000D01*
G01X806833D02*
Y769000D01*
X808833D01*
X809500Y768750D01*
X810000Y768167D01*
X810167Y767500D01*
X810000Y766833D01*
X809583Y766333D01*
X808833Y766083D01*
X806833D01*
G01X812600Y763833D02*
X815600Y769000D01*
G01X817617D02*
X819700Y764000D01*
X821783Y769000D01*
G01X824300D02*
X826300D01*
G01X825300D02*
Y764000D01*
G01X824300D02*
X826300D01*
G01X829233D02*
Y769000D01*
X831233D01*
X831900Y768750D01*
X832400Y768167D01*
X832567Y767500D01*
X832400Y766833D01*
X831983Y766333D01*
X831233Y766083D01*
X829233D01*
G01X836500Y763833D02*
X836333Y763917D01*
Y764083D01*
X836500Y764167D01*
X836667Y764083D01*
Y763917D01*
X836500Y763833D01*
G01Y766083D02*
X836333Y766167D01*
Y766333D01*
X836500Y766417D01*
X836667Y766333D01*
Y766167D01*
X836500Y766083D01*
G01X713000Y752000D02*
X1344500D01*
G01X724813Y813000D02*
Y818000D01*
X726897D01*
X727563Y817750D01*
X727980Y817417D01*
X728147Y816750D01*
X727980Y816083D01*
X727480Y815667D01*
X726897Y815417D01*
X724813D01*
G01X726897D02*
X728147Y813000D01*
G01X732080D02*
X731580Y813083D01*
X731080Y813417D01*
X730747Y814000D01*
X730580Y814667D01*
X730747Y815333D01*
X731080Y815917D01*
X731580Y816250D01*
X732080Y816333D01*
X732580Y816250D01*
X733080Y815917D01*
X733413Y815333D01*
X733497Y814667D01*
X733413Y814000D01*
X733080Y813417D01*
X732580Y813083D01*
X732080Y813000D01*
G01X736263Y816333D02*
Y814000D01*
X736597Y813417D01*
X737097Y813083D01*
X737680Y813000D01*
X738263Y813083D01*
X738763Y813417D01*
X739097Y814000D01*
G01Y813000D02*
Y816333D01*
G01X743280Y818000D02*
Y813000D01*
G01X742113Y816333D02*
X744447D01*
G01X748880D02*
Y813000D01*
G01Y817667D02*
X748713Y817750D01*
Y817917D01*
X748880Y818000D01*
X749047Y817917D01*
Y817750D01*
X748880Y817667D01*
G01X753063Y813000D02*
Y816333D01*
G01Y815500D02*
X753397Y815917D01*
X753897Y816250D01*
X754563Y816333D01*
X755147Y816250D01*
X755647Y815917D01*
X755897Y815333D01*
Y813000D01*
G01X758913Y811750D02*
X759497Y811417D01*
X760163Y811333D01*
X760747Y811417D01*
X761247Y811833D01*
X761580Y812417D01*
Y816333D01*
G01Y815667D02*
X761247Y816000D01*
X760747Y816250D01*
X760163Y816333D01*
X759497Y816167D01*
X759080Y815833D01*
X758747Y815250D01*
X758580Y814667D01*
X758663Y814167D01*
X758997Y813583D01*
X759497Y813167D01*
X760163Y813000D01*
X760663Y813083D01*
X761247Y813417D01*
X761580Y813750D01*
G01X712980Y850500D02*
X1343000D01*
G01X802167Y-15500D02*
Y-10500D01*
X803833D01*
X804500Y-10750D01*
X805000Y-11083D01*
X805417Y-11583D01*
X805750Y-12167D01*
X805833Y-13000D01*
X805750Y-13833D01*
X805417Y-14417D01*
X805000Y-14917D01*
X804500Y-15250D01*
X803833Y-15500D01*
X802167D01*
G01X809600D02*
Y-10500D01*
X808600Y-11500D01*
G01Y-15500D02*
X810600D01*
G01X813617Y-13417D02*
X814200Y-12833D01*
X814700Y-12500D01*
X815367Y-12333D01*
X815950Y-12500D01*
X816367Y-12833D01*
X816700Y-13333D01*
X816783Y-13917D01*
X816700Y-14417D01*
X816367Y-14917D01*
X815867Y-15333D01*
X815283Y-15500D01*
X814617Y-15333D01*
X814033Y-14833D01*
X813700Y-14083D01*
X813617Y-13250D01*
X813783Y-12167D01*
X814033Y-11583D01*
X814450Y-11000D01*
X815033Y-10583D01*
X815617Y-10500D01*
X816200Y-10667D01*
X816617Y-11083D01*
G01X777583Y104700D02*
Y99700D01*
X780917D01*
G01X783600Y103033D02*
X786100Y99700D01*
G01Y103033D02*
X783600Y99700D01*
G01X790450Y99533D02*
X790283Y99617D01*
Y99783D01*
X790450Y99867D01*
X790617Y99783D01*
Y99617D01*
X790450Y99533D01*
G01Y101783D02*
X790283Y101867D01*
Y102033D01*
X790450Y102117D01*
X790617Y102033D01*
Y101867D01*
X790450Y101783D01*
G01X799150Y99700D02*
Y103033D01*
G01Y102117D02*
X799400Y102533D01*
X799817Y102867D01*
X800400Y103033D01*
X800983Y102867D01*
X801400Y102533D01*
X801650Y102117D01*
Y99700D01*
G01Y102117D02*
X801900Y102533D01*
X802317Y102867D01*
X802900Y103033D01*
X803483Y102867D01*
X803900Y102533D01*
X804150Y102033D01*
Y99700D01*
G01X805833Y103033D02*
Y100700D01*
X806167Y100117D01*
X806667Y99783D01*
X807250Y99700D01*
X807833Y99783D01*
X808333Y100117D01*
X808667Y100700D01*
G01Y99700D02*
Y103033D01*
G01X811600Y100283D02*
X812017Y99950D01*
X812600Y99700D01*
X813100D01*
X813600Y99867D01*
X813933Y100117D01*
X814100Y100450D01*
X814017Y100950D01*
X813683Y101200D01*
X812183Y101700D01*
X811850Y102283D01*
X812017Y102700D01*
X812350Y102950D01*
X812850Y103033D01*
X813350Y102950D01*
X813850Y102700D01*
G01X818450Y104700D02*
Y99700D01*
G01X817283Y103033D02*
X819617D01*
G01X828150Y99700D02*
Y104700D01*
G01Y102200D02*
X828567Y102700D01*
X829067Y102950D01*
X829567Y103033D01*
X830317Y102867D01*
X830817Y102533D01*
X831150Y101950D01*
Y101283D01*
X830983Y100617D01*
X830650Y100117D01*
X830067Y99783D01*
X829567Y99700D01*
X829067Y99783D01*
X828567Y100033D01*
X828150Y100450D01*
G01X834000Y101950D02*
X836667D01*
X836417Y102533D01*
X836000Y102867D01*
X835417Y103033D01*
X834833Y102950D01*
X834333Y102700D01*
X834000Y102117D01*
X833833Y101617D01*
Y101117D01*
X834000Y100617D01*
X834417Y100117D01*
X834917Y99783D01*
X835500Y99700D01*
X836083Y99867D01*
X836667Y100367D01*
G01X844950Y99700D02*
Y104700D01*
G01Y102200D02*
X845367Y102700D01*
X845867Y102950D01*
X846367Y103033D01*
X847117Y102867D01*
X847617Y102533D01*
X847950Y101950D01*
Y101283D01*
X847783Y100617D01*
X847450Y100117D01*
X846867Y99783D01*
X846367Y99700D01*
X845867Y99783D01*
X845367Y100033D01*
X844950Y100450D01*
G01X850883Y99700D02*
Y103033D01*
G01Y102367D02*
X851300Y102700D01*
X851717Y102950D01*
X852300Y103033D01*
X852717Y102950D01*
X853217Y102700D01*
G01X857650Y99700D02*
X857150Y99783D01*
X856650Y100117D01*
X856317Y100700D01*
X856150Y101367D01*
X856317Y102033D01*
X856650Y102617D01*
X857150Y102950D01*
X857650Y103033D01*
X858150Y102950D01*
X858650Y102617D01*
X858983Y102033D01*
X859067Y101367D01*
X858983Y100700D01*
X858650Y100117D01*
X858150Y99783D01*
X857650Y99700D01*
G01X861833D02*
Y104700D01*
G01X864500Y103033D02*
X861833Y101117D01*
G01X862917Y101867D02*
X864667Y99700D01*
G01X867600Y101950D02*
X870267D01*
X870017Y102533D01*
X869600Y102867D01*
X869017Y103033D01*
X868433Y102950D01*
X867933Y102700D01*
X867600Y102117D01*
X867433Y101617D01*
Y101117D01*
X867600Y100617D01*
X868017Y100117D01*
X868517Y99783D01*
X869100Y99700D01*
X869683Y99867D01*
X870267Y100367D01*
G01X873033Y99700D02*
Y103033D01*
G01Y102200D02*
X873367Y102617D01*
X873867Y102950D01*
X874533Y103033D01*
X875117Y102950D01*
X875617Y102617D01*
X875867Y102033D01*
Y99700D01*
G01X885650D02*
Y104700D01*
G01X892750Y99700D02*
Y103033D01*
G01Y102450D02*
X892417Y102783D01*
X891917Y102950D01*
X891333Y103033D01*
X890750Y102867D01*
X890250Y102533D01*
X889917Y102033D01*
X889750Y101367D01*
X889917Y100700D01*
X890250Y100200D01*
X890750Y99867D01*
X891333Y99700D01*
X891917Y99783D01*
X892417Y100033D01*
X892750Y100367D01*
G01X895100Y98200D02*
X895600Y98033D01*
X896267Y98200D01*
X896683Y98533D01*
X897017Y98950D01*
X897517Y100283D01*
X898600Y103033D01*
G01X895933D02*
X897517Y100283D01*
G01X901200Y101950D02*
X903867D01*
X903617Y102533D01*
X903200Y102867D01*
X902617Y103033D01*
X902033Y102950D01*
X901533Y102700D01*
X901200Y102117D01*
X901033Y101617D01*
Y101117D01*
X901200Y100617D01*
X901617Y100117D01*
X902117Y99783D01*
X902700Y99700D01*
X903283Y99867D01*
X903867Y100367D01*
G01X906883Y99700D02*
Y103033D01*
G01Y102367D02*
X907300Y102700D01*
X907717Y102950D01*
X908300Y103033D01*
X908717Y102950D01*
X909217Y102700D01*
G01X776983Y116310D02*
Y111310D01*
X780317D01*
G01X782833D02*
Y114643D01*
G01Y113810D02*
X783167Y114227D01*
X783667Y114560D01*
X784333Y114643D01*
X784917Y114560D01*
X785417Y114227D01*
X785667Y113643D01*
Y111310D01*
G01X789850Y111143D02*
X789683Y111227D01*
Y111393D01*
X789850Y111477D01*
X790017Y111393D01*
Y111227D01*
X789850Y111143D01*
G01Y113393D02*
X789683Y113477D01*
Y113643D01*
X789850Y113727D01*
X790017Y113643D01*
Y113477D01*
X789850Y113393D01*
G01X802383Y114227D02*
X801800Y114560D01*
X801300Y114643D01*
X800633Y114477D01*
X800133Y114143D01*
X799800Y113560D01*
X799717Y112977D01*
X799800Y112393D01*
X800133Y111893D01*
X800633Y111477D01*
X801300Y111310D01*
X801883Y111477D01*
X802383Y111810D01*
G01X808150Y111310D02*
Y114643D01*
G01Y114060D02*
X807817Y114393D01*
X807317Y114560D01*
X806733Y114643D01*
X806150Y114477D01*
X805650Y114143D01*
X805317Y113643D01*
X805150Y112977D01*
X805317Y112310D01*
X805650Y111810D01*
X806150Y111477D01*
X806733Y111310D01*
X807317Y111393D01*
X807817Y111643D01*
X808150Y111977D01*
G01X810833Y111310D02*
Y114643D01*
G01Y113810D02*
X811167Y114227D01*
X811667Y114560D01*
X812333Y114643D01*
X812917Y114560D01*
X813417Y114227D01*
X813667Y113643D01*
Y111310D01*
G01X817850Y114643D02*
X818683Y115685D01*
Y116310D01*
X818058D01*
Y115685D01*
X818683D01*
G01X823450Y116310D02*
Y111310D01*
G01X822283Y114643D02*
X824617D01*
G01X833150Y111310D02*
Y116310D01*
G01Y113810D02*
X833567Y114310D01*
X834067Y114560D01*
X834567Y114643D01*
X835317Y114477D01*
X835817Y114143D01*
X836150Y113560D01*
Y112893D01*
X835983Y112227D01*
X835650Y111727D01*
X835067Y111393D01*
X834567Y111310D01*
X834067Y111393D01*
X833567Y111643D01*
X833150Y112060D01*
G01X839000Y113560D02*
X841667D01*
X841417Y114143D01*
X841000Y114477D01*
X840417Y114643D01*
X839833Y114560D01*
X839333Y114310D01*
X839000Y113727D01*
X838833Y113227D01*
Y112727D01*
X839000Y112227D01*
X839417Y111727D01*
X839917Y111393D01*
X840500Y111310D01*
X841083Y111477D01*
X841667Y111977D01*
G01X849950Y111310D02*
Y116310D01*
G01Y113810D02*
X850367Y114310D01*
X850867Y114560D01*
X851367Y114643D01*
X852117Y114477D01*
X852617Y114143D01*
X852950Y113560D01*
Y112893D01*
X852783Y112227D01*
X852450Y111727D01*
X851867Y111393D01*
X851367Y111310D01*
X850867Y111393D01*
X850367Y111643D01*
X849950Y112060D01*
G01X855883Y111310D02*
Y114643D01*
G01Y113977D02*
X856300Y114310D01*
X856717Y114560D01*
X857300Y114643D01*
X857717Y114560D01*
X858217Y114310D01*
G01X862650Y111310D02*
X862150Y111393D01*
X861650Y111727D01*
X861317Y112310D01*
X861150Y112977D01*
X861317Y113643D01*
X861650Y114227D01*
X862150Y114560D01*
X862650Y114643D01*
X863150Y114560D01*
X863650Y114227D01*
X863983Y113643D01*
X864067Y112977D01*
X863983Y112310D01*
X863650Y111727D01*
X863150Y111393D01*
X862650Y111310D01*
G01X866833D02*
Y116310D01*
G01X869500Y114643D02*
X866833Y112727D01*
G01X867917Y113477D02*
X869667Y111310D01*
G01X872600Y113560D02*
X875267D01*
X875017Y114143D01*
X874600Y114477D01*
X874017Y114643D01*
X873433Y114560D01*
X872933Y114310D01*
X872600Y113727D01*
X872433Y113227D01*
Y112727D01*
X872600Y112227D01*
X873017Y111727D01*
X873517Y111393D01*
X874100Y111310D01*
X874683Y111477D01*
X875267Y111977D01*
G01X878033Y111310D02*
Y114643D01*
G01Y113810D02*
X878367Y114227D01*
X878867Y114560D01*
X879533Y114643D01*
X880117Y114560D01*
X880617Y114227D01*
X880867Y113643D01*
Y111310D01*
G01X890650D02*
Y116310D01*
G01X897750Y111310D02*
Y114643D01*
G01Y114060D02*
X897417Y114393D01*
X896917Y114560D01*
X896333Y114643D01*
X895750Y114477D01*
X895250Y114143D01*
X894917Y113643D01*
X894750Y112977D01*
X894917Y112310D01*
X895250Y111810D01*
X895750Y111477D01*
X896333Y111310D01*
X896917Y111393D01*
X897417Y111643D01*
X897750Y111977D01*
G01X900100Y109810D02*
X900600Y109643D01*
X901267Y109810D01*
X901683Y110143D01*
X902017Y110560D01*
X902517Y111893D01*
X903600Y114643D01*
G01X900933D02*
X902517Y111893D01*
G01X906200Y113560D02*
X908867D01*
X908617Y114143D01*
X908200Y114477D01*
X907617Y114643D01*
X907033Y114560D01*
X906533Y114310D01*
X906200Y113727D01*
X906033Y113227D01*
Y112727D01*
X906200Y112227D01*
X906617Y111727D01*
X907117Y111393D01*
X907700Y111310D01*
X908283Y111477D01*
X908867Y111977D01*
G01X911883Y111310D02*
Y114643D01*
G01Y113977D02*
X912300Y114310D01*
X912717Y114560D01*
X913300Y114643D01*
X913717Y114560D01*
X914217Y114310D01*
G01X777167Y123000D02*
Y128000D01*
X778833D01*
X779500Y127750D01*
X780000Y127417D01*
X780417Y126917D01*
X780750Y126333D01*
X780833Y125500D01*
X780750Y124667D01*
X780417Y124083D01*
X780000Y123583D01*
X779500Y123250D01*
X778833Y123000D01*
X777167D01*
G01X783433D02*
Y126333D01*
G01Y125667D02*
X783850Y126000D01*
X784267Y126250D01*
X784850Y126333D01*
X785267Y126250D01*
X785767Y126000D01*
G01X790200Y126333D02*
Y123000D01*
G01Y127667D02*
X790033Y127750D01*
Y127917D01*
X790200Y128000D01*
X790367Y127917D01*
Y127750D01*
X790200Y127667D01*
G01X795800Y123000D02*
Y128000D01*
G01X801400Y123000D02*
Y128000D01*
G01X811017Y123000D02*
Y128000D01*
X814183D01*
G01X813017Y125583D02*
X811017D01*
G01X817033Y123000D02*
Y126333D01*
G01Y125667D02*
X817450Y126000D01*
X817867Y126250D01*
X818450Y126333D01*
X818867Y126250D01*
X819367Y126000D01*
G01X823800Y123000D02*
X823300Y123083D01*
X822800Y123417D01*
X822467Y124000D01*
X822300Y124667D01*
X822467Y125333D01*
X822800Y125917D01*
X823300Y126250D01*
X823800Y126333D01*
X824300Y126250D01*
X824800Y125917D01*
X825133Y125333D01*
X825217Y124667D01*
X825133Y124000D01*
X824800Y123417D01*
X824300Y123083D01*
X823800Y123000D01*
G01X826900D02*
Y126333D01*
G01Y125417D02*
X827150Y125833D01*
X827567Y126167D01*
X828150Y126333D01*
X828733Y126167D01*
X829150Y125833D01*
X829400Y125417D01*
Y123000D01*
G01Y125417D02*
X829650Y125833D01*
X830067Y126167D01*
X830650Y126333D01*
X831233Y126167D01*
X831650Y125833D01*
X831900Y125333D01*
Y123000D01*
G01X838933Y128000D02*
Y123000D01*
X842267D01*
G01X846200D02*
Y128000D01*
X845200Y127000D01*
G01Y123000D02*
X847200D01*
G01X856983Y121333D02*
X856150Y122167D01*
X855733Y123000D01*
Y126333D01*
X856150Y127167D01*
X856983Y128000D01*
G01X863000D02*
Y123000D01*
G01X861083Y128000D02*
X864917D01*
G01X868600Y123000D02*
X867933Y123083D01*
X867350Y123417D01*
X866850Y123917D01*
X866517Y124500D01*
X866350Y125167D01*
Y125833D01*
X866517Y126500D01*
X866850Y127083D01*
X867350Y127583D01*
X867933Y127917D01*
X868600Y128000D01*
X869267Y127917D01*
X869850Y127583D01*
X870350Y127083D01*
X870683Y126500D01*
X870850Y125833D01*
Y125167D01*
X870683Y124500D01*
X870350Y123917D01*
X869850Y123417D01*
X869267Y123083D01*
X868600Y123000D01*
G01X872533D02*
Y128000D01*
X874533D01*
X875200Y127750D01*
X875700Y127167D01*
X875867Y126500D01*
X875700Y125833D01*
X875283Y125333D01*
X874533Y125083D01*
X872533D01*
G01X880217Y121333D02*
X881050Y122167D01*
X881467Y123000D01*
Y126333D01*
X881050Y127167D01*
X880217Y128000D01*
G01X891000D02*
Y123000D01*
G01X889833Y126333D02*
X892167D01*
G01X896600Y123000D02*
X896100Y123083D01*
X895600Y123417D01*
X895267Y124000D01*
X895100Y124667D01*
X895267Y125333D01*
X895600Y125917D01*
X896100Y126250D01*
X896600Y126333D01*
X897100Y126250D01*
X897600Y125917D01*
X897933Y125333D01*
X898017Y124667D01*
X897933Y124000D01*
X897600Y123417D01*
X897100Y123083D01*
X896600Y123000D01*
G01X906133Y128000D02*
Y123000D01*
X909467D01*
G01X912150Y126333D02*
X914650Y123000D01*
G01Y126333D02*
X912150Y123000D01*
G01X794500Y674500D02*
Y669500D01*
G01X793333Y672833D02*
X795667D01*
G01X798683Y669500D02*
Y674500D01*
G01Y672083D02*
X799100Y672500D01*
X799517Y672750D01*
X800183Y672833D01*
X800683Y672750D01*
X801267Y672417D01*
X801517Y671917D01*
Y669500D01*
G01X805700Y672833D02*
Y669500D01*
G01Y674167D02*
X805533Y674250D01*
Y674417D01*
X805700Y674500D01*
X805867Y674417D01*
Y674250D01*
X805700Y674167D01*
G01X812633Y672417D02*
X812050Y672750D01*
X811550Y672833D01*
X810883Y672667D01*
X810383Y672333D01*
X810050Y671750D01*
X809967Y671167D01*
X810050Y670583D01*
X810383Y670083D01*
X810883Y669667D01*
X811550Y669500D01*
X812133Y669667D01*
X812633Y670000D01*
G01X815483Y669500D02*
Y674500D01*
G01X818150Y672833D02*
X815483Y670917D01*
G01X816567Y671667D02*
X818317Y669500D01*
G01X821083D02*
Y672833D01*
G01Y672000D02*
X821417Y672417D01*
X821917Y672750D01*
X822583Y672833D01*
X823167Y672750D01*
X823667Y672417D01*
X823917Y671833D01*
Y669500D01*
G01X826850Y671750D02*
X829517D01*
X829267Y672333D01*
X828850Y672667D01*
X828267Y672833D01*
X827683Y672750D01*
X827183Y672500D01*
X826850Y671917D01*
X826683Y671417D01*
Y670917D01*
X826850Y670417D01*
X827267Y669917D01*
X827767Y669583D01*
X828350Y669500D01*
X828933Y669667D01*
X829517Y670167D01*
G01X832450Y670083D02*
X832867Y669750D01*
X833450Y669500D01*
X833950D01*
X834450Y669667D01*
X834783Y669917D01*
X834950Y670250D01*
X834867Y670750D01*
X834533Y671000D01*
X833033Y671500D01*
X832700Y672083D01*
X832867Y672500D01*
X833200Y672750D01*
X833700Y672833D01*
X834200Y672750D01*
X834700Y672500D01*
G01X838050Y670083D02*
X838467Y669750D01*
X839050Y669500D01*
X839550D01*
X840050Y669667D01*
X840383Y669917D01*
X840550Y670250D01*
X840467Y670750D01*
X840133Y671000D01*
X838633Y671500D01*
X838300Y672083D01*
X838467Y672500D01*
X838800Y672750D01*
X839300Y672833D01*
X839800Y672750D01*
X840300Y672500D01*
G01X788000Y850610D02*
Y782110D01*
G01X798500Y795500D02*
Y790500D01*
G01X796583Y795500D02*
X800417D01*
G01X802017Y793833D02*
X803017Y790500D01*
X804100Y793833D01*
X805183Y790500D01*
X806183Y793833D01*
G01X809700D02*
Y790500D01*
G01Y795167D02*
X809533Y795250D01*
Y795417D01*
X809700Y795500D01*
X809867Y795417D01*
Y795250D01*
X809700Y795167D01*
G01X814050Y791083D02*
X814467Y790750D01*
X815050Y790500D01*
X815550D01*
X816050Y790667D01*
X816383Y790917D01*
X816550Y791250D01*
X816467Y791750D01*
X816133Y792000D01*
X814633Y792500D01*
X814300Y793083D01*
X814467Y793500D01*
X814800Y793750D01*
X815300Y793833D01*
X815800Y793750D01*
X816300Y793500D01*
G01X820900Y795500D02*
Y790500D01*
G01X819733Y793833D02*
X822067D01*
G01X833600Y790500D02*
Y793833D01*
G01Y793250D02*
X833267Y793583D01*
X832767Y793750D01*
X832183Y793833D01*
X831600Y793667D01*
X831100Y793333D01*
X830767Y792833D01*
X830600Y792167D01*
X830767Y791500D01*
X831100Y791000D01*
X831600Y790667D01*
X832183Y790500D01*
X832767Y790583D01*
X833267Y790833D01*
X833600Y791167D01*
G01X836283Y790500D02*
Y793833D01*
G01Y793000D02*
X836617Y793417D01*
X837117Y793750D01*
X837783Y793833D01*
X838367Y793750D01*
X838867Y793417D01*
X839117Y792833D01*
Y790500D01*
G01X844800Y795500D02*
Y790500D01*
G01Y791250D02*
X844467Y790833D01*
X843967Y790583D01*
X843383Y790500D01*
X842717Y790667D01*
X842217Y791083D01*
X841883Y791583D01*
X841800Y792167D01*
X841883Y792750D01*
X842217Y793250D01*
X842717Y793667D01*
X843383Y793833D01*
X843967Y793750D01*
X844383Y793583D01*
X844800Y793250D01*
G01X853000Y790500D02*
Y795500D01*
G01Y793000D02*
X853417Y793500D01*
X853917Y793750D01*
X854417Y793833D01*
X855167Y793667D01*
X855667Y793333D01*
X856000Y792750D01*
Y792083D01*
X855833Y791417D01*
X855500Y790917D01*
X854917Y790583D01*
X854417Y790500D01*
X853917Y790583D01*
X853417Y790833D01*
X853000Y791250D01*
G01X860100Y790500D02*
X859600Y790583D01*
X859100Y790917D01*
X858767Y791500D01*
X858600Y792167D01*
X858767Y792833D01*
X859100Y793417D01*
X859600Y793750D01*
X860100Y793833D01*
X860600Y793750D01*
X861100Y793417D01*
X861433Y792833D01*
X861517Y792167D01*
X861433Y791500D01*
X861100Y790917D01*
X860600Y790583D01*
X860100Y790500D01*
G01X863617Y793833D02*
X864617Y790500D01*
X865700Y793833D01*
X866783Y790500D01*
X867783Y793833D01*
G01X796833Y826500D02*
Y831500D01*
X798917D01*
X799583Y831250D01*
X800000Y830917D01*
X800167Y830250D01*
X800000Y829583D01*
X799500Y829167D01*
X798917Y828917D01*
X796833D01*
G01X798917D02*
X800167Y826500D01*
G01X804100D02*
X803600Y826583D01*
X803100Y826917D01*
X802767Y827500D01*
X802600Y828167D01*
X802767Y828833D01*
X803100Y829417D01*
X803600Y829750D01*
X804100Y829833D01*
X804600Y829750D01*
X805100Y829417D01*
X805433Y828833D01*
X805517Y828167D01*
X805433Y827500D01*
X805100Y826917D01*
X804600Y826583D01*
X804100Y826500D01*
G01X808283Y829833D02*
Y827500D01*
X808617Y826917D01*
X809117Y826583D01*
X809700Y826500D01*
X810283Y826583D01*
X810783Y826917D01*
X811117Y827500D01*
G01Y826500D02*
Y829833D01*
G01X815300Y831500D02*
Y826500D01*
G01X814133Y829833D02*
X816467D01*
G01X820900D02*
Y826500D01*
G01Y831167D02*
X820733Y831250D01*
Y831417D01*
X820900Y831500D01*
X821067Y831417D01*
Y831250D01*
X820900Y831167D01*
G01X825083Y826500D02*
Y829833D01*
G01Y829000D02*
X825417Y829417D01*
X825917Y829750D01*
X826583Y829833D01*
X827167Y829750D01*
X827667Y829417D01*
X827917Y828833D01*
Y826500D01*
G01X830933Y825250D02*
X831517Y824917D01*
X832183Y824833D01*
X832767Y824917D01*
X833267Y825333D01*
X833600Y825917D01*
Y829833D01*
G01Y829167D02*
X833267Y829500D01*
X832767Y829750D01*
X832183Y829833D01*
X831517Y829667D01*
X831100Y829333D01*
X830767Y828750D01*
X830600Y828167D01*
X830683Y827667D01*
X831017Y827083D01*
X831517Y826667D01*
X832183Y826500D01*
X832683Y826583D01*
X833267Y826917D01*
X833600Y827250D01*
G01X843300Y831500D02*
Y826500D01*
G01X842133Y829833D02*
X844467D01*
G01X848900Y826500D02*
X848400Y826583D01*
X847900Y826917D01*
X847567Y827500D01*
X847400Y828167D01*
X847567Y828833D01*
X847900Y829417D01*
X848400Y829750D01*
X848900Y829833D01*
X849400Y829750D01*
X849900Y829417D01*
X850233Y828833D01*
X850317Y828167D01*
X850233Y827500D01*
X849900Y826917D01*
X849400Y826583D01*
X848900Y826500D01*
G01X854500D02*
Y831500D01*
G01X858850Y828750D02*
X861517D01*
X861267Y829333D01*
X860850Y829667D01*
X860267Y829833D01*
X859683Y829750D01*
X859183Y829500D01*
X858850Y828917D01*
X858683Y828417D01*
Y827917D01*
X858850Y827417D01*
X859267Y826917D01*
X859767Y826583D01*
X860350Y826500D01*
X860933Y826667D01*
X861517Y827167D01*
G01X864533Y826500D02*
Y829833D01*
G01Y829167D02*
X864950Y829500D01*
X865367Y829750D01*
X865950Y829833D01*
X866367Y829750D01*
X866867Y829500D01*
G01X872800Y826500D02*
Y829833D01*
G01Y829250D02*
X872467Y829583D01*
X871967Y829750D01*
X871383Y829833D01*
X870800Y829667D01*
X870300Y829333D01*
X869967Y828833D01*
X869800Y828167D01*
X869967Y827500D01*
X870300Y827000D01*
X870800Y826667D01*
X871383Y826500D01*
X871967Y826583D01*
X872467Y826833D01*
X872800Y827167D01*
G01X875483Y826500D02*
Y829833D01*
G01Y829000D02*
X875817Y829417D01*
X876317Y829750D01*
X876983Y829833D01*
X877567Y829750D01*
X878067Y829417D01*
X878317Y828833D01*
Y826500D01*
G01X883833Y829417D02*
X883250Y829750D01*
X882750Y829833D01*
X882083Y829667D01*
X881583Y829333D01*
X881250Y828750D01*
X881167Y828167D01*
X881250Y827583D01*
X881583Y827083D01*
X882083Y826667D01*
X882750Y826500D01*
X883333Y826667D01*
X883833Y827000D01*
G01X886850Y828750D02*
X889517D01*
X889267Y829333D01*
X888850Y829667D01*
X888267Y829833D01*
X887683Y829750D01*
X887183Y829500D01*
X886850Y828917D01*
X886683Y828417D01*
Y827917D01*
X886850Y827417D01*
X887267Y826917D01*
X887767Y826583D01*
X888350Y826500D01*
X888933Y826667D01*
X889517Y827167D01*
G01X788000Y805500D02*
X1343000D01*
G01X827667Y150500D02*
Y155500D01*
X829333D01*
X830000Y155250D01*
X830500Y154917D01*
X830917Y154417D01*
X831250Y153833D01*
X831333Y153000D01*
X831250Y152167D01*
X830917Y151583D01*
X830500Y151083D01*
X830000Y150750D01*
X829333Y150500D01*
X827667D01*
G01X835100D02*
Y155500D01*
X834100Y154500D01*
G01Y150500D02*
X836100D01*
G01X825667Y314500D02*
Y319500D01*
X827333D01*
X828000Y319250D01*
X828500Y318917D01*
X828917Y318417D01*
X829250Y317833D01*
X829333Y317000D01*
X829250Y316167D01*
X828917Y315583D01*
X828500Y315083D01*
X828000Y314750D01*
X827333Y314500D01*
X825667D01*
G01X831517Y318667D02*
X832017Y319167D01*
X832600Y319417D01*
X833267Y319500D01*
X834100Y319333D01*
X834683Y318917D01*
X834850Y318417D01*
X834767Y317917D01*
X834433Y317500D01*
X832767Y316667D01*
X832017Y316083D01*
X831517Y315250D01*
X831350Y314500D01*
X834850D01*
G01X821590Y376450D02*
Y379783D01*
G01Y379200D02*
X821257Y379533D01*
X820757Y379700D01*
X820173Y379783D01*
X819590Y379617D01*
X819090Y379283D01*
X818757Y378783D01*
X818590Y378117D01*
X818757Y377450D01*
X819090Y376950D01*
X819590Y376617D01*
X820173Y376450D01*
X820757Y376533D01*
X821257Y376783D01*
X821590Y377117D01*
G01X824273Y376450D02*
Y379783D01*
G01Y378950D02*
X824607Y379367D01*
X825107Y379700D01*
X825773Y379783D01*
X826357Y379700D01*
X826857Y379367D01*
X827107Y378783D01*
Y376450D01*
G01X832790Y381450D02*
Y376450D01*
G01Y377200D02*
X832457Y376783D01*
X831957Y376533D01*
X831373Y376450D01*
X830707Y376617D01*
X830207Y377033D01*
X829873Y377533D01*
X829790Y378117D01*
X829873Y378700D01*
X830207Y379200D01*
X830707Y379617D01*
X831373Y379783D01*
X831957Y379700D01*
X832373Y379533D01*
X832790Y379200D01*
G01X843823Y379367D02*
X843240Y379700D01*
X842740Y379783D01*
X842073Y379617D01*
X841573Y379283D01*
X841240Y378700D01*
X841157Y378117D01*
X841240Y377533D01*
X841573Y377033D01*
X842073Y376617D01*
X842740Y376450D01*
X843323Y376617D01*
X843823Y376950D01*
G01X848090Y376450D02*
X847590Y376533D01*
X847090Y376867D01*
X846757Y377450D01*
X846590Y378117D01*
X846757Y378783D01*
X847090Y379367D01*
X847590Y379700D01*
X848090Y379783D01*
X848590Y379700D01*
X849090Y379367D01*
X849423Y378783D01*
X849507Y378117D01*
X849423Y377450D01*
X849090Y376867D01*
X848590Y376533D01*
X848090Y376450D01*
G01X852190Y379783D02*
X853690Y376450D01*
X855190Y379783D01*
G01X858040Y378700D02*
X860707D01*
X860457Y379283D01*
X860040Y379617D01*
X859457Y379783D01*
X858873Y379700D01*
X858373Y379450D01*
X858040Y378867D01*
X857873Y378367D01*
Y377867D01*
X858040Y377367D01*
X858457Y376867D01*
X858957Y376533D01*
X859540Y376450D01*
X860123Y376617D01*
X860707Y377117D01*
G01X863723Y376450D02*
Y379783D01*
G01Y379117D02*
X864140Y379450D01*
X864557Y379700D01*
X865140Y379783D01*
X865557Y379700D01*
X866057Y379450D01*
G01X869240Y378700D02*
X871907D01*
X871657Y379283D01*
X871240Y379617D01*
X870657Y379783D01*
X870073Y379700D01*
X869573Y379450D01*
X869240Y378867D01*
X869073Y378367D01*
Y377867D01*
X869240Y377367D01*
X869657Y376867D01*
X870157Y376533D01*
X870740Y376450D01*
X871323Y376617D01*
X871907Y377117D01*
G01X877590Y381450D02*
Y376450D01*
G01Y377200D02*
X877257Y376783D01*
X876757Y376533D01*
X876173Y376450D01*
X875507Y376617D01*
X875007Y377033D01*
X874673Y377533D01*
X874590Y378117D01*
X874673Y378700D01*
X875007Y379200D01*
X875507Y379617D01*
X876173Y379783D01*
X876757Y379700D01*
X877173Y379533D01*
X877590Y379200D01*
G01X885207Y379783D02*
X886207Y376450D01*
X887290Y379783D01*
X888373Y376450D01*
X889373Y379783D01*
G01X892890D02*
Y376450D01*
G01Y381117D02*
X892723Y381200D01*
Y381367D01*
X892890Y381450D01*
X893057Y381367D01*
Y381200D01*
X892890Y381117D01*
G01X898490Y381450D02*
Y376450D01*
G01X897323Y379783D02*
X899657D01*
G01X902673Y376450D02*
Y381450D01*
G01Y379033D02*
X903090Y379450D01*
X903507Y379700D01*
X904173Y379783D01*
X904673Y379700D01*
X905257Y379367D01*
X905507Y378867D01*
Y376450D01*
G01X916623Y379367D02*
X916040Y379700D01*
X915540Y379783D01*
X914873Y379617D01*
X914373Y379283D01*
X914040Y378700D01*
X913957Y378117D01*
X914040Y377533D01*
X914373Y377033D01*
X914873Y376617D01*
X915540Y376450D01*
X916123Y376617D01*
X916623Y376950D01*
G01X920890Y376450D02*
X920390Y376533D01*
X919890Y376867D01*
X919557Y377450D01*
X919390Y378117D01*
X919557Y378783D01*
X919890Y379367D01*
X920390Y379700D01*
X920890Y379783D01*
X921390Y379700D01*
X921890Y379367D01*
X922223Y378783D01*
X922307Y378117D01*
X922223Y377450D01*
X921890Y376867D01*
X921390Y376533D01*
X920890Y376450D01*
G01X924990Y374783D02*
Y379783D01*
G01Y379033D02*
X925407Y379450D01*
X925823Y379700D01*
X926490Y379783D01*
X927073Y379700D01*
X927657Y379283D01*
X927907Y378700D01*
X927990Y378117D01*
X927907Y377533D01*
X927657Y376950D01*
X927157Y376617D01*
X926490Y376450D01*
X925907Y376533D01*
X925323Y376783D01*
X924990Y377117D01*
G01X930590Y374783D02*
Y379783D01*
G01Y379033D02*
X931007Y379450D01*
X931423Y379700D01*
X932090Y379783D01*
X932673Y379700D01*
X933257Y379283D01*
X933507Y378700D01*
X933590Y378117D01*
X933507Y377533D01*
X933257Y376950D01*
X932757Y376617D01*
X932090Y376450D01*
X931507Y376533D01*
X930923Y376783D01*
X930590Y377117D01*
G01X936440Y378700D02*
X939107D01*
X938857Y379283D01*
X938440Y379617D01*
X937857Y379783D01*
X937273Y379700D01*
X936773Y379450D01*
X936440Y378867D01*
X936273Y378367D01*
Y377867D01*
X936440Y377367D01*
X936857Y376867D01*
X937357Y376533D01*
X937940Y376450D01*
X938523Y376617D01*
X939107Y377117D01*
G01X942123Y376450D02*
Y379783D01*
G01Y379117D02*
X942540Y379450D01*
X942957Y379700D01*
X943540Y379783D01*
X943957Y379700D01*
X944457Y379450D01*
G01X819590Y389810D02*
Y394060D01*
X819757Y394477D01*
X820090Y394727D01*
X820590Y394810D01*
X821090Y394643D01*
X821340Y394227D01*
G01X820340Y392810D02*
X818673D01*
G01X825690Y389810D02*
X825190Y389893D01*
X824690Y390227D01*
X824357Y390810D01*
X824190Y391477D01*
X824357Y392143D01*
X824690Y392727D01*
X825190Y393060D01*
X825690Y393143D01*
X826190Y393060D01*
X826690Y392727D01*
X827023Y392143D01*
X827107Y391477D01*
X827023Y390810D01*
X826690Y390227D01*
X826190Y389893D01*
X825690Y389810D01*
G01X831290D02*
Y394810D01*
G01X836890Y389810D02*
Y394810D01*
G01X842490Y389810D02*
X841990Y389893D01*
X841490Y390227D01*
X841157Y390810D01*
X840990Y391477D01*
X841157Y392143D01*
X841490Y392727D01*
X841990Y393060D01*
X842490Y393143D01*
X842990Y393060D01*
X843490Y392727D01*
X843823Y392143D01*
X843907Y391477D01*
X843823Y390810D01*
X843490Y390227D01*
X842990Y389893D01*
X842490Y389810D01*
G01X846007Y393143D02*
X847007Y389810D01*
X848090Y393143D01*
X849173Y389810D01*
X850173Y393143D01*
G01X859790Y392310D02*
X861457D01*
Y390810D01*
X860957Y390310D01*
X860373Y389977D01*
X859540Y389810D01*
X858707Y389977D01*
X858123Y390310D01*
X857623Y390810D01*
X857290Y391393D01*
X857123Y392060D01*
Y392643D01*
X857290Y393143D01*
X857623Y393727D01*
X858123Y394227D01*
X858623Y394560D01*
X859290Y394810D01*
X859873D01*
X860540Y394643D01*
X861040Y394310D01*
G01X863640Y392060D02*
X866307D01*
X866057Y392643D01*
X865640Y392977D01*
X865057Y393143D01*
X864473Y393060D01*
X863973Y392810D01*
X863640Y392227D01*
X863473Y391727D01*
Y391227D01*
X863640Y390727D01*
X864057Y390227D01*
X864557Y389893D01*
X865140Y389810D01*
X865723Y389977D01*
X866307Y390477D01*
G01X869323Y389810D02*
Y393143D01*
G01Y392477D02*
X869740Y392810D01*
X870157Y393060D01*
X870740Y393143D01*
X871157Y393060D01*
X871657Y392810D01*
G01X874590Y389810D02*
Y394810D01*
G01Y392310D02*
X875007Y392810D01*
X875507Y393060D01*
X876007Y393143D01*
X876757Y392977D01*
X877257Y392643D01*
X877590Y392060D01*
Y391393D01*
X877423Y390727D01*
X877090Y390227D01*
X876507Y389893D01*
X876007Y389810D01*
X875507Y389893D01*
X875007Y390143D01*
X874590Y390560D01*
G01X880440Y392060D02*
X883107D01*
X882857Y392643D01*
X882440Y392977D01*
X881857Y393143D01*
X881273Y393060D01*
X880773Y392810D01*
X880440Y392227D01*
X880273Y391727D01*
Y391227D01*
X880440Y390727D01*
X880857Y390227D01*
X881357Y389893D01*
X881940Y389810D01*
X882523Y389977D01*
X883107Y390477D01*
G01X886123Y389810D02*
Y393143D01*
G01Y392477D02*
X886540Y392810D01*
X886957Y393060D01*
X887540Y393143D01*
X887957Y393060D01*
X888457Y392810D01*
G01X899990Y389810D02*
Y393143D01*
G01Y392560D02*
X899657Y392893D01*
X899157Y393060D01*
X898573Y393143D01*
X897990Y392977D01*
X897490Y392643D01*
X897157Y392143D01*
X896990Y391477D01*
X897157Y390810D01*
X897490Y390310D01*
X897990Y389977D01*
X898573Y389810D01*
X899157Y389893D01*
X899657Y390143D01*
X899990Y390477D01*
G01X902673Y389810D02*
Y393143D01*
G01Y392310D02*
X903007Y392727D01*
X903507Y393060D01*
X904173Y393143D01*
X904757Y393060D01*
X905257Y392727D01*
X905507Y392143D01*
Y389810D01*
G01X911190Y394810D02*
Y389810D01*
G01Y390560D02*
X910857Y390143D01*
X910357Y389893D01*
X909773Y389810D01*
X909107Y389977D01*
X908607Y390393D01*
X908273Y390893D01*
X908190Y391477D01*
X908273Y392060D01*
X908607Y392560D01*
X909107Y392977D01*
X909773Y393143D01*
X910357Y393060D01*
X910773Y392893D01*
X911190Y392560D01*
G01X919390Y388143D02*
Y393143D01*
G01Y392393D02*
X919807Y392810D01*
X920223Y393060D01*
X920890Y393143D01*
X921473Y393060D01*
X922057Y392643D01*
X922307Y392060D01*
X922390Y391477D01*
X922307Y390893D01*
X922057Y390310D01*
X921557Y389977D01*
X920890Y389810D01*
X920307Y389893D01*
X919723Y390143D01*
X919390Y390477D01*
G01X926490Y389810D02*
Y394810D01*
G01X930673Y393143D02*
Y390810D01*
X931007Y390227D01*
X931507Y389893D01*
X932090Y389810D01*
X932673Y389893D01*
X933173Y390227D01*
X933507Y390810D01*
G01Y389810D02*
Y393143D01*
G01X936523Y388560D02*
X937107Y388227D01*
X937773Y388143D01*
X938357Y388227D01*
X938857Y388643D01*
X939190Y389227D01*
Y393143D01*
G01Y392477D02*
X938857Y392810D01*
X938357Y393060D01*
X937773Y393143D01*
X937107Y392977D01*
X936690Y392643D01*
X936357Y392060D01*
X936190Y391477D01*
X936273Y390977D01*
X936607Y390393D01*
X937107Y389977D01*
X937773Y389810D01*
X938273Y389893D01*
X938857Y390227D01*
X939190Y390560D01*
G01X946807Y393143D02*
X947807Y389810D01*
X948890Y393143D01*
X949973Y389810D01*
X950973Y393143D01*
G01X954490D02*
Y389810D01*
G01Y394477D02*
X954323Y394560D01*
Y394727D01*
X954490Y394810D01*
X954657Y394727D01*
Y394560D01*
X954490Y394477D01*
G01X960090Y394810D02*
Y389810D01*
G01X958923Y393143D02*
X961257D01*
G01X964273Y389810D02*
Y394810D01*
G01Y392393D02*
X964690Y392810D01*
X965107Y393060D01*
X965773Y393143D01*
X966273Y393060D01*
X966857Y392727D01*
X967107Y392227D01*
Y389810D01*
G01X975723D02*
Y393143D01*
G01Y392477D02*
X976140Y392810D01*
X976557Y393060D01*
X977140Y393143D01*
X977557Y393060D01*
X978057Y392810D01*
G01X981240Y392060D02*
X983907D01*
X983657Y392643D01*
X983240Y392977D01*
X982657Y393143D01*
X982073Y393060D01*
X981573Y392810D01*
X981240Y392227D01*
X981073Y391727D01*
Y391227D01*
X981240Y390727D01*
X981657Y390227D01*
X982157Y389893D01*
X982740Y389810D01*
X983323Y389977D01*
X983907Y390477D01*
G01X986840Y390393D02*
X987257Y390060D01*
X987840Y389810D01*
X988340D01*
X988840Y389977D01*
X989173Y390227D01*
X989340Y390560D01*
X989257Y391060D01*
X988923Y391310D01*
X987423Y391810D01*
X987090Y392393D01*
X987257Y392810D01*
X987590Y393060D01*
X988090Y393143D01*
X988590Y393060D01*
X989090Y392810D01*
G01X993690Y393143D02*
Y389810D01*
G01Y394477D02*
X993523Y394560D01*
Y394727D01*
X993690Y394810D01*
X993857Y394727D01*
Y394560D01*
X993690Y394477D01*
G01X997873Y389810D02*
Y393143D01*
G01Y392310D02*
X998207Y392727D01*
X998707Y393060D01*
X999373Y393143D01*
X999957Y393060D01*
X1000457Y392727D01*
X1000707Y392143D01*
Y389810D01*
G01X812000Y604500D02*
Y366000D01*
G01X821500Y440500D02*
Y444750D01*
X821667Y445167D01*
X822000Y445417D01*
X822500Y445500D01*
X823000Y445333D01*
X823250Y444917D01*
G01X822250Y443500D02*
X820583D01*
G01X827600Y440500D02*
X827100Y440583D01*
X826600Y440917D01*
X826267Y441500D01*
X826100Y442167D01*
X826267Y442833D01*
X826600Y443417D01*
X827100Y443750D01*
X827600Y443833D01*
X828100Y443750D01*
X828600Y443417D01*
X828933Y442833D01*
X829017Y442167D01*
X828933Y441500D01*
X828600Y440917D01*
X828100Y440583D01*
X827600Y440500D01*
G01X833200D02*
Y445500D01*
G01X838800Y440500D02*
Y445500D01*
G01X844400Y440500D02*
X843900Y440583D01*
X843400Y440917D01*
X843067Y441500D01*
X842900Y442167D01*
X843067Y442833D01*
X843400Y443417D01*
X843900Y443750D01*
X844400Y443833D01*
X844900Y443750D01*
X845400Y443417D01*
X845733Y442833D01*
X845817Y442167D01*
X845733Y441500D01*
X845400Y440917D01*
X844900Y440583D01*
X844400Y440500D01*
G01X847917Y443833D02*
X848917Y440500D01*
X850000Y443833D01*
X851083Y440500D01*
X852083Y443833D01*
G01X861700Y443000D02*
X863367D01*
Y441500D01*
X862867Y441000D01*
X862283Y440667D01*
X861450Y440500D01*
X860617Y440667D01*
X860033Y441000D01*
X859533Y441500D01*
X859200Y442083D01*
X859033Y442750D01*
Y443333D01*
X859200Y443833D01*
X859533Y444417D01*
X860033Y444917D01*
X860533Y445250D01*
X861200Y445500D01*
X861783D01*
X862450Y445333D01*
X862950Y445000D01*
G01X865550Y442750D02*
X868217D01*
X867967Y443333D01*
X867550Y443667D01*
X866967Y443833D01*
X866383Y443750D01*
X865883Y443500D01*
X865550Y442917D01*
X865383Y442417D01*
Y441917D01*
X865550Y441417D01*
X865967Y440917D01*
X866467Y440583D01*
X867050Y440500D01*
X867633Y440667D01*
X868217Y441167D01*
G01X871233Y440500D02*
Y443833D01*
G01Y443167D02*
X871650Y443500D01*
X872067Y443750D01*
X872650Y443833D01*
X873067Y443750D01*
X873567Y443500D01*
G01X876500Y440500D02*
Y445500D01*
G01Y443000D02*
X876917Y443500D01*
X877417Y443750D01*
X877917Y443833D01*
X878667Y443667D01*
X879167Y443333D01*
X879500Y442750D01*
Y442083D01*
X879333Y441417D01*
X879000Y440917D01*
X878417Y440583D01*
X877917Y440500D01*
X877417Y440583D01*
X876917Y440833D01*
X876500Y441250D01*
G01X882350Y442750D02*
X885017D01*
X884767Y443333D01*
X884350Y443667D01*
X883767Y443833D01*
X883183Y443750D01*
X882683Y443500D01*
X882350Y442917D01*
X882183Y442417D01*
Y441917D01*
X882350Y441417D01*
X882767Y440917D01*
X883267Y440583D01*
X883850Y440500D01*
X884433Y440667D01*
X885017Y441167D01*
G01X888033Y440500D02*
Y443833D01*
G01Y443167D02*
X888450Y443500D01*
X888867Y443750D01*
X889450Y443833D01*
X889867Y443750D01*
X890367Y443500D01*
G01X821500Y419500D02*
Y423750D01*
X821667Y424167D01*
X822000Y424417D01*
X822500Y424500D01*
X823000Y424333D01*
X823250Y423917D01*
G01X822250Y422500D02*
X820583D01*
G01X827600Y419500D02*
X827100Y419583D01*
X826600Y419917D01*
X826267Y420500D01*
X826100Y421167D01*
X826267Y421833D01*
X826600Y422417D01*
X827100Y422750D01*
X827600Y422833D01*
X828100Y422750D01*
X828600Y422417D01*
X828933Y421833D01*
X829017Y421167D01*
X828933Y420500D01*
X828600Y419917D01*
X828100Y419583D01*
X827600Y419500D01*
G01X833200D02*
Y424500D01*
G01X838800Y419500D02*
Y424500D01*
G01X844400Y419500D02*
X843900Y419583D01*
X843400Y419917D01*
X843067Y420500D01*
X842900Y421167D01*
X843067Y421833D01*
X843400Y422417D01*
X843900Y422750D01*
X844400Y422833D01*
X844900Y422750D01*
X845400Y422417D01*
X845733Y421833D01*
X845817Y421167D01*
X845733Y420500D01*
X845400Y419917D01*
X844900Y419583D01*
X844400Y419500D01*
G01X847917Y422833D02*
X848917Y419500D01*
X850000Y422833D01*
X851083Y419500D01*
X852083Y422833D01*
G01X861700Y422000D02*
X863367D01*
Y420500D01*
X862867Y420000D01*
X862283Y419667D01*
X861450Y419500D01*
X860617Y419667D01*
X860033Y420000D01*
X859533Y420500D01*
X859200Y421083D01*
X859033Y421750D01*
Y422333D01*
X859200Y422833D01*
X859533Y423417D01*
X860033Y423917D01*
X860533Y424250D01*
X861200Y424500D01*
X861783D01*
X862450Y424333D01*
X862950Y424000D01*
G01X865550Y421750D02*
X868217D01*
X867967Y422333D01*
X867550Y422667D01*
X866967Y422833D01*
X866383Y422750D01*
X865883Y422500D01*
X865550Y421917D01*
X865383Y421417D01*
Y420917D01*
X865550Y420417D01*
X865967Y419917D01*
X866467Y419583D01*
X867050Y419500D01*
X867633Y419667D01*
X868217Y420167D01*
G01X871233Y419500D02*
Y422833D01*
G01Y422167D02*
X871650Y422500D01*
X872067Y422750D01*
X872650Y422833D01*
X873067Y422750D01*
X873567Y422500D01*
G01X876500Y419500D02*
Y424500D01*
G01Y422000D02*
X876917Y422500D01*
X877417Y422750D01*
X877917Y422833D01*
X878667Y422667D01*
X879167Y422333D01*
X879500Y421750D01*
Y421083D01*
X879333Y420417D01*
X879000Y419917D01*
X878417Y419583D01*
X877917Y419500D01*
X877417Y419583D01*
X876917Y419833D01*
X876500Y420250D01*
G01X882350Y421750D02*
X885017D01*
X884767Y422333D01*
X884350Y422667D01*
X883767Y422833D01*
X883183Y422750D01*
X882683Y422500D01*
X882350Y421917D01*
X882183Y421417D01*
Y420917D01*
X882350Y420417D01*
X882767Y419917D01*
X883267Y419583D01*
X883850Y419500D01*
X884433Y419667D01*
X885017Y420167D01*
G01X888033Y419500D02*
Y422833D01*
G01Y422167D02*
X888450Y422500D01*
X888867Y422750D01*
X889450Y422833D01*
X889867Y422750D01*
X890367Y422500D01*
G01X901900Y419500D02*
Y422833D01*
G01Y422250D02*
X901567Y422583D01*
X901067Y422750D01*
X900483Y422833D01*
X899900Y422667D01*
X899400Y422333D01*
X899067Y421833D01*
X898900Y421167D01*
X899067Y420500D01*
X899400Y420000D01*
X899900Y419667D01*
X900483Y419500D01*
X901067Y419583D01*
X901567Y419833D01*
X901900Y420167D01*
G01X904583Y419500D02*
Y422833D01*
G01Y422000D02*
X904917Y422417D01*
X905417Y422750D01*
X906083Y422833D01*
X906667Y422750D01*
X907167Y422417D01*
X907417Y421833D01*
Y419500D01*
G01X913100Y424500D02*
Y419500D01*
G01Y420250D02*
X912767Y419833D01*
X912267Y419583D01*
X911683Y419500D01*
X911017Y419667D01*
X910517Y420083D01*
X910183Y420583D01*
X910100Y421167D01*
X910183Y421750D01*
X910517Y422250D01*
X911017Y422667D01*
X911683Y422833D01*
X912267Y422750D01*
X912683Y422583D01*
X913100Y422250D01*
G01X921300Y417833D02*
Y422833D01*
G01Y422083D02*
X921717Y422500D01*
X922133Y422750D01*
X922800Y422833D01*
X923383Y422750D01*
X923967Y422333D01*
X924217Y421750D01*
X924300Y421167D01*
X924217Y420583D01*
X923967Y420000D01*
X923467Y419667D01*
X922800Y419500D01*
X922217Y419583D01*
X921633Y419833D01*
X921300Y420167D01*
G01X928400Y419500D02*
Y424500D01*
G01X932583Y422833D02*
Y420500D01*
X932917Y419917D01*
X933417Y419583D01*
X934000Y419500D01*
X934583Y419583D01*
X935083Y419917D01*
X935417Y420500D01*
G01Y419500D02*
Y422833D01*
G01X938433Y418250D02*
X939017Y417917D01*
X939683Y417833D01*
X940267Y417917D01*
X940767Y418333D01*
X941100Y418917D01*
Y422833D01*
G01Y422167D02*
X940767Y422500D01*
X940267Y422750D01*
X939683Y422833D01*
X939017Y422667D01*
X938600Y422333D01*
X938267Y421750D01*
X938100Y421167D01*
X938183Y420667D01*
X938517Y420083D01*
X939017Y419667D01*
X939683Y419500D01*
X940183Y419583D01*
X940767Y419917D01*
X941100Y420250D01*
G01X948717Y422833D02*
X949717Y419500D01*
X950800Y422833D01*
X951883Y419500D01*
X952883Y422833D01*
G01X956400D02*
Y419500D01*
G01Y424167D02*
X956233Y424250D01*
Y424417D01*
X956400Y424500D01*
X956567Y424417D01*
Y424250D01*
X956400Y424167D01*
G01X962000Y424500D02*
Y419500D01*
G01X960833Y422833D02*
X963167D01*
G01X966183Y419500D02*
Y424500D01*
G01Y422083D02*
X966600Y422500D01*
X967017Y422750D01*
X967683Y422833D01*
X968183Y422750D01*
X968767Y422417D01*
X969017Y421917D01*
Y419500D01*
G01X977633D02*
Y422833D01*
G01Y422167D02*
X978050Y422500D01*
X978467Y422750D01*
X979050Y422833D01*
X979467Y422750D01*
X979967Y422500D01*
G01X983150Y421750D02*
X985817D01*
X985567Y422333D01*
X985150Y422667D01*
X984567Y422833D01*
X983983Y422750D01*
X983483Y422500D01*
X983150Y421917D01*
X982983Y421417D01*
Y420917D01*
X983150Y420417D01*
X983567Y419917D01*
X984067Y419583D01*
X984650Y419500D01*
X985233Y419667D01*
X985817Y420167D01*
G01X988750Y420083D02*
X989167Y419750D01*
X989750Y419500D01*
X990250D01*
X990750Y419667D01*
X991083Y419917D01*
X991250Y420250D01*
X991167Y420750D01*
X990833Y421000D01*
X989333Y421500D01*
X989000Y422083D01*
X989167Y422500D01*
X989500Y422750D01*
X990000Y422833D01*
X990500Y422750D01*
X991000Y422500D01*
G01X995600Y422833D02*
Y419500D01*
G01Y424167D02*
X995433Y424250D01*
Y424417D01*
X995600Y424500D01*
X995767Y424417D01*
Y424250D01*
X995600Y424167D01*
G01X999783Y419500D02*
Y422833D01*
G01Y422000D02*
X1000117Y422417D01*
X1000617Y422750D01*
X1001283Y422833D01*
X1001867Y422750D01*
X1002367Y422417D01*
X1002617Y421833D01*
Y419500D01*
G01X823500Y455500D02*
Y458833D01*
G01Y458250D02*
X823167Y458583D01*
X822667Y458750D01*
X822083Y458833D01*
X821500Y458667D01*
X821000Y458333D01*
X820667Y457833D01*
X820500Y457167D01*
X820667Y456500D01*
X821000Y456000D01*
X821500Y455667D01*
X822083Y455500D01*
X822667Y455583D01*
X823167Y455833D01*
X823500Y456167D01*
G01X826183Y455500D02*
Y458833D01*
G01Y458000D02*
X826517Y458417D01*
X827017Y458750D01*
X827683Y458833D01*
X828267Y458750D01*
X828767Y458417D01*
X829017Y457833D01*
Y455500D01*
G01X834700Y460500D02*
Y455500D01*
G01Y456250D02*
X834367Y455833D01*
X833867Y455583D01*
X833283Y455500D01*
X832617Y455667D01*
X832117Y456083D01*
X831783Y456583D01*
X831700Y457167D01*
X831783Y457750D01*
X832117Y458250D01*
X832617Y458667D01*
X833283Y458833D01*
X833867Y458750D01*
X834283Y458583D01*
X834700Y458250D01*
G01X842900Y455500D02*
Y460500D01*
G01Y458000D02*
X843317Y458500D01*
X843817Y458750D01*
X844317Y458833D01*
X845067Y458667D01*
X845567Y458333D01*
X845900Y457750D01*
Y457083D01*
X845733Y456417D01*
X845400Y455917D01*
X844817Y455583D01*
X844317Y455500D01*
X843817Y455583D01*
X843317Y455833D01*
X842900Y456250D01*
G01X850000Y455500D02*
X849500Y455583D01*
X849000Y455917D01*
X848667Y456500D01*
X848500Y457167D01*
X848667Y457833D01*
X849000Y458417D01*
X849500Y458750D01*
X850000Y458833D01*
X850500Y458750D01*
X851000Y458417D01*
X851333Y457833D01*
X851417Y457167D01*
X851333Y456500D01*
X851000Y455917D01*
X850500Y455583D01*
X850000Y455500D01*
G01X855600Y460500D02*
Y455500D01*
G01X854433Y458833D02*
X856767D01*
G01X861200Y460500D02*
Y455500D01*
G01X860033Y458833D02*
X862367D01*
G01X866800Y455500D02*
X866300Y455583D01*
X865800Y455917D01*
X865467Y456500D01*
X865300Y457167D01*
X865467Y457833D01*
X865800Y458417D01*
X866300Y458750D01*
X866800Y458833D01*
X867300Y458750D01*
X867800Y458417D01*
X868133Y457833D01*
X868217Y457167D01*
X868133Y456500D01*
X867800Y455917D01*
X867300Y455583D01*
X866800Y455500D01*
G01X869900D02*
Y458833D01*
G01Y457917D02*
X870150Y458333D01*
X870567Y458667D01*
X871150Y458833D01*
X871733Y458667D01*
X872150Y458333D01*
X872400Y457917D01*
Y455500D01*
G01Y457917D02*
X872650Y458333D01*
X873067Y458667D01*
X873650Y458833D01*
X874233Y458667D01*
X874650Y458333D01*
X874900Y457833D01*
Y455500D01*
G01X882350Y456083D02*
X882767Y455750D01*
X883350Y455500D01*
X883850D01*
X884350Y455667D01*
X884683Y455917D01*
X884850Y456250D01*
X884767Y456750D01*
X884433Y457000D01*
X882933Y457500D01*
X882600Y458083D01*
X882767Y458500D01*
X883100Y458750D01*
X883600Y458833D01*
X884100Y458750D01*
X884600Y458500D01*
G01X889200Y458833D02*
Y455500D01*
G01Y460167D02*
X889033Y460250D01*
Y460417D01*
X889200Y460500D01*
X889367Y460417D01*
Y460250D01*
X889200Y460167D01*
G01X896300Y460500D02*
Y455500D01*
G01Y456250D02*
X895967Y455833D01*
X895467Y455583D01*
X894883Y455500D01*
X894217Y455667D01*
X893717Y456083D01*
X893383Y456583D01*
X893300Y457167D01*
X893383Y457750D01*
X893717Y458250D01*
X894217Y458667D01*
X894883Y458833D01*
X895467Y458750D01*
X895883Y458583D01*
X896300Y458250D01*
G01X899150Y457750D02*
X901817D01*
X901567Y458333D01*
X901150Y458667D01*
X900567Y458833D01*
X899983Y458750D01*
X899483Y458500D01*
X899150Y457917D01*
X898983Y457417D01*
Y456917D01*
X899150Y456417D01*
X899567Y455917D01*
X900067Y455583D01*
X900650Y455500D01*
X901233Y455667D01*
X901817Y456167D01*
G01X819917Y470833D02*
X820917Y467500D01*
X822000Y470833D01*
X823083Y467500D01*
X824083Y470833D01*
G01X827600D02*
Y467500D01*
G01Y472167D02*
X827433Y472250D01*
Y472417D01*
X827600Y472500D01*
X827767Y472417D01*
Y472250D01*
X827600Y472167D01*
G01X833200Y472500D02*
Y467500D01*
G01X832033Y470833D02*
X834367D01*
G01X837383Y467500D02*
Y472500D01*
G01Y470083D02*
X837800Y470500D01*
X838217Y470750D01*
X838883Y470833D01*
X839383Y470750D01*
X839967Y470417D01*
X840217Y469917D01*
Y467500D01*
G01X844400D02*
X843900Y467583D01*
X843400Y467917D01*
X843067Y468500D01*
X842900Y469167D01*
X843067Y469833D01*
X843400Y470417D01*
X843900Y470750D01*
X844400Y470833D01*
X844900Y470750D01*
X845400Y470417D01*
X845733Y469833D01*
X845817Y469167D01*
X845733Y468500D01*
X845400Y467917D01*
X844900Y467583D01*
X844400Y467500D01*
G01X848583Y470833D02*
Y468500D01*
X848917Y467917D01*
X849417Y467583D01*
X850000Y467500D01*
X850583Y467583D01*
X851083Y467917D01*
X851417Y468500D01*
G01Y467500D02*
Y470833D01*
G01X855600Y472500D02*
Y467500D01*
G01X854433Y470833D02*
X856767D01*
G01X865550Y468083D02*
X865967Y467750D01*
X866550Y467500D01*
X867050D01*
X867550Y467667D01*
X867883Y467917D01*
X868050Y468250D01*
X867967Y468750D01*
X867633Y469000D01*
X866133Y469500D01*
X865800Y470083D01*
X865967Y470500D01*
X866300Y470750D01*
X866800Y470833D01*
X867300Y470750D01*
X867800Y470500D01*
G01X872400Y467500D02*
X871900Y467583D01*
X871400Y467917D01*
X871067Y468500D01*
X870900Y469167D01*
X871067Y469833D01*
X871400Y470417D01*
X871900Y470750D01*
X872400Y470833D01*
X872900Y470750D01*
X873400Y470417D01*
X873733Y469833D01*
X873817Y469167D01*
X873733Y468500D01*
X873400Y467917D01*
X872900Y467583D01*
X872400Y467500D01*
G01X878000D02*
Y472500D01*
G01X885100D02*
Y467500D01*
G01Y468250D02*
X884767Y467833D01*
X884267Y467583D01*
X883683Y467500D01*
X883017Y467667D01*
X882517Y468083D01*
X882183Y468583D01*
X882100Y469167D01*
X882183Y469750D01*
X882517Y470250D01*
X883017Y470667D01*
X883683Y470833D01*
X884267Y470750D01*
X884683Y470583D01*
X885100Y470250D01*
G01X887950Y469750D02*
X890617D01*
X890367Y470333D01*
X889950Y470667D01*
X889367Y470833D01*
X888783Y470750D01*
X888283Y470500D01*
X887950Y469917D01*
X887783Y469417D01*
Y468917D01*
X887950Y468417D01*
X888367Y467917D01*
X888867Y467583D01*
X889450Y467500D01*
X890033Y467667D01*
X890617Y468167D01*
G01X893633Y467500D02*
Y470833D01*
G01Y470167D02*
X894050Y470500D01*
X894467Y470750D01*
X895050Y470833D01*
X895467Y470750D01*
X895967Y470500D01*
G01X903500Y467500D02*
Y470833D01*
G01Y469917D02*
X903750Y470333D01*
X904167Y470667D01*
X904750Y470833D01*
X905333Y470667D01*
X905750Y470333D01*
X906000Y469917D01*
Y467500D01*
G01Y469917D02*
X906250Y470333D01*
X906667Y470667D01*
X907250Y470833D01*
X907833Y470667D01*
X908250Y470333D01*
X908500Y469833D01*
Y467500D01*
G01X913100D02*
Y470833D01*
G01Y470250D02*
X912767Y470583D01*
X912267Y470750D01*
X911683Y470833D01*
X911100Y470667D01*
X910600Y470333D01*
X910267Y469833D01*
X910100Y469167D01*
X910267Y468500D01*
X910600Y468000D01*
X911100Y467667D01*
X911683Y467500D01*
X912267Y467583D01*
X912767Y467833D01*
X913100Y468167D01*
G01X915950Y468083D02*
X916367Y467750D01*
X916950Y467500D01*
X917450D01*
X917950Y467667D01*
X918283Y467917D01*
X918450Y468250D01*
X918367Y468750D01*
X918033Y469000D01*
X916533Y469500D01*
X916200Y470083D01*
X916367Y470500D01*
X916700Y470750D01*
X917200Y470833D01*
X917700Y470750D01*
X918200Y470500D01*
G01X921383Y467500D02*
Y472500D01*
G01X924050Y470833D02*
X921383Y468917D01*
G01X922467Y469667D02*
X924217Y467500D01*
G01X932500Y465833D02*
Y470833D01*
G01Y470083D02*
X932917Y470500D01*
X933333Y470750D01*
X934000Y470833D01*
X934583Y470750D01*
X935167Y470333D01*
X935417Y469750D01*
X935500Y469167D01*
X935417Y468583D01*
X935167Y468000D01*
X934667Y467667D01*
X934000Y467500D01*
X933417Y467583D01*
X932833Y467833D01*
X932500Y468167D01*
G01X941100Y467500D02*
Y470833D01*
G01Y470250D02*
X940767Y470583D01*
X940267Y470750D01*
X939683Y470833D01*
X939100Y470667D01*
X938600Y470333D01*
X938267Y469833D01*
X938100Y469167D01*
X938267Y468500D01*
X938600Y468000D01*
X939100Y467667D01*
X939683Y467500D01*
X940267Y467583D01*
X940767Y467833D01*
X941100Y468167D01*
G01X946700Y472500D02*
Y467500D01*
G01Y468250D02*
X946367Y467833D01*
X945867Y467583D01*
X945283Y467500D01*
X944617Y467667D01*
X944117Y468083D01*
X943783Y468583D01*
X943700Y469167D01*
X943783Y469750D01*
X944117Y470250D01*
X944617Y470667D01*
X945283Y470833D01*
X945867Y470750D01*
X946283Y470583D01*
X946700Y470250D01*
G01X956400Y467500D02*
X955900Y467583D01*
X955400Y467917D01*
X955067Y468500D01*
X954900Y469167D01*
X955067Y469833D01*
X955400Y470417D01*
X955900Y470750D01*
X956400Y470833D01*
X956900Y470750D01*
X957400Y470417D01*
X957733Y469833D01*
X957817Y469167D01*
X957733Y468500D01*
X957400Y467917D01*
X956900Y467583D01*
X956400Y467500D01*
G01X960583D02*
Y470833D01*
G01Y470000D02*
X960917Y470417D01*
X961417Y470750D01*
X962083Y470833D01*
X962667Y470750D01*
X963167Y470417D01*
X963417Y469833D01*
Y467500D01*
G01X973200Y472500D02*
Y467500D01*
G01X972033Y470833D02*
X974367D01*
G01X978800Y467500D02*
X978300Y467583D01*
X977800Y467917D01*
X977467Y468500D01*
X977300Y469167D01*
X977467Y469833D01*
X977800Y470417D01*
X978300Y470750D01*
X978800Y470833D01*
X979300Y470750D01*
X979800Y470417D01*
X980133Y469833D01*
X980217Y469167D01*
X980133Y468500D01*
X979800Y467917D01*
X979300Y467583D01*
X978800Y467500D01*
G01X982900Y465833D02*
Y470833D01*
G01Y470083D02*
X983317Y470500D01*
X983733Y470750D01*
X984400Y470833D01*
X984983Y470750D01*
X985567Y470333D01*
X985817Y469750D01*
X985900Y469167D01*
X985817Y468583D01*
X985567Y468000D01*
X985067Y467667D01*
X984400Y467500D01*
X983817Y467583D01*
X983233Y467833D01*
X982900Y468167D01*
G01X829750Y542583D02*
X830167Y542250D01*
X830750Y542000D01*
X831250D01*
X831750Y542167D01*
X832083Y542417D01*
X832250Y542750D01*
X832167Y543250D01*
X831833Y543500D01*
X830333Y544000D01*
X830000Y544583D01*
X830167Y545000D01*
X830500Y545250D01*
X831000Y545333D01*
X831500Y545250D01*
X832000Y545000D01*
G01X836600Y542000D02*
X836100Y542083D01*
X835600Y542417D01*
X835267Y543000D01*
X835100Y543667D01*
X835267Y544333D01*
X835600Y544917D01*
X836100Y545250D01*
X836600Y545333D01*
X837100Y545250D01*
X837600Y544917D01*
X837933Y544333D01*
X838017Y543667D01*
X837933Y543000D01*
X837600Y542417D01*
X837100Y542083D01*
X836600Y542000D01*
G01X842200D02*
Y547000D01*
G01X849300D02*
Y542000D01*
G01Y542750D02*
X848967Y542333D01*
X848467Y542083D01*
X847883Y542000D01*
X847217Y542167D01*
X846717Y542583D01*
X846383Y543083D01*
X846300Y543667D01*
X846383Y544250D01*
X846717Y544750D01*
X847217Y545167D01*
X847883Y545333D01*
X848467Y545250D01*
X848883Y545083D01*
X849300Y544750D01*
G01X852150Y544250D02*
X854817D01*
X854567Y544833D01*
X854150Y545167D01*
X853567Y545333D01*
X852983Y545250D01*
X852483Y545000D01*
X852150Y544417D01*
X851983Y543917D01*
Y543417D01*
X852150Y542917D01*
X852567Y542417D01*
X853067Y542083D01*
X853650Y542000D01*
X854233Y542167D01*
X854817Y542667D01*
G01X857833Y542000D02*
Y545333D01*
G01Y544667D02*
X858250Y545000D01*
X858667Y545250D01*
X859250Y545333D01*
X859667Y545250D01*
X860167Y545000D01*
G01X867700Y542000D02*
Y545333D01*
G01Y544417D02*
X867950Y544833D01*
X868367Y545167D01*
X868950Y545333D01*
X869533Y545167D01*
X869950Y544833D01*
X870200Y544417D01*
Y542000D01*
G01Y544417D02*
X870450Y544833D01*
X870867Y545167D01*
X871450Y545333D01*
X872033Y545167D01*
X872450Y544833D01*
X872700Y544333D01*
Y542000D01*
G01X877300D02*
Y545333D01*
G01Y544750D02*
X876967Y545083D01*
X876467Y545250D01*
X875883Y545333D01*
X875300Y545167D01*
X874800Y544833D01*
X874467Y544333D01*
X874300Y543667D01*
X874467Y543000D01*
X874800Y542500D01*
X875300Y542167D01*
X875883Y542000D01*
X876467Y542083D01*
X876967Y542333D01*
X877300Y542667D01*
G01X880150Y542583D02*
X880567Y542250D01*
X881150Y542000D01*
X881650D01*
X882150Y542167D01*
X882483Y542417D01*
X882650Y542750D01*
X882567Y543250D01*
X882233Y543500D01*
X880733Y544000D01*
X880400Y544583D01*
X880567Y545000D01*
X880900Y545250D01*
X881400Y545333D01*
X881900Y545250D01*
X882400Y545000D01*
G01X885583Y542000D02*
Y547000D01*
G01X888250Y545333D02*
X885583Y543417D01*
G01X886667Y544167D02*
X888417Y542000D01*
G01X896700Y540333D02*
Y545333D01*
G01Y544583D02*
X897117Y545000D01*
X897533Y545250D01*
X898200Y545333D01*
X898783Y545250D01*
X899367Y544833D01*
X899617Y544250D01*
X899700Y543667D01*
X899617Y543083D01*
X899367Y542500D01*
X898867Y542167D01*
X898200Y542000D01*
X897617Y542083D01*
X897033Y542333D01*
X896700Y542667D01*
G01X905300Y542000D02*
Y545333D01*
G01Y544750D02*
X904967Y545083D01*
X904467Y545250D01*
X903883Y545333D01*
X903300Y545167D01*
X902800Y544833D01*
X902467Y544333D01*
X902300Y543667D01*
X902467Y543000D01*
X902800Y542500D01*
X903300Y542167D01*
X903883Y542000D01*
X904467Y542083D01*
X904967Y542333D01*
X905300Y542667D01*
G01X910900Y547000D02*
Y542000D01*
G01Y542750D02*
X910567Y542333D01*
X910067Y542083D01*
X909483Y542000D01*
X908817Y542167D01*
X908317Y542583D01*
X907983Y543083D01*
X907900Y543667D01*
X907983Y544250D01*
X908317Y544750D01*
X908817Y545167D01*
X909483Y545333D01*
X910067Y545250D01*
X910483Y545083D01*
X910900Y544750D01*
G01X829917Y563333D02*
X830917Y560000D01*
X832000Y563333D01*
X833083Y560000D01*
X834083Y563333D01*
G01X836183Y560000D02*
Y565000D01*
G01Y562583D02*
X836600Y563000D01*
X837017Y563250D01*
X837683Y563333D01*
X838183Y563250D01*
X838767Y562917D01*
X839017Y562417D01*
Y560000D01*
G01X843200Y563333D02*
Y560000D01*
G01Y564667D02*
X843033Y564750D01*
Y564917D01*
X843200Y565000D01*
X843367Y564917D01*
Y564750D01*
X843200Y564667D01*
G01X850133Y562917D02*
X849550Y563250D01*
X849050Y563333D01*
X848383Y563167D01*
X847883Y562833D01*
X847550Y562250D01*
X847467Y561667D01*
X847550Y561083D01*
X847883Y560583D01*
X848383Y560167D01*
X849050Y560000D01*
X849633Y560167D01*
X850133Y560500D01*
G01X852983Y560000D02*
Y565000D01*
G01Y562583D02*
X853400Y563000D01*
X853817Y563250D01*
X854483Y563333D01*
X854983Y563250D01*
X855567Y562917D01*
X855817Y562417D01*
Y560000D01*
G01X864350Y560583D02*
X864767Y560250D01*
X865350Y560000D01*
X865850D01*
X866350Y560167D01*
X866683Y560417D01*
X866850Y560750D01*
X866767Y561250D01*
X866433Y561500D01*
X864933Y562000D01*
X864600Y562583D01*
X864767Y563000D01*
X865100Y563250D01*
X865600Y563333D01*
X866100Y563250D01*
X866600Y563000D01*
G01X871200Y563333D02*
Y560000D01*
G01Y564667D02*
X871033Y564750D01*
Y564917D01*
X871200Y565000D01*
X871367Y564917D01*
Y564750D01*
X871200Y564667D01*
G01X875550Y563333D02*
X878050D01*
X875550Y560000D01*
X878050D01*
G01X881150Y562250D02*
X883817D01*
X883567Y562833D01*
X883150Y563167D01*
X882567Y563333D01*
X881983Y563250D01*
X881483Y563000D01*
X881150Y562417D01*
X880983Y561917D01*
Y561417D01*
X881150Y560917D01*
X881567Y560417D01*
X882067Y560083D01*
X882650Y560000D01*
X883233Y560167D01*
X883817Y560667D01*
G01X893600Y563333D02*
Y560000D01*
G01Y564667D02*
X893433Y564750D01*
Y564917D01*
X893600Y565000D01*
X893767Y564917D01*
Y564750D01*
X893600Y564667D01*
G01X897950Y560583D02*
X898367Y560250D01*
X898950Y560000D01*
X899450D01*
X899950Y560167D01*
X900283Y560417D01*
X900450Y560750D01*
X900367Y561250D01*
X900033Y561500D01*
X898533Y562000D01*
X898200Y562583D01*
X898367Y563000D01*
X898700Y563250D01*
X899200Y563333D01*
X899700Y563250D01*
X900200Y563000D01*
G01X908900Y560000D02*
Y565000D01*
G01Y562500D02*
X909317Y563000D01*
X909817Y563250D01*
X910317Y563333D01*
X911067Y563167D01*
X911567Y562833D01*
X911900Y562250D01*
Y561583D01*
X911733Y560917D01*
X911400Y560417D01*
X910817Y560083D01*
X910317Y560000D01*
X909817Y560083D01*
X909317Y560333D01*
X908900Y560750D01*
G01X916000Y563333D02*
Y560000D01*
G01Y564667D02*
X915833Y564750D01*
Y564917D01*
X916000Y565000D01*
X916167Y564917D01*
Y564750D01*
X916000Y564667D01*
G01X920433Y558750D02*
X921017Y558417D01*
X921683Y558333D01*
X922267Y558417D01*
X922767Y558833D01*
X923100Y559417D01*
Y563333D01*
G01Y562667D02*
X922767Y563000D01*
X922267Y563250D01*
X921683Y563333D01*
X921017Y563167D01*
X920600Y562833D01*
X920267Y562250D01*
X920100Y561667D01*
X920183Y561167D01*
X920517Y560583D01*
X921017Y560167D01*
X921683Y560000D01*
X922183Y560083D01*
X922767Y560417D01*
X923100Y560750D01*
G01X926033Y558750D02*
X926617Y558417D01*
X927283Y558333D01*
X927867Y558417D01*
X928367Y558833D01*
X928700Y559417D01*
Y563333D01*
G01Y562667D02*
X928367Y563000D01*
X927867Y563250D01*
X927283Y563333D01*
X926617Y563167D01*
X926200Y562833D01*
X925867Y562250D01*
X925700Y561667D01*
X925783Y561167D01*
X926117Y560583D01*
X926617Y560167D01*
X927283Y560000D01*
X927783Y560083D01*
X928367Y560417D01*
X928700Y560750D01*
G01X931550Y562250D02*
X934217D01*
X933967Y562833D01*
X933550Y563167D01*
X932967Y563333D01*
X932383Y563250D01*
X931883Y563000D01*
X931550Y562417D01*
X931383Y561917D01*
Y561417D01*
X931550Y560917D01*
X931967Y560417D01*
X932467Y560083D01*
X933050Y560000D01*
X933633Y560167D01*
X934217Y560667D01*
G01X937233Y560000D02*
Y563333D01*
G01Y562667D02*
X937650Y563000D01*
X938067Y563250D01*
X938650Y563333D01*
X939067Y563250D01*
X939567Y563000D01*
G01X949600Y565000D02*
Y560000D01*
G01X948433Y563333D02*
X950767D01*
G01X953783Y560000D02*
Y565000D01*
G01Y562583D02*
X954200Y563000D01*
X954617Y563250D01*
X955283Y563333D01*
X955783Y563250D01*
X956367Y562917D01*
X956617Y562417D01*
Y560000D01*
G01X962300D02*
Y563333D01*
G01Y562750D02*
X961967Y563083D01*
X961467Y563250D01*
X960883Y563333D01*
X960300Y563167D01*
X959800Y562833D01*
X959467Y562333D01*
X959300Y561667D01*
X959467Y561000D01*
X959800Y560500D01*
X960300Y560167D01*
X960883Y560000D01*
X961467Y560083D01*
X961967Y560333D01*
X962300Y560667D01*
G01X964983Y560000D02*
Y563333D01*
G01Y562500D02*
X965317Y562917D01*
X965817Y563250D01*
X966483Y563333D01*
X967067Y563250D01*
X967567Y562917D01*
X967817Y562333D01*
Y560000D01*
G01X979100D02*
Y563333D01*
G01Y562750D02*
X978767Y563083D01*
X978267Y563250D01*
X977683Y563333D01*
X977100Y563167D01*
X976600Y562833D01*
X976267Y562333D01*
X976100Y561667D01*
X976267Y561000D01*
X976600Y560500D01*
X977100Y560167D01*
X977683Y560000D01*
X978267Y560083D01*
X978767Y560333D01*
X979100Y560667D01*
G01X981783Y560000D02*
Y563333D01*
G01Y562500D02*
X982117Y562917D01*
X982617Y563250D01*
X983283Y563333D01*
X983867Y563250D01*
X984367Y562917D01*
X984617Y562333D01*
Y560000D01*
G01X987383D02*
Y563333D01*
G01Y562500D02*
X987717Y562917D01*
X988217Y563250D01*
X988883Y563333D01*
X989467Y563250D01*
X989967Y562917D01*
X990217Y562333D01*
Y560000D01*
G01X992983Y563333D02*
Y561000D01*
X993317Y560417D01*
X993817Y560083D01*
X994400Y560000D01*
X994983Y560083D01*
X995483Y560417D01*
X995817Y561000D01*
G01Y560000D02*
Y563333D01*
G01X1001500Y560000D02*
Y563333D01*
G01Y562750D02*
X1001167Y563083D01*
X1000667Y563250D01*
X1000083Y563333D01*
X999500Y563167D01*
X999000Y562833D01*
X998667Y562333D01*
X998500Y561667D01*
X998667Y561000D01*
X999000Y560500D01*
X999500Y560167D01*
X1000083Y560000D01*
X1000667Y560083D01*
X1001167Y560333D01*
X1001500Y560667D01*
G01X1005600Y560000D02*
Y565000D01*
G01X822000Y569000D02*
Y574000D01*
X821000Y573000D01*
G01Y569000D02*
X823000D01*
G01X827600Y568833D02*
X827433Y568917D01*
Y569083D01*
X827600Y569167D01*
X827767Y569083D01*
Y568917D01*
X827600Y568833D01*
G01X833200Y569000D02*
X832533Y569083D01*
X831950Y569417D01*
X831450Y569917D01*
X831117Y570500D01*
X830950Y571167D01*
Y571833D01*
X831117Y572500D01*
X831450Y573083D01*
X831950Y573583D01*
X832533Y573917D01*
X833200Y574000D01*
X833867Y573917D01*
X834450Y573583D01*
X834950Y573083D01*
X835283Y572500D01*
X835450Y571833D01*
Y571167D01*
X835283Y570500D01*
X834950Y569917D01*
X834450Y569417D01*
X833867Y569083D01*
X833200Y569000D01*
G01X837383D02*
Y572333D01*
G01Y571500D02*
X837717Y571917D01*
X838217Y572250D01*
X838883Y572333D01*
X839467Y572250D01*
X839967Y571917D01*
X840217Y571333D01*
Y569000D01*
G01X843150Y571250D02*
X845817D01*
X845567Y571833D01*
X845150Y572167D01*
X844567Y572333D01*
X843983Y572250D01*
X843483Y572000D01*
X843150Y571417D01*
X842983Y570917D01*
Y570417D01*
X843150Y569917D01*
X843567Y569417D01*
X844067Y569083D01*
X844650Y569000D01*
X845233Y569167D01*
X845817Y569667D01*
G01X854350Y569583D02*
X854767Y569250D01*
X855350Y569000D01*
X855850D01*
X856350Y569167D01*
X856683Y569417D01*
X856850Y569750D01*
X856767Y570250D01*
X856433Y570500D01*
X854933Y571000D01*
X854600Y571583D01*
X854767Y572000D01*
X855100Y572250D01*
X855600Y572333D01*
X856100Y572250D01*
X856600Y572000D01*
G01X861200Y572333D02*
Y569000D01*
G01Y573667D02*
X861033Y573750D01*
Y573917D01*
X861200Y574000D01*
X861367Y573917D01*
Y573750D01*
X861200Y573667D01*
G01X868300Y574000D02*
Y569000D01*
G01Y569750D02*
X867967Y569333D01*
X867467Y569083D01*
X866883Y569000D01*
X866217Y569167D01*
X865717Y569583D01*
X865383Y570083D01*
X865300Y570667D01*
X865383Y571250D01*
X865717Y571750D01*
X866217Y572167D01*
X866883Y572333D01*
X867467Y572250D01*
X867883Y572083D01*
X868300Y571750D01*
G01X871150Y571250D02*
X873817D01*
X873567Y571833D01*
X873150Y572167D01*
X872567Y572333D01*
X871983Y572250D01*
X871483Y572000D01*
X871150Y571417D01*
X870983Y570917D01*
Y570417D01*
X871150Y569917D01*
X871567Y569417D01*
X872067Y569083D01*
X872650Y569000D01*
X873233Y569167D01*
X873817Y569667D01*
G01X881517Y572333D02*
X882517Y569000D01*
X883600Y572333D01*
X884683Y569000D01*
X885683Y572333D01*
G01X889200D02*
Y569000D01*
G01Y573667D02*
X889033Y573750D01*
Y573917D01*
X889200Y574000D01*
X889367Y573917D01*
Y573750D01*
X889200Y573667D01*
G01X894800Y574000D02*
Y569000D01*
G01X893633Y572333D02*
X895967D01*
G01X898983Y569000D02*
Y574000D01*
G01Y571583D02*
X899400Y572000D01*
X899817Y572250D01*
X900483Y572333D01*
X900983Y572250D01*
X901567Y571917D01*
X901817Y571417D01*
Y569000D01*
G01X910350Y569583D02*
X910767Y569250D01*
X911350Y569000D01*
X911850D01*
X912350Y569167D01*
X912683Y569417D01*
X912850Y569750D01*
X912767Y570250D01*
X912433Y570500D01*
X910933Y571000D01*
X910600Y571583D01*
X910767Y572000D01*
X911100Y572250D01*
X911600Y572333D01*
X912100Y572250D01*
X912600Y572000D01*
G01X917200Y569000D02*
X916700Y569083D01*
X916200Y569417D01*
X915867Y570000D01*
X915700Y570667D01*
X915867Y571333D01*
X916200Y571917D01*
X916700Y572250D01*
X917200Y572333D01*
X917700Y572250D01*
X918200Y571917D01*
X918533Y571333D01*
X918617Y570667D01*
X918533Y570000D01*
X918200Y569417D01*
X917700Y569083D01*
X917200Y569000D01*
G01X922800D02*
Y574000D01*
G01X929900D02*
Y569000D01*
G01Y569750D02*
X929567Y569333D01*
X929067Y569083D01*
X928483Y569000D01*
X927817Y569167D01*
X927317Y569583D01*
X926983Y570083D01*
X926900Y570667D01*
X926983Y571250D01*
X927317Y571750D01*
X927817Y572167D01*
X928483Y572333D01*
X929067Y572250D01*
X929483Y572083D01*
X929900Y571750D01*
G01X932750Y571250D02*
X935417D01*
X935167Y571833D01*
X934750Y572167D01*
X934167Y572333D01*
X933583Y572250D01*
X933083Y572000D01*
X932750Y571417D01*
X932583Y570917D01*
Y570417D01*
X932750Y569917D01*
X933167Y569417D01*
X933667Y569083D01*
X934250Y569000D01*
X934833Y569167D01*
X935417Y569667D01*
G01X938433Y569000D02*
Y572333D01*
G01Y571667D02*
X938850Y572000D01*
X939267Y572250D01*
X939850Y572333D01*
X940267Y572250D01*
X940767Y572000D01*
G01X948300Y569000D02*
Y572333D01*
G01Y571417D02*
X948550Y571833D01*
X948967Y572167D01*
X949550Y572333D01*
X950133Y572167D01*
X950550Y571833D01*
X950800Y571417D01*
Y569000D01*
G01Y571417D02*
X951050Y571833D01*
X951467Y572167D01*
X952050Y572333D01*
X952633Y572167D01*
X953050Y571833D01*
X953300Y571333D01*
Y569000D01*
G01X957900D02*
Y572333D01*
G01Y571750D02*
X957567Y572083D01*
X957067Y572250D01*
X956483Y572333D01*
X955900Y572167D01*
X955400Y571833D01*
X955067Y571333D01*
X954900Y570667D01*
X955067Y570000D01*
X955400Y569500D01*
X955900Y569167D01*
X956483Y569000D01*
X957067Y569083D01*
X957567Y569333D01*
X957900Y569667D01*
G01X960750Y569583D02*
X961167Y569250D01*
X961750Y569000D01*
X962250D01*
X962750Y569167D01*
X963083Y569417D01*
X963250Y569750D01*
X963167Y570250D01*
X962833Y570500D01*
X961333Y571000D01*
X961000Y571583D01*
X961167Y572000D01*
X961500Y572250D01*
X962000Y572333D01*
X962500Y572250D01*
X963000Y572000D01*
G01X966183Y569000D02*
Y574000D01*
G01X968850Y572333D02*
X966183Y570417D01*
G01X967267Y571167D02*
X969017Y569000D01*
G01X977300Y567333D02*
Y572333D01*
G01Y571583D02*
X977717Y572000D01*
X978133Y572250D01*
X978800Y572333D01*
X979383Y572250D01*
X979967Y571833D01*
X980217Y571250D01*
X980300Y570667D01*
X980217Y570083D01*
X979967Y569500D01*
X979467Y569167D01*
X978800Y569000D01*
X978217Y569083D01*
X977633Y569333D01*
X977300Y569667D01*
G01X985900Y569000D02*
Y572333D01*
G01Y571750D02*
X985567Y572083D01*
X985067Y572250D01*
X984483Y572333D01*
X983900Y572167D01*
X983400Y571833D01*
X983067Y571333D01*
X982900Y570667D01*
X983067Y570000D01*
X983400Y569500D01*
X983900Y569167D01*
X984483Y569000D01*
X985067Y569083D01*
X985567Y569333D01*
X985900Y569667D01*
G01X991500Y574000D02*
Y569000D01*
G01Y569750D02*
X991167Y569333D01*
X990667Y569083D01*
X990083Y569000D01*
X989417Y569167D01*
X988917Y569583D01*
X988583Y570083D01*
X988500Y570667D01*
X988583Y571250D01*
X988917Y571750D01*
X989417Y572167D01*
X990083Y572333D01*
X990667Y572250D01*
X991083Y572083D01*
X991500Y571750D01*
G01X831333Y551000D02*
Y554333D01*
G01Y553667D02*
X831750Y554000D01*
X832167Y554250D01*
X832750Y554333D01*
X833167Y554250D01*
X833667Y554000D01*
G01X838100Y554333D02*
Y551000D01*
G01Y555667D02*
X837933Y555750D01*
Y555917D01*
X838100Y556000D01*
X838267Y555917D01*
Y555750D01*
X838100Y555667D01*
G01X842283Y551000D02*
Y554333D01*
G01Y553500D02*
X842617Y553917D01*
X843117Y554250D01*
X843783Y554333D01*
X844367Y554250D01*
X844867Y553917D01*
X845117Y553333D01*
Y551000D01*
G01X848133Y549750D02*
X848717Y549417D01*
X849383Y549333D01*
X849967Y549417D01*
X850467Y549833D01*
X850800Y550417D01*
Y554333D01*
G01Y553667D02*
X850467Y554000D01*
X849967Y554250D01*
X849383Y554333D01*
X848717Y554167D01*
X848300Y553833D01*
X847967Y553250D01*
X847800Y552667D01*
X847883Y552167D01*
X848217Y551583D01*
X848717Y551167D01*
X849383Y551000D01*
X849883Y551083D01*
X850467Y551417D01*
X850800Y551750D01*
G01X859250Y551583D02*
X859667Y551250D01*
X860250Y551000D01*
X860750D01*
X861250Y551167D01*
X861583Y551417D01*
X861750Y551750D01*
X861667Y552250D01*
X861333Y552500D01*
X859833Y553000D01*
X859500Y553583D01*
X859667Y554000D01*
X860000Y554250D01*
X860500Y554333D01*
X861000Y554250D01*
X861500Y554000D01*
G01X866100Y554333D02*
Y551000D01*
G01Y555667D02*
X865933Y555750D01*
Y555917D01*
X866100Y556000D01*
X866267Y555917D01*
Y555750D01*
X866100Y555667D01*
G01X870450Y554333D02*
X872950D01*
X870450Y551000D01*
X872950D01*
G01X876050Y553250D02*
X878717D01*
X878467Y553833D01*
X878050Y554167D01*
X877467Y554333D01*
X876883Y554250D01*
X876383Y554000D01*
X876050Y553417D01*
X875883Y552917D01*
Y552417D01*
X876050Y551917D01*
X876467Y551417D01*
X876967Y551083D01*
X877550Y551000D01*
X878133Y551167D01*
X878717Y551667D01*
G01X888333Y550083D02*
X888667Y551167D01*
G01X809000Y686500D02*
Y691500D01*
G01Y689000D02*
X809417Y689500D01*
X809917Y689750D01*
X810417Y689833D01*
X811167Y689667D01*
X811667Y689333D01*
X812000Y688750D01*
Y688083D01*
X811833Y687417D01*
X811500Y686917D01*
X810917Y686583D01*
X810417Y686500D01*
X809917Y686583D01*
X809417Y686833D01*
X809000Y687250D01*
G01X816100Y686500D02*
X815600Y686583D01*
X815100Y686917D01*
X814767Y687500D01*
X814600Y688167D01*
X814767Y688833D01*
X815100Y689417D01*
X815600Y689750D01*
X816100Y689833D01*
X816600Y689750D01*
X817100Y689417D01*
X817433Y688833D01*
X817517Y688167D01*
X817433Y687500D01*
X817100Y686917D01*
X816600Y686583D01*
X816100Y686500D01*
G01X823200D02*
Y689833D01*
G01Y689250D02*
X822867Y689583D01*
X822367Y689750D01*
X821783Y689833D01*
X821200Y689667D01*
X820700Y689333D01*
X820367Y688833D01*
X820200Y688167D01*
X820367Y687500D01*
X820700Y687000D01*
X821200Y686667D01*
X821783Y686500D01*
X822367Y686583D01*
X822867Y686833D01*
X823200Y687167D01*
G01X826133Y686500D02*
Y689833D01*
G01Y689167D02*
X826550Y689500D01*
X826967Y689750D01*
X827550Y689833D01*
X827967Y689750D01*
X828467Y689500D01*
G01X834400Y691500D02*
Y686500D01*
G01Y687250D02*
X834067Y686833D01*
X833567Y686583D01*
X832983Y686500D01*
X832317Y686667D01*
X831817Y687083D01*
X831483Y687583D01*
X831400Y688167D01*
X831483Y688750D01*
X831817Y689250D01*
X832317Y689667D01*
X832983Y689833D01*
X833567Y689750D01*
X833983Y689583D01*
X834400Y689250D01*
G01X843083Y734500D02*
Y739500D01*
G01Y737083D02*
X843500Y737500D01*
X843917Y737750D01*
X844583Y737833D01*
X845083Y737750D01*
X845667Y737417D01*
X845917Y736917D01*
Y734500D01*
G01X851600D02*
Y737833D01*
G01Y737250D02*
X851267Y737583D01*
X850767Y737750D01*
X850183Y737833D01*
X849600Y737667D01*
X849100Y737333D01*
X848767Y736833D01*
X848600Y736167D01*
X848767Y735500D01*
X849100Y735000D01*
X849600Y734667D01*
X850183Y734500D01*
X850767Y734583D01*
X851267Y734833D01*
X851600Y735167D01*
G01X855700Y734500D02*
Y739500D01*
G01X860800Y734500D02*
Y738750D01*
X860967Y739167D01*
X861300Y739417D01*
X861800Y739500D01*
X862300Y739333D01*
X862550Y738917D01*
G01X861550Y737500D02*
X859883D01*
G01X871000Y732833D02*
Y737833D01*
G01Y737083D02*
X871417Y737500D01*
X871833Y737750D01*
X872500Y737833D01*
X873083Y737750D01*
X873667Y737333D01*
X873917Y736750D01*
X874000Y736167D01*
X873917Y735583D01*
X873667Y735000D01*
X873167Y734667D01*
X872500Y734500D01*
X871917Y734583D01*
X871333Y734833D01*
X871000Y735167D01*
G01X878100Y734500D02*
Y739500D01*
G01X882283Y737833D02*
Y735500D01*
X882617Y734917D01*
X883117Y734583D01*
X883700Y734500D01*
X884283Y734583D01*
X884783Y734917D01*
X885117Y735500D01*
G01Y734500D02*
Y737833D01*
G01X888133Y733250D02*
X888717Y732917D01*
X889383Y732833D01*
X889967Y732917D01*
X890467Y733333D01*
X890800Y733917D01*
Y737833D01*
G01Y737167D02*
X890467Y737500D01*
X889967Y737750D01*
X889383Y737833D01*
X888717Y737667D01*
X888300Y737333D01*
X887967Y736750D01*
X887800Y736167D01*
X887883Y735667D01*
X888217Y735083D01*
X888717Y734667D01*
X889383Y734500D01*
X889883Y734583D01*
X890467Y734917D01*
X890800Y735250D01*
G01X893733Y733250D02*
X894317Y732917D01*
X894983Y732833D01*
X895567Y732917D01*
X896067Y733333D01*
X896400Y733917D01*
Y737833D01*
G01Y737167D02*
X896067Y737500D01*
X895567Y737750D01*
X894983Y737833D01*
X894317Y737667D01*
X893900Y737333D01*
X893567Y736750D01*
X893400Y736167D01*
X893483Y735667D01*
X893817Y735083D01*
X894317Y734667D01*
X894983Y734500D01*
X895483Y734583D01*
X896067Y734917D01*
X896400Y735250D01*
G01X900500Y737833D02*
Y734500D01*
G01Y739167D02*
X900333Y739250D01*
Y739417D01*
X900500Y739500D01*
X900667Y739417D01*
Y739250D01*
X900500Y739167D01*
G01X904683Y734500D02*
Y737833D01*
G01Y737000D02*
X905017Y737417D01*
X905517Y737750D01*
X906183Y737833D01*
X906767Y737750D01*
X907267Y737417D01*
X907517Y736833D01*
Y734500D01*
G01X910533Y733250D02*
X911117Y732917D01*
X911783Y732833D01*
X912367Y732917D01*
X912867Y733333D01*
X913200Y733917D01*
Y737833D01*
G01Y737167D02*
X912867Y737500D01*
X912367Y737750D01*
X911783Y737833D01*
X911117Y737667D01*
X910700Y737333D01*
X910367Y736750D01*
X910200Y736167D01*
X910283Y735667D01*
X910617Y735083D01*
X911117Y734667D01*
X911783Y734500D01*
X912283Y734583D01*
X912867Y734917D01*
X913200Y735250D01*
G01X868250Y152000D02*
Y157000D01*
G01X871750D02*
Y152000D01*
G01Y154500D02*
X868250D01*
G01X875600Y152000D02*
X874933Y152083D01*
X874350Y152417D01*
X873850Y152917D01*
X873517Y153500D01*
X873350Y154167D01*
Y154833D01*
X873517Y155500D01*
X873850Y156083D01*
X874350Y156583D01*
X874933Y156917D01*
X875600Y157000D01*
X876267Y156917D01*
X876850Y156583D01*
X877350Y156083D01*
X877683Y155500D01*
X877850Y154833D01*
Y154167D01*
X877683Y153500D01*
X877350Y152917D01*
X876850Y152417D01*
X876267Y152083D01*
X875600Y152000D01*
G01X879533Y157000D02*
Y152000D01*
X882867D01*
G01X888467D02*
X885133D01*
Y157000D01*
X888467D01*
G01X887133Y154583D02*
X885133D01*
G01X912300Y152000D02*
Y155333D01*
G01Y154417D02*
X912550Y154833D01*
X912967Y155167D01*
X913550Y155333D01*
X914133Y155167D01*
X914550Y154833D01*
X914800Y154417D01*
Y152000D01*
G01Y154417D02*
X915050Y154833D01*
X915467Y155167D01*
X916050Y155333D01*
X916633Y155167D01*
X917050Y154833D01*
X917300Y154333D01*
Y152000D01*
G01X920400Y155333D02*
Y152000D01*
G01Y156667D02*
X920233Y156750D01*
Y156917D01*
X920400Y157000D01*
X920567Y156917D01*
Y156750D01*
X920400Y156667D01*
G01X926000Y152000D02*
Y157000D01*
G01X930350Y152583D02*
X930767Y152250D01*
X931350Y152000D01*
X931850D01*
X932350Y152167D01*
X932683Y152417D01*
X932850Y152750D01*
X932767Y153250D01*
X932433Y153500D01*
X930933Y154000D01*
X930600Y154583D01*
X930767Y155000D01*
X931100Y155250D01*
X931600Y155333D01*
X932100Y155250D01*
X932600Y155000D01*
G01X936783Y150333D02*
X935950Y151167D01*
X935533Y152000D01*
Y155333D01*
X935950Y156167D01*
X936783Y157000D01*
G01X941133Y152000D02*
Y157000D01*
X943133D01*
X943800Y156750D01*
X944300Y156167D01*
X944467Y155500D01*
X944300Y154833D01*
X943883Y154333D01*
X943133Y154083D01*
X941133D01*
G01X948400Y157000D02*
Y152000D01*
G01X946483Y157000D02*
X950317D01*
G01X952250Y152000D02*
Y157000D01*
G01X955750D02*
Y152000D01*
G01Y154500D02*
X952250D01*
G01X960017Y150333D02*
X960850Y151167D01*
X961267Y152000D01*
Y155333D01*
X960850Y156167D01*
X960017Y157000D01*
G01X900833Y214500D02*
Y209500D01*
X904167D01*
G01X906683D02*
Y212833D01*
G01Y212000D02*
X907017Y212417D01*
X907517Y212750D01*
X908183Y212833D01*
X908767Y212750D01*
X909267Y212417D01*
X909517Y211833D01*
Y209500D01*
G01X868167Y308167D02*
X868500Y308417D01*
X868750Y308833D01*
X868917Y309417D01*
X868750Y309917D01*
X868417Y310250D01*
X867833Y310500D01*
X865583D01*
Y305500D01*
X868333D01*
X868917Y305833D01*
X869250Y306333D01*
X869417Y306917D01*
X869250Y307500D01*
X868750Y308000D01*
X868167Y308167D01*
X865583D01*
G01X871017Y305500D02*
X873100Y310500D01*
X875183Y305500D01*
G01X874433Y307250D02*
X871767D01*
G01X880533Y310083D02*
X880033Y310333D01*
X879450Y310500D01*
X878783D01*
X878033Y310250D01*
X877450Y309833D01*
X877033Y309333D01*
X876700Y308500D01*
X876617Y307750D01*
X876783Y307000D01*
X877033Y306500D01*
X877533Y306000D01*
X878117Y305667D01*
X878700Y305500D01*
X879283D01*
X879867Y305667D01*
X880367Y305917D01*
X880783Y306250D01*
G01X882467Y305500D02*
Y310500D01*
G01X885633D02*
X882467Y307417D01*
G01X886133Y305500D02*
X883883Y308833D01*
G01X893667Y305500D02*
Y310500D01*
X895333D01*
X896000Y310250D01*
X896500Y309917D01*
X896917Y309417D01*
X897250Y308833D01*
X897333Y308000D01*
X897250Y307167D01*
X896917Y306583D01*
X896500Y306083D01*
X896000Y305750D01*
X895333Y305500D01*
X893667D01*
G01X899433D02*
Y310500D01*
X901517D01*
X902183Y310250D01*
X902600Y309917D01*
X902767Y309250D01*
X902600Y308583D01*
X902100Y308167D01*
X901517Y307917D01*
X899433D01*
G01X901517D02*
X902767Y305500D01*
G01X905700Y310500D02*
X907700D01*
G01X906700D02*
Y305500D01*
G01X905700D02*
X907700D01*
G01X910633Y310500D02*
Y305500D01*
X913967D01*
G01X916233Y310500D02*
Y305500D01*
X919567D01*
G01X943400D02*
Y308833D01*
G01Y307917D02*
X943650Y308333D01*
X944067Y308667D01*
X944650Y308833D01*
X945233Y308667D01*
X945650Y308333D01*
X945900Y307917D01*
Y305500D01*
G01Y307917D02*
X946150Y308333D01*
X946567Y308667D01*
X947150Y308833D01*
X947733Y308667D01*
X948150Y308333D01*
X948400Y307833D01*
Y305500D01*
G01X951500Y308833D02*
Y305500D01*
G01Y310167D02*
X951333Y310250D01*
Y310417D01*
X951500Y310500D01*
X951667Y310417D01*
Y310250D01*
X951500Y310167D01*
G01X957100Y305500D02*
Y310500D01*
G01X961450Y306083D02*
X961867Y305750D01*
X962450Y305500D01*
X962950D01*
X963450Y305667D01*
X963783Y305917D01*
X963950Y306250D01*
X963867Y306750D01*
X963533Y307000D01*
X962033Y307500D01*
X961700Y308083D01*
X961867Y308500D01*
X962200Y308750D01*
X962700Y308833D01*
X963200Y308750D01*
X963700Y308500D01*
G01X967883Y303833D02*
X967050Y304667D01*
X966633Y305500D01*
Y308833D01*
X967050Y309667D01*
X967883Y310500D01*
G01X971983Y305500D02*
Y310500D01*
X975817Y305500D01*
Y310500D01*
G01X977833Y305500D02*
Y310500D01*
X979833D01*
X980500Y310250D01*
X981000Y309667D01*
X981167Y309000D01*
X981000Y308333D01*
X980583Y307833D01*
X979833Y307583D01*
X977833D01*
G01X985100Y310500D02*
Y305500D01*
G01X983183Y310500D02*
X987017D01*
G01X988950Y305500D02*
Y310500D01*
G01X992450D02*
Y305500D01*
G01Y308000D02*
X988950D01*
G01X996717Y303833D02*
X997550Y304667D01*
X997967Y305500D01*
Y308833D01*
X997550Y309667D01*
X996717Y310500D01*
G01X889267Y349073D02*
X892933Y352740D01*
G01X891100Y353407D02*
Y348407D01*
G01X892933Y349073D02*
X889267Y352740D01*
G01X888600Y350907D02*
X893600D01*
G01X896283Y347573D02*
X895450Y348407D01*
X895033Y349240D01*
Y352573D01*
X895450Y353407D01*
X896283Y354240D01*
G01X900467Y349990D02*
X900967Y349573D01*
X901550Y349323D01*
X902300Y349240D01*
X903050Y349407D01*
X903633Y349740D01*
X904050Y350323D01*
X904133Y350990D01*
X903967Y351657D01*
X903550Y352073D01*
X902967Y352407D01*
X902383Y352490D01*
X901800Y352407D01*
X901050Y352073D01*
X901300Y354240D01*
X903550D01*
G01X907900Y349073D02*
X907733Y349157D01*
Y349323D01*
X907900Y349407D01*
X908067Y349323D01*
Y349157D01*
X907900Y349073D01*
G01X913500Y349240D02*
Y354240D01*
X912500Y353240D01*
G01Y349240D02*
X914500D01*
G01X919517Y347573D02*
X920350Y348407D01*
X920767Y349240D01*
Y352573D01*
X920350Y353407D01*
X919517Y354240D01*
G01X894000Y556000D02*
Y551000D01*
G01X892833Y554333D02*
X895167D01*
G01X898183Y551000D02*
Y556000D01*
G01Y553583D02*
X898600Y554000D01*
X899017Y554250D01*
X899683Y554333D01*
X900183Y554250D01*
X900767Y553917D01*
X901017Y553417D01*
Y551000D01*
G01X903950Y553250D02*
X906617D01*
X906367Y553833D01*
X905950Y554167D01*
X905367Y554333D01*
X904783Y554250D01*
X904283Y554000D01*
X903950Y553417D01*
X903783Y552917D01*
Y552417D01*
X903950Y551917D01*
X904367Y551417D01*
X904867Y551083D01*
X905450Y551000D01*
X906033Y551167D01*
X906617Y551667D01*
G01X916400Y551000D02*
X915900Y551083D01*
X915400Y551417D01*
X915067Y552000D01*
X914900Y552667D01*
X915067Y553333D01*
X915400Y553917D01*
X915900Y554250D01*
X916400Y554333D01*
X916900Y554250D01*
X917400Y553917D01*
X917733Y553333D01*
X917817Y552667D01*
X917733Y552000D01*
X917400Y551417D01*
X916900Y551083D01*
X916400Y551000D01*
G01X922000Y556000D02*
Y551000D01*
G01X920833Y554333D02*
X923167D01*
G01X926183Y551000D02*
Y556000D01*
G01Y553583D02*
X926600Y554000D01*
X927017Y554250D01*
X927683Y554333D01*
X928183Y554250D01*
X928767Y553917D01*
X929017Y553417D01*
Y551000D01*
G01X931950Y553250D02*
X934617D01*
X934367Y553833D01*
X933950Y554167D01*
X933367Y554333D01*
X932783Y554250D01*
X932283Y554000D01*
X931950Y553417D01*
X931783Y552917D01*
Y552417D01*
X931950Y551917D01*
X932367Y551417D01*
X932867Y551083D01*
X933450Y551000D01*
X934033Y551167D01*
X934617Y551667D01*
G01X937633Y551000D02*
Y554333D01*
G01Y553667D02*
X938050Y554000D01*
X938467Y554250D01*
X939050Y554333D01*
X939467Y554250D01*
X939967Y554000D01*
G01X948750Y551583D02*
X949167Y551250D01*
X949750Y551000D01*
X950250D01*
X950750Y551167D01*
X951083Y551417D01*
X951250Y551750D01*
X951167Y552250D01*
X950833Y552500D01*
X949333Y553000D01*
X949000Y553583D01*
X949167Y554000D01*
X949500Y554250D01*
X950000Y554333D01*
X950500Y554250D01*
X951000Y554000D01*
G01X955600Y554333D02*
Y551000D01*
G01Y555667D02*
X955433Y555750D01*
Y555917D01*
X955600Y556000D01*
X955767Y555917D01*
Y555750D01*
X955600Y555667D01*
G01X962700Y556000D02*
Y551000D01*
G01Y551750D02*
X962367Y551333D01*
X961867Y551083D01*
X961283Y551000D01*
X960617Y551167D01*
X960117Y551583D01*
X959783Y552083D01*
X959700Y552667D01*
X959783Y553250D01*
X960117Y553750D01*
X960617Y554167D01*
X961283Y554333D01*
X961867Y554250D01*
X962283Y554083D01*
X962700Y553750D01*
G01X965550Y553250D02*
X968217D01*
X967967Y553833D01*
X967550Y554167D01*
X966967Y554333D01*
X966383Y554250D01*
X965883Y554000D01*
X965550Y553417D01*
X965383Y552917D01*
Y552417D01*
X965550Y551917D01*
X965967Y551417D01*
X966467Y551083D01*
X967050Y551000D01*
X967633Y551167D01*
X968217Y551667D01*
G01X975917Y554333D02*
X976917Y551000D01*
X978000Y554333D01*
X979083Y551000D01*
X980083Y554333D01*
G01X983600D02*
Y551000D01*
G01Y555667D02*
X983433Y555750D01*
Y555917D01*
X983600Y556000D01*
X983767Y555917D01*
Y555750D01*
X983600Y555667D01*
G01X989200Y556000D02*
Y551000D01*
G01X988033Y554333D02*
X990367D01*
G01X993383Y551000D02*
Y556000D01*
G01Y553583D02*
X993800Y554000D01*
X994217Y554250D01*
X994883Y554333D01*
X995383Y554250D01*
X995967Y553917D01*
X996217Y553417D01*
Y551000D01*
G01X1000400D02*
X999900Y551083D01*
X999400Y551417D01*
X999067Y552000D01*
X998900Y552667D01*
X999067Y553333D01*
X999400Y553917D01*
X999900Y554250D01*
X1000400Y554333D01*
X1000900Y554250D01*
X1001400Y553917D01*
X1001733Y553333D01*
X1001817Y552667D01*
X1001733Y552000D01*
X1001400Y551417D01*
X1000900Y551083D01*
X1000400Y551000D01*
G01X1004583Y554333D02*
Y552000D01*
X1004917Y551417D01*
X1005417Y551083D01*
X1006000Y551000D01*
X1006583Y551083D01*
X1007083Y551417D01*
X1007417Y552000D01*
G01Y551000D02*
Y554333D01*
G01X1011600Y556000D02*
Y551000D01*
G01X1010433Y554333D02*
X1012767D01*
G01X878000Y591500D02*
X879667D01*
Y590000D01*
X879167Y589500D01*
X878583Y589167D01*
X877750Y589000D01*
X876917Y589167D01*
X876333Y589500D01*
X875833Y590000D01*
X875500Y590583D01*
X875333Y591250D01*
Y591833D01*
X875500Y592333D01*
X875833Y592917D01*
X876333Y593417D01*
X876833Y593750D01*
X877500Y594000D01*
X878083D01*
X878750Y593833D01*
X879250Y593500D01*
G01X881850Y591250D02*
X884517D01*
X884267Y591833D01*
X883850Y592167D01*
X883267Y592333D01*
X882683Y592250D01*
X882183Y592000D01*
X881850Y591417D01*
X881683Y590917D01*
Y590417D01*
X881850Y589917D01*
X882267Y589417D01*
X882767Y589083D01*
X883350Y589000D01*
X883933Y589167D01*
X884517Y589667D01*
G01X887533Y589000D02*
Y592333D01*
G01Y591667D02*
X887950Y592000D01*
X888367Y592250D01*
X888950Y592333D01*
X889367Y592250D01*
X889867Y592000D01*
G01X892800Y589000D02*
Y594000D01*
G01Y591500D02*
X893217Y592000D01*
X893717Y592250D01*
X894217Y592333D01*
X894967Y592167D01*
X895467Y591833D01*
X895800Y591250D01*
Y590583D01*
X895633Y589917D01*
X895300Y589417D01*
X894717Y589083D01*
X894217Y589000D01*
X893717Y589083D01*
X893217Y589333D01*
X892800Y589750D01*
G01X898650Y591250D02*
X901317D01*
X901067Y591833D01*
X900650Y592167D01*
X900067Y592333D01*
X899483Y592250D01*
X898983Y592000D01*
X898650Y591417D01*
X898483Y590917D01*
Y590417D01*
X898650Y589917D01*
X899067Y589417D01*
X899567Y589083D01*
X900150Y589000D01*
X900733Y589167D01*
X901317Y589667D01*
G01X904333Y589000D02*
Y592333D01*
G01Y591667D02*
X904750Y592000D01*
X905167Y592250D01*
X905750Y592333D01*
X906167Y592250D01*
X906667Y592000D01*
G01X918200Y594000D02*
Y589000D01*
G01Y589750D02*
X917867Y589333D01*
X917367Y589083D01*
X916783Y589000D01*
X916117Y589167D01*
X915617Y589583D01*
X915283Y590083D01*
X915200Y590667D01*
X915283Y591250D01*
X915617Y591750D01*
X916117Y592167D01*
X916783Y592333D01*
X917367Y592250D01*
X917783Y592083D01*
X918200Y591750D01*
G01X921050Y591250D02*
X923717D01*
X923467Y591833D01*
X923050Y592167D01*
X922467Y592333D01*
X921883Y592250D01*
X921383Y592000D01*
X921050Y591417D01*
X920883Y590917D01*
Y590417D01*
X921050Y589917D01*
X921467Y589417D01*
X921967Y589083D01*
X922550Y589000D01*
X923133Y589167D01*
X923717Y589667D01*
G01X926650Y589583D02*
X927067Y589250D01*
X927650Y589000D01*
X928150D01*
X928650Y589167D01*
X928983Y589417D01*
X929150Y589750D01*
X929067Y590250D01*
X928733Y590500D01*
X927233Y591000D01*
X926900Y591583D01*
X927067Y592000D01*
X927400Y592250D01*
X927900Y592333D01*
X928400Y592250D01*
X928900Y592000D01*
G01X933500Y592333D02*
Y589000D01*
G01Y593667D02*
X933333Y593750D01*
Y593917D01*
X933500Y594000D01*
X933667Y593917D01*
Y593750D01*
X933500Y593667D01*
G01X937933Y587750D02*
X938517Y587417D01*
X939183Y587333D01*
X939767Y587417D01*
X940267Y587833D01*
X940600Y588417D01*
Y592333D01*
G01Y591667D02*
X940267Y592000D01*
X939767Y592250D01*
X939183Y592333D01*
X938517Y592167D01*
X938100Y591833D01*
X937767Y591250D01*
X937600Y590667D01*
X937683Y590167D01*
X938017Y589583D01*
X938517Y589167D01*
X939183Y589000D01*
X939683Y589083D01*
X940267Y589417D01*
X940600Y589750D01*
G01X943283Y589000D02*
Y592333D01*
G01Y591500D02*
X943617Y591917D01*
X944117Y592250D01*
X944783Y592333D01*
X945367Y592250D01*
X945867Y591917D01*
X946117Y591333D01*
Y589000D01*
G01X928583Y23083D02*
X929167Y22667D01*
X929833Y22500D01*
X930500Y22667D01*
X931083Y23167D01*
X931500Y23917D01*
X931667Y24667D01*
Y25583D01*
X931500Y26333D01*
X931083Y27000D01*
X930583Y27333D01*
X930000Y27500D01*
X929333Y27333D01*
X928833Y27000D01*
X928500Y26500D01*
X928333Y25833D01*
X928500Y25250D01*
X928917Y24667D01*
X929417Y24333D01*
X930000Y24250D01*
X930667Y24417D01*
X931167Y24833D01*
X931667Y25583D01*
G01X934017Y24583D02*
X934600Y25167D01*
X935100Y25500D01*
X935767Y25667D01*
X936350Y25500D01*
X936767Y25167D01*
X937100Y24667D01*
X937183Y24083D01*
X937100Y23583D01*
X936767Y23083D01*
X936267Y22667D01*
X935683Y22500D01*
X935017Y22667D01*
X934433Y23167D01*
X934100Y23917D01*
X934017Y24750D01*
X934183Y25833D01*
X934433Y26417D01*
X934850Y27000D01*
X935433Y27417D01*
X936017Y27500D01*
X936600Y27333D01*
X937017Y26917D01*
G01X909000Y67500D02*
Y72500D01*
X905917Y68917D01*
X910083D01*
G01X911767Y68250D02*
X912267Y67833D01*
X912850Y67583D01*
X913600Y67500D01*
X914350Y67667D01*
X914933Y68000D01*
X915350Y68583D01*
X915433Y69250D01*
X915267Y69917D01*
X914850Y70333D01*
X914267Y70667D01*
X913683Y70750D01*
X913100Y70667D01*
X912350Y70333D01*
X912600Y72500D01*
X914850D01*
G01X909250Y184083D02*
X909667Y183750D01*
X910250Y183500D01*
X910750D01*
X911250Y183667D01*
X911583Y183917D01*
X911750Y184250D01*
X911667Y184750D01*
X911333Y185000D01*
X909833Y185500D01*
X909500Y186083D01*
X909667Y186500D01*
X910000Y186750D01*
X910500Y186833D01*
X911000Y186750D01*
X911500Y186500D01*
G01X916100Y188500D02*
Y183500D01*
G01X914933Y186833D02*
X917267D01*
G01X920283D02*
Y184500D01*
X920617Y183917D01*
X921117Y183583D01*
X921700Y183500D01*
X922283Y183583D01*
X922783Y183917D01*
X923117Y184500D01*
G01Y183500D02*
Y186833D01*
G01X925800Y183500D02*
Y188500D01*
G01Y186000D02*
X926217Y186500D01*
X926717Y186750D01*
X927217Y186833D01*
X927967Y186667D01*
X928467Y186333D01*
X928800Y185750D01*
Y185083D01*
X928633Y184417D01*
X928300Y183917D01*
X927717Y183583D01*
X927217Y183500D01*
X926717Y183583D01*
X926217Y183833D01*
X925800Y184250D01*
G01X938500Y183500D02*
Y188500D01*
G01X942850Y185750D02*
X945517D01*
X945267Y186333D01*
X944850Y186667D01*
X944267Y186833D01*
X943683Y186750D01*
X943183Y186500D01*
X942850Y185917D01*
X942683Y185417D01*
Y184917D01*
X942850Y184417D01*
X943267Y183917D01*
X943767Y183583D01*
X944350Y183500D01*
X944933Y183667D01*
X945517Y184167D01*
G01X948283Y183500D02*
Y186833D01*
G01Y186000D02*
X948617Y186417D01*
X949117Y186750D01*
X949783Y186833D01*
X950367Y186750D01*
X950867Y186417D01*
X951117Y185833D01*
Y183500D01*
G01X954133Y182250D02*
X954717Y181917D01*
X955383Y181833D01*
X955967Y181917D01*
X956467Y182333D01*
X956800Y182917D01*
Y186833D01*
G01Y186167D02*
X956467Y186500D01*
X955967Y186750D01*
X955383Y186833D01*
X954717Y186667D01*
X954300Y186333D01*
X953967Y185750D01*
X953800Y185167D01*
X953883Y184667D01*
X954217Y184083D01*
X954717Y183667D01*
X955383Y183500D01*
X955883Y183583D01*
X956467Y183917D01*
X956800Y184250D01*
G01X960900Y188500D02*
Y183500D01*
G01X959733Y186833D02*
X962067D01*
G01X965083Y183500D02*
Y188500D01*
G01Y186083D02*
X965500Y186500D01*
X965917Y186750D01*
X966583Y186833D01*
X967083Y186750D01*
X967667Y186417D01*
X967917Y185917D01*
Y183500D01*
G01X971017Y184417D02*
X973183D01*
G01Y185917D02*
X971017D01*
G01X976117Y185583D02*
X976700Y186167D01*
X977200Y186500D01*
X977867Y186667D01*
X978450Y186500D01*
X978867Y186167D01*
X979200Y185667D01*
X979283Y185083D01*
X979200Y184583D01*
X978867Y184083D01*
X978367Y183667D01*
X977783Y183500D01*
X977117Y183667D01*
X976533Y184167D01*
X976200Y184917D01*
X976117Y185750D01*
X976283Y186833D01*
X976533Y187417D01*
X976950Y188000D01*
X977533Y188417D01*
X978117Y188500D01*
X978700Y188333D01*
X979117Y187917D01*
G01X982383Y185167D02*
X984383D01*
G01X983300Y186250D02*
Y184083D01*
G01X987400Y183333D02*
X990400Y188500D01*
G01X993417Y185167D02*
X995583D01*
G01X998267Y184250D02*
X998767Y183833D01*
X999350Y183583D01*
X1000100Y183500D01*
X1000850Y183667D01*
X1001433Y184000D01*
X1001850Y184583D01*
X1001933Y185250D01*
X1001767Y185917D01*
X1001350Y186333D01*
X1000767Y186667D01*
X1000183Y186750D01*
X999600Y186667D01*
X998850Y186333D01*
X999100Y188500D01*
X1001350D01*
G01X1003200Y183500D02*
Y186833D01*
G01Y185917D02*
X1003450Y186333D01*
X1003867Y186667D01*
X1004450Y186833D01*
X1005033Y186667D01*
X1005450Y186333D01*
X1005700Y185917D01*
Y183500D01*
G01Y185917D02*
X1005950Y186333D01*
X1006367Y186667D01*
X1006950Y186833D01*
X1007533Y186667D01*
X1007950Y186333D01*
X1008200Y185833D01*
Y183500D01*
G01X1011300Y186833D02*
Y183500D01*
G01Y188167D02*
X1011133Y188250D01*
Y188417D01*
X1011300Y188500D01*
X1011467Y188417D01*
Y188250D01*
X1011300Y188167D01*
G01X1016900Y183500D02*
Y188500D01*
G01X902833Y255500D02*
Y250500D01*
X906167D01*
G01X908850Y253833D02*
X911350Y250500D01*
G01Y253833D02*
X908850Y250500D01*
G01X929000Y734500D02*
Y738750D01*
X929167Y739167D01*
X929500Y739417D01*
X930000Y739500D01*
X930500Y739333D01*
X930750Y738917D01*
G01X929750Y737500D02*
X928083D01*
G01X933683Y737833D02*
Y735500D01*
X934017Y734917D01*
X934517Y734583D01*
X935100Y734500D01*
X935683Y734583D01*
X936183Y734917D01*
X936517Y735500D01*
G01Y734500D02*
Y737833D01*
G01X940700Y734500D02*
Y739500D01*
G01X946300Y734500D02*
Y739500D01*
G01X956000Y732833D02*
Y737833D01*
G01Y737083D02*
X956417Y737500D01*
X956833Y737750D01*
X957500Y737833D01*
X958083Y737750D01*
X958667Y737333D01*
X958917Y736750D01*
X959000Y736167D01*
X958917Y735583D01*
X958667Y735000D01*
X958167Y734667D01*
X957500Y734500D01*
X956917Y734583D01*
X956333Y734833D01*
X956000Y735167D01*
G01X963100Y734500D02*
Y739500D01*
G01X967283Y737833D02*
Y735500D01*
X967617Y734917D01*
X968117Y734583D01*
X968700Y734500D01*
X969283Y734583D01*
X969783Y734917D01*
X970117Y735500D01*
G01Y734500D02*
Y737833D01*
G01X973133Y733250D02*
X973717Y732917D01*
X974383Y732833D01*
X974967Y732917D01*
X975467Y733333D01*
X975800Y733917D01*
Y737833D01*
G01Y737167D02*
X975467Y737500D01*
X974967Y737750D01*
X974383Y737833D01*
X973717Y737667D01*
X973300Y737333D01*
X972967Y736750D01*
X972800Y736167D01*
X972883Y735667D01*
X973217Y735083D01*
X973717Y734667D01*
X974383Y734500D01*
X974883Y734583D01*
X975467Y734917D01*
X975800Y735250D01*
G01X978733Y733250D02*
X979317Y732917D01*
X979983Y732833D01*
X980567Y732917D01*
X981067Y733333D01*
X981400Y733917D01*
Y737833D01*
G01Y737167D02*
X981067Y737500D01*
X980567Y737750D01*
X979983Y737833D01*
X979317Y737667D01*
X978900Y737333D01*
X978567Y736750D01*
X978400Y736167D01*
X978483Y735667D01*
X978817Y735083D01*
X979317Y734667D01*
X979983Y734500D01*
X980483Y734583D01*
X981067Y734917D01*
X981400Y735250D01*
G01X985500Y737833D02*
Y734500D01*
G01Y739167D02*
X985333Y739250D01*
Y739417D01*
X985500Y739500D01*
X985667Y739417D01*
Y739250D01*
X985500Y739167D01*
G01X989683Y734500D02*
Y737833D01*
G01Y737000D02*
X990017Y737417D01*
X990517Y737750D01*
X991183Y737833D01*
X991767Y737750D01*
X992267Y737417D01*
X992517Y736833D01*
Y734500D01*
G01X995533Y733250D02*
X996117Y732917D01*
X996783Y732833D01*
X997367Y732917D01*
X997867Y733333D01*
X998200Y733917D01*
Y737833D01*
G01Y737167D02*
X997867Y737500D01*
X997367Y737750D01*
X996783Y737833D01*
X996117Y737667D01*
X995700Y737333D01*
X995367Y736750D01*
X995200Y736167D01*
X995283Y735667D01*
X995617Y735083D01*
X996117Y734667D01*
X996783Y734500D01*
X997283Y734583D01*
X997867Y734917D01*
X998200Y735250D01*
G01X948000Y850610D02*
Y782110D01*
G01X995667Y5500D02*
Y10500D01*
X997333D01*
X998000Y10250D01*
X998500Y9917D01*
X998917Y9417D01*
X999250Y8833D01*
X999333Y8000D01*
X999250Y7167D01*
X998917Y6583D01*
X998500Y6083D01*
X998000Y5750D01*
X997333Y5500D01*
X995667D01*
G01X1003100D02*
Y10500D01*
X1002100Y9500D01*
G01Y5500D02*
X1004100D01*
G01X1007117Y7583D02*
X1007700Y8167D01*
X1008200Y8500D01*
X1008867Y8667D01*
X1009450Y8500D01*
X1009867Y8167D01*
X1010200Y7667D01*
X1010283Y7083D01*
X1010200Y6583D01*
X1009867Y6083D01*
X1009367Y5667D01*
X1008783Y5500D01*
X1008117Y5667D01*
X1007533Y6167D01*
X1007200Y6917D01*
X1007117Y7750D01*
X1007283Y8833D01*
X1007533Y9417D01*
X1007950Y10000D01*
X1008533Y10417D01*
X1009117Y10500D01*
X1009700Y10333D01*
X1010117Y9917D01*
G01X1014300Y5333D02*
X1014133Y5417D01*
Y5583D01*
X1014300Y5667D01*
X1014467Y5583D01*
Y5417D01*
X1014300Y5333D01*
G01Y7583D02*
X1014133Y7667D01*
Y7833D01*
X1014300Y7917D01*
X1014467Y7833D01*
Y7667D01*
X1014300Y7583D01*
G01X1018067Y5500D02*
Y10500D01*
X1019733D01*
X1020400Y10250D01*
X1020900Y9917D01*
X1021317Y9417D01*
X1021650Y8833D01*
X1021733Y8000D01*
X1021650Y7167D01*
X1021317Y6583D01*
X1020900Y6083D01*
X1020400Y5750D01*
X1019733Y5500D01*
X1018067D01*
G01X1025500Y8833D02*
Y5500D01*
G01Y10167D02*
X1025333Y10250D01*
Y10417D01*
X1025500Y10500D01*
X1025667Y10417D01*
Y10250D01*
X1025500Y10167D01*
G01X1032600Y5500D02*
Y8833D01*
G01Y8250D02*
X1032267Y8583D01*
X1031767Y8750D01*
X1031183Y8833D01*
X1030600Y8667D01*
X1030100Y8333D01*
X1029767Y7833D01*
X1029600Y7167D01*
X1029767Y6500D01*
X1030100Y6000D01*
X1030600Y5667D01*
X1031183Y5500D01*
X1031767Y5583D01*
X1032267Y5833D01*
X1032600Y6167D01*
G01X1034200Y5500D02*
Y8833D01*
G01Y7917D02*
X1034450Y8333D01*
X1034867Y8667D01*
X1035450Y8833D01*
X1036033Y8667D01*
X1036450Y8333D01*
X1036700Y7917D01*
Y5500D01*
G01Y7917D02*
X1036950Y8333D01*
X1037367Y8667D01*
X1037950Y8833D01*
X1038533Y8667D01*
X1038950Y8333D01*
X1039200Y7833D01*
Y5500D01*
G01X1041050Y7750D02*
X1043717D01*
X1043467Y8333D01*
X1043050Y8667D01*
X1042467Y8833D01*
X1041883Y8750D01*
X1041383Y8500D01*
X1041050Y7917D01*
X1040883Y7417D01*
Y6917D01*
X1041050Y6417D01*
X1041467Y5917D01*
X1041967Y5583D01*
X1042550Y5500D01*
X1043133Y5667D01*
X1043717Y6167D01*
G01X1047900Y10500D02*
Y5500D01*
G01X1046733Y8833D02*
X1049067D01*
G01X1052250Y7750D02*
X1054917D01*
X1054667Y8333D01*
X1054250Y8667D01*
X1053667Y8833D01*
X1053083Y8750D01*
X1052583Y8500D01*
X1052250Y7917D01*
X1052083Y7417D01*
Y6917D01*
X1052250Y6417D01*
X1052667Y5917D01*
X1053167Y5583D01*
X1053750Y5500D01*
X1054333Y5667D01*
X1054917Y6167D01*
G01X1057933Y5500D02*
Y8833D01*
G01Y8167D02*
X1058350Y8500D01*
X1058767Y8750D01*
X1059350Y8833D01*
X1059767Y8750D01*
X1060267Y8500D01*
G01X1070300Y5500D02*
Y10500D01*
X1069300Y9500D01*
G01Y5500D02*
X1071300D01*
G01X1074317Y7583D02*
X1074900Y8167D01*
X1075400Y8500D01*
X1076067Y8667D01*
X1076650Y8500D01*
X1077067Y8167D01*
X1077400Y7667D01*
X1077483Y7083D01*
X1077400Y6583D01*
X1077067Y6083D01*
X1076567Y5667D01*
X1075983Y5500D01*
X1075317Y5667D01*
X1074733Y6167D01*
X1074400Y6917D01*
X1074317Y7750D01*
X1074483Y8833D01*
X1074733Y9417D01*
X1075150Y10000D01*
X1075733Y10417D01*
X1076317Y10500D01*
X1076900Y10333D01*
X1077317Y9917D01*
G01X1079000Y5500D02*
Y8833D01*
G01Y7917D02*
X1079250Y8333D01*
X1079667Y8667D01*
X1080250Y8833D01*
X1080833Y8667D01*
X1081250Y8333D01*
X1081500Y7917D01*
Y5500D01*
G01Y7917D02*
X1081750Y8333D01*
X1082167Y8667D01*
X1082750Y8833D01*
X1083333Y8667D01*
X1083750Y8333D01*
X1084000Y7833D01*
Y5500D01*
G01X1087100Y8833D02*
Y5500D01*
G01Y10167D02*
X1086933Y10250D01*
Y10417D01*
X1087100Y10500D01*
X1087267Y10417D01*
Y10250D01*
X1087100Y10167D01*
G01X1092700Y5500D02*
Y10500D01*
G01X980667Y16500D02*
X977333D01*
Y21500D01*
X980667D01*
G01X979333Y19083D02*
X977333D01*
G01X983350Y19833D02*
X985850Y16500D01*
G01Y19833D02*
X983350Y16500D01*
G01X990200Y16333D02*
X990033Y16417D01*
Y16583D01*
X990200Y16667D01*
X990367Y16583D01*
Y16417D01*
X990200Y16333D01*
G01X994050Y16500D02*
Y21500D01*
G01X997550D02*
Y16500D01*
G01Y19000D02*
X994050D01*
G01X999733Y16500D02*
Y21500D01*
X1001817D01*
X1002483Y21250D01*
X1002900Y20917D01*
X1003067Y20250D01*
X1002900Y19583D01*
X1002400Y19167D01*
X1001817Y18917D01*
X999733D01*
G01X1001817D02*
X1003067Y16500D01*
G01X1008667D02*
X1005333D01*
Y21500D01*
X1008667D01*
G01X1007333Y19083D02*
X1005333D01*
G01X1013600Y16500D02*
Y21500D01*
X1010517Y17917D01*
X1014683D01*
G01X1016367Y17250D02*
X1016867Y16833D01*
X1017450Y16583D01*
X1018200Y16500D01*
X1018950Y16667D01*
X1019533Y17000D01*
X1019950Y17583D01*
X1020033Y18250D01*
X1019867Y18917D01*
X1019450Y19333D01*
X1018867Y19667D01*
X1018283Y19750D01*
X1017700Y19667D01*
X1016950Y19333D01*
X1017200Y21500D01*
X1019450D01*
G01X1022050Y16500D02*
X1025550Y21500D01*
G01X1022050D02*
X1025550Y16500D01*
G01X1027983Y17083D02*
X1028567Y16667D01*
X1029233Y16500D01*
X1029900Y16667D01*
X1030483Y17167D01*
X1030900Y17917D01*
X1031067Y18667D01*
Y19583D01*
X1030900Y20333D01*
X1030483Y21000D01*
X1029983Y21333D01*
X1029400Y21500D01*
X1028733Y21333D01*
X1028233Y21000D01*
X1027900Y20500D01*
X1027733Y19833D01*
X1027900Y19250D01*
X1028317Y18667D01*
X1028817Y18333D01*
X1029400Y18250D01*
X1030067Y18417D01*
X1030567Y18833D01*
X1031067Y19583D01*
G01X1033417Y18583D02*
X1034000Y19167D01*
X1034500Y19500D01*
X1035167Y19667D01*
X1035750Y19500D01*
X1036167Y19167D01*
X1036500Y18667D01*
X1036583Y18083D01*
X1036500Y17583D01*
X1036167Y17083D01*
X1035667Y16667D01*
X1035083Y16500D01*
X1034417Y16667D01*
X1033833Y17167D01*
X1033500Y17917D01*
X1033417Y18750D01*
X1033583Y19833D01*
X1033833Y20417D01*
X1034250Y21000D01*
X1034833Y21417D01*
X1035417Y21500D01*
X1036000Y21333D01*
X1036417Y20917D01*
G01X1040183Y14833D02*
X1039350Y15667D01*
X1038933Y16500D01*
Y19833D01*
X1039350Y20667D01*
X1040183Y21500D01*
G01X1044367Y16500D02*
Y21500D01*
X1046033D01*
X1046700Y21250D01*
X1047200Y20917D01*
X1047617Y20417D01*
X1047950Y19833D01*
X1048033Y19000D01*
X1047950Y18167D01*
X1047617Y17583D01*
X1047200Y17083D01*
X1046700Y16750D01*
X1046033Y16500D01*
X1044367D01*
G01X1051800D02*
Y21500D01*
X1050800Y20500D01*
G01Y16500D02*
X1052800D01*
G01X1055817Y18583D02*
X1056400Y19167D01*
X1056900Y19500D01*
X1057567Y19667D01*
X1058150Y19500D01*
X1058567Y19167D01*
X1058900Y18667D01*
X1058983Y18083D01*
X1058900Y17583D01*
X1058567Y17083D01*
X1058067Y16667D01*
X1057483Y16500D01*
X1056817Y16667D01*
X1056233Y17167D01*
X1055900Y17917D01*
X1055817Y18750D01*
X1055983Y19833D01*
X1056233Y20417D01*
X1056650Y21000D01*
X1057233Y21417D01*
X1057817Y21500D01*
X1058400Y21333D01*
X1058817Y20917D01*
G01X1061250Y16500D02*
X1064750Y21500D01*
G01X1061250D02*
X1064750Y16500D01*
G01X1069600D02*
Y21500D01*
X1066517Y17917D01*
X1070683D01*
G01X1074617Y14833D02*
X1075450Y15667D01*
X1075867Y16500D01*
Y19833D01*
X1075450Y20667D01*
X1074617Y21500D01*
G01X977333Y65500D02*
Y70500D01*
X979417D01*
X980083Y70250D01*
X980500Y69917D01*
X980667Y69250D01*
X980500Y68583D01*
X980000Y68167D01*
X979417Y67917D01*
X977333D01*
G01X979417D02*
X980667Y65500D01*
G01X986267D02*
X982933D01*
Y70500D01*
X986267D01*
G01X984933Y68083D02*
X982933D01*
G01X992033Y70083D02*
X991533Y70333D01*
X990950Y70500D01*
X990283D01*
X989533Y70250D01*
X988950Y69833D01*
X988533Y69333D01*
X988200Y68500D01*
X988117Y67750D01*
X988283Y67000D01*
X988533Y66500D01*
X989033Y66000D01*
X989617Y65667D01*
X990200Y65500D01*
X990783D01*
X991367Y65667D01*
X991867Y65917D01*
X992283Y66250D01*
G01X995800Y70500D02*
Y65500D01*
G01X993883Y70500D02*
X997717D01*
G01X999317Y65500D02*
X1001400Y70500D01*
X1003483Y65500D01*
G01X1002733Y67250D02*
X1000067D01*
G01X1005083Y65500D02*
Y70500D01*
X1008917Y65500D01*
Y70500D01*
G01X1013100Y68000D02*
X1014767D01*
Y66500D01*
X1014267Y66000D01*
X1013683Y65667D01*
X1012850Y65500D01*
X1012017Y65667D01*
X1011433Y66000D01*
X1010933Y66500D01*
X1010600Y67083D01*
X1010433Y67750D01*
Y68333D01*
X1010600Y68833D01*
X1010933Y69417D01*
X1011433Y69917D01*
X1011933Y70250D01*
X1012600Y70500D01*
X1013183D01*
X1013850Y70333D01*
X1014350Y70000D01*
G01X1016533Y70500D02*
Y65500D01*
X1019867D01*
G01X1025467D02*
X1022133D01*
Y70500D01*
X1025467D01*
G01X1024133Y68083D02*
X1022133D01*
G01X1033167Y65500D02*
Y70500D01*
X1034833D01*
X1035500Y70250D01*
X1036000Y69917D01*
X1036417Y69417D01*
X1036750Y68833D01*
X1036833Y68000D01*
X1036750Y67167D01*
X1036417Y66583D01*
X1036000Y66083D01*
X1035500Y65750D01*
X1034833Y65500D01*
X1033167D01*
G01X1038933D02*
Y70500D01*
X1041017D01*
X1041683Y70250D01*
X1042100Y69917D01*
X1042267Y69250D01*
X1042100Y68583D01*
X1041600Y68167D01*
X1041017Y67917D01*
X1038933D01*
G01X1041017D02*
X1042267Y65500D01*
G01X1045200Y70500D02*
X1047200D01*
G01X1046200D02*
Y65500D01*
G01X1045200D02*
X1047200D01*
G01X1050133Y70500D02*
Y65500D01*
X1053467D01*
G01X1055733Y70500D02*
Y65500D01*
X1059067D01*
G01X1066850D02*
Y70500D01*
G01X1070350D02*
Y65500D01*
G01Y68000D02*
X1066850D01*
G01X1074200Y65500D02*
X1073533Y65583D01*
X1072950Y65917D01*
X1072450Y66417D01*
X1072117Y67000D01*
X1071950Y67667D01*
Y68333D01*
X1072117Y69000D01*
X1072450Y69583D01*
X1072950Y70083D01*
X1073533Y70417D01*
X1074200Y70500D01*
X1074867Y70417D01*
X1075450Y70083D01*
X1075950Y69583D01*
X1076283Y69000D01*
X1076450Y68333D01*
Y67667D01*
X1076283Y67000D01*
X1075950Y66417D01*
X1075450Y65917D01*
X1074867Y65583D01*
X1074200Y65500D01*
G01X1078133Y70500D02*
Y65500D01*
X1081467D01*
G01X1087067D02*
X1083733D01*
Y70500D01*
X1087067D01*
G01X1085733Y68083D02*
X1083733D01*
G01X1094767Y65500D02*
Y70500D01*
X1096433D01*
X1097100Y70250D01*
X1097600Y69917D01*
X1098017Y69417D01*
X1098350Y68833D01*
X1098433Y68000D01*
X1098350Y67167D01*
X1098017Y66583D01*
X1097600Y66083D01*
X1097100Y65750D01*
X1096433Y65500D01*
X1094767D01*
G01X1103867D02*
X1100533D01*
Y70500D01*
X1103867D01*
G01X1102533Y68083D02*
X1100533D01*
G01X1106217Y65500D02*
Y70500D01*
X1109383D01*
G01X1108217Y68083D02*
X1106217D01*
G01X1112400Y70500D02*
X1114400D01*
G01X1113400D02*
Y65500D01*
G01X1112400D02*
X1114400D01*
G01X1117083D02*
Y70500D01*
X1120917Y65500D01*
Y70500D01*
G01X1126267Y65500D02*
X1122933D01*
Y70500D01*
X1126267D01*
G01X1124933Y68083D02*
X1122933D01*
G01X956000Y795980D02*
Y790980D01*
G01X954083Y795980D02*
X957917D01*
G01X959517Y794313D02*
X960517Y790980D01*
X961600Y794313D01*
X962683Y790980D01*
X963683Y794313D01*
G01X967200D02*
Y790980D01*
G01Y795647D02*
X967033Y795730D01*
Y795897D01*
X967200Y795980D01*
X967367Y795897D01*
Y795730D01*
X967200Y795647D01*
G01X971550Y791563D02*
X971967Y791230D01*
X972550Y790980D01*
X973050D01*
X973550Y791147D01*
X973883Y791397D01*
X974050Y791730D01*
X973967Y792230D01*
X973633Y792480D01*
X972133Y792980D01*
X971800Y793563D01*
X971967Y793980D01*
X972300Y794230D01*
X972800Y794313D01*
X973300Y794230D01*
X973800Y793980D01*
G01X978400Y795980D02*
Y790980D01*
G01X977233Y794313D02*
X979567D01*
G01X991100Y790980D02*
Y794313D01*
G01Y793730D02*
X990767Y794063D01*
X990267Y794230D01*
X989683Y794313D01*
X989100Y794147D01*
X988600Y793813D01*
X988267Y793313D01*
X988100Y792647D01*
X988267Y791980D01*
X988600Y791480D01*
X989100Y791147D01*
X989683Y790980D01*
X990267Y791063D01*
X990767Y791313D01*
X991100Y791647D01*
G01X993783Y790980D02*
Y794313D01*
G01Y793480D02*
X994117Y793897D01*
X994617Y794230D01*
X995283Y794313D01*
X995867Y794230D01*
X996367Y793897D01*
X996617Y793313D01*
Y790980D01*
G01X1002300Y795980D02*
Y790980D01*
G01Y791730D02*
X1001967Y791313D01*
X1001467Y791063D01*
X1000883Y790980D01*
X1000217Y791147D01*
X999717Y791563D01*
X999383Y792063D01*
X999300Y792647D01*
X999383Y793230D01*
X999717Y793730D01*
X1000217Y794147D01*
X1000883Y794313D01*
X1001467Y794230D01*
X1001883Y794063D01*
X1002300Y793730D01*
G01X1010500Y790980D02*
Y795980D01*
G01Y793480D02*
X1010917Y793980D01*
X1011417Y794230D01*
X1011917Y794313D01*
X1012667Y794147D01*
X1013167Y793813D01*
X1013500Y793230D01*
Y792563D01*
X1013333Y791897D01*
X1013000Y791397D01*
X1012417Y791063D01*
X1011917Y790980D01*
X1011417Y791063D01*
X1010917Y791313D01*
X1010500Y791730D01*
G01X1017600Y790980D02*
X1017100Y791063D01*
X1016600Y791397D01*
X1016267Y791980D01*
X1016100Y792647D01*
X1016267Y793313D01*
X1016600Y793897D01*
X1017100Y794230D01*
X1017600Y794313D01*
X1018100Y794230D01*
X1018600Y793897D01*
X1018933Y793313D01*
X1019017Y792647D01*
X1018933Y791980D01*
X1018600Y791397D01*
X1018100Y791063D01*
X1017600Y790980D01*
G01X1021117Y794313D02*
X1022117Y790980D01*
X1023200Y794313D01*
X1024283Y790980D01*
X1025283Y794313D01*
G01X957500Y811500D02*
X959167D01*
Y810000D01*
X958667Y809500D01*
X958083Y809167D01*
X957250Y809000D01*
X956417Y809167D01*
X955833Y809500D01*
X955333Y810000D01*
X955000Y810583D01*
X954833Y811250D01*
Y811833D01*
X955000Y812333D01*
X955333Y812917D01*
X955833Y813417D01*
X956333Y813750D01*
X957000Y814000D01*
X957583D01*
X958250Y813833D01*
X958750Y813500D01*
G01X961100Y808833D02*
X964100Y814000D01*
G01X966617Y809000D02*
Y814000D01*
X969783D01*
G01X968617Y811583D02*
X966617D01*
G01X977650Y809667D02*
X978317Y809250D01*
X979067Y809000D01*
X979733D01*
X980400Y809250D01*
X980900Y809667D01*
X981150Y810250D01*
X980983Y810833D01*
X980567Y811333D01*
X979817Y811667D01*
X978817Y811833D01*
X978233Y812167D01*
X977983Y812750D01*
X978150Y813333D01*
X978567Y813750D01*
X979150Y814000D01*
X979733D01*
X980317Y813833D01*
X980817Y813417D01*
G01X985000Y809000D02*
Y814000D01*
G01X990600Y809000D02*
X990100Y809083D01*
X989600Y809417D01*
X989267Y810000D01*
X989100Y810667D01*
X989267Y811333D01*
X989600Y811917D01*
X990100Y812250D01*
X990600Y812333D01*
X991100Y812250D01*
X991600Y811917D01*
X991933Y811333D01*
X992017Y810667D01*
X991933Y810000D01*
X991600Y809417D01*
X991100Y809083D01*
X990600Y809000D01*
G01X996200Y814000D02*
Y809000D01*
G01X995033Y812333D02*
X997367D01*
G01X955750Y826250D02*
X958417D01*
X958167Y826833D01*
X957750Y827167D01*
X957167Y827333D01*
X956583Y827250D01*
X956083Y827000D01*
X955750Y826417D01*
X955583Y825917D01*
Y825417D01*
X955750Y824917D01*
X956167Y824417D01*
X956667Y824083D01*
X957250Y824000D01*
X957833Y824167D01*
X958417Y824667D01*
G01X964100Y829000D02*
Y824000D01*
G01Y824750D02*
X963767Y824333D01*
X963267Y824083D01*
X962683Y824000D01*
X962017Y824167D01*
X961517Y824583D01*
X961183Y825083D01*
X961100Y825667D01*
X961183Y826250D01*
X961517Y826750D01*
X962017Y827167D01*
X962683Y827333D01*
X963267Y827250D01*
X963683Y827083D01*
X964100Y826750D01*
G01X967033Y822750D02*
X967617Y822417D01*
X968283Y822333D01*
X968867Y822417D01*
X969367Y822833D01*
X969700Y823417D01*
Y827333D01*
G01Y826667D02*
X969367Y827000D01*
X968867Y827250D01*
X968283Y827333D01*
X967617Y827167D01*
X967200Y826833D01*
X966867Y826250D01*
X966700Y825667D01*
X966783Y825167D01*
X967117Y824583D01*
X967617Y824167D01*
X968283Y824000D01*
X968783Y824083D01*
X969367Y824417D01*
X969700Y824750D01*
G01X972550Y826250D02*
X975217D01*
X974967Y826833D01*
X974550Y827167D01*
X973967Y827333D01*
X973383Y827250D01*
X972883Y827000D01*
X972550Y826417D01*
X972383Y825917D01*
Y825417D01*
X972550Y824917D01*
X972967Y824417D01*
X973467Y824083D01*
X974050Y824000D01*
X974633Y824167D01*
X975217Y824667D01*
G01X985000Y829000D02*
Y824000D01*
G01X983833Y827333D02*
X986167D01*
G01X990600Y824000D02*
X990100Y824083D01*
X989600Y824417D01*
X989267Y825000D01*
X989100Y825667D01*
X989267Y826333D01*
X989600Y826917D01*
X990100Y827250D01*
X990600Y827333D01*
X991100Y827250D01*
X991600Y826917D01*
X991933Y826333D01*
X992017Y825667D01*
X991933Y825000D01*
X991600Y824417D01*
X991100Y824083D01*
X990600Y824000D01*
G01X1000383D02*
Y829000D01*
G01Y826583D02*
X1000800Y827000D01*
X1001217Y827250D01*
X1001883Y827333D01*
X1002383Y827250D01*
X1002967Y826917D01*
X1003217Y826417D01*
Y824000D01*
G01X1007400D02*
X1006900Y824083D01*
X1006400Y824417D01*
X1006067Y825000D01*
X1005900Y825667D01*
X1006067Y826333D01*
X1006400Y826917D01*
X1006900Y827250D01*
X1007400Y827333D01*
X1007900Y827250D01*
X1008400Y826917D01*
X1008733Y826333D01*
X1008817Y825667D01*
X1008733Y825000D01*
X1008400Y824417D01*
X1007900Y824083D01*
X1007400Y824000D01*
G01X1013000D02*
Y829000D01*
G01X1017350Y826250D02*
X1020017D01*
X1019767Y826833D01*
X1019350Y827167D01*
X1018767Y827333D01*
X1018183Y827250D01*
X1017683Y827000D01*
X1017350Y826417D01*
X1017183Y825917D01*
Y825417D01*
X1017350Y824917D01*
X1017767Y824417D01*
X1018267Y824083D01*
X1018850Y824000D01*
X1019433Y824167D01*
X1020017Y824667D01*
G01X948500Y819500D02*
X1343000D01*
G01X948500Y834500D02*
X1343000D01*
G01X955750Y842750D02*
X958417D01*
X958167Y843333D01*
X957750Y843667D01*
X957167Y843833D01*
X956583Y843750D01*
X956083Y843500D01*
X955750Y842917D01*
X955583Y842417D01*
Y841917D01*
X955750Y841417D01*
X956167Y840917D01*
X956667Y840583D01*
X957250Y840500D01*
X957833Y840667D01*
X958417Y841167D01*
G01X964100Y845500D02*
Y840500D01*
G01Y841250D02*
X963767Y840833D01*
X963267Y840583D01*
X962683Y840500D01*
X962017Y840667D01*
X961517Y841083D01*
X961183Y841583D01*
X961100Y842167D01*
X961183Y842750D01*
X961517Y843250D01*
X962017Y843667D01*
X962683Y843833D01*
X963267Y843750D01*
X963683Y843583D01*
X964100Y843250D01*
G01X967033Y839250D02*
X967617Y838917D01*
X968283Y838833D01*
X968867Y838917D01*
X969367Y839333D01*
X969700Y839917D01*
Y843833D01*
G01Y843167D02*
X969367Y843500D01*
X968867Y843750D01*
X968283Y843833D01*
X967617Y843667D01*
X967200Y843333D01*
X966867Y842750D01*
X966700Y842167D01*
X966783Y841667D01*
X967117Y841083D01*
X967617Y840667D01*
X968283Y840500D01*
X968783Y840583D01*
X969367Y840917D01*
X969700Y841250D01*
G01X972550Y842750D02*
X975217D01*
X974967Y843333D01*
X974550Y843667D01*
X973967Y843833D01*
X973383Y843750D01*
X972883Y843500D01*
X972550Y842917D01*
X972383Y842417D01*
Y841917D01*
X972550Y841417D01*
X972967Y840917D01*
X973467Y840583D01*
X974050Y840500D01*
X974633Y840667D01*
X975217Y841167D01*
G01X985000Y845500D02*
Y840500D01*
G01X983833Y843833D02*
X986167D01*
G01X990600Y840500D02*
X990100Y840583D01*
X989600Y840917D01*
X989267Y841500D01*
X989100Y842167D01*
X989267Y842833D01*
X989600Y843417D01*
X990100Y843750D01*
X990600Y843833D01*
X991100Y843750D01*
X991600Y843417D01*
X991933Y842833D01*
X992017Y842167D01*
X991933Y841500D01*
X991600Y840917D01*
X991100Y840583D01*
X990600Y840500D01*
G01X1000550Y842750D02*
X1003217D01*
X1002967Y843333D01*
X1002550Y843667D01*
X1001967Y843833D01*
X1001383Y843750D01*
X1000883Y843500D01*
X1000550Y842917D01*
X1000383Y842417D01*
Y841917D01*
X1000550Y841417D01*
X1000967Y840917D01*
X1001467Y840583D01*
X1002050Y840500D01*
X1002633Y840667D01*
X1003217Y841167D01*
G01X1008900Y845500D02*
Y840500D01*
G01Y841250D02*
X1008567Y840833D01*
X1008067Y840583D01*
X1007483Y840500D01*
X1006817Y840667D01*
X1006317Y841083D01*
X1005983Y841583D01*
X1005900Y842167D01*
X1005983Y842750D01*
X1006317Y843250D01*
X1006817Y843667D01*
X1007483Y843833D01*
X1008067Y843750D01*
X1008483Y843583D01*
X1008900Y843250D01*
G01X1011833Y839250D02*
X1012417Y838917D01*
X1013083Y838833D01*
X1013667Y838917D01*
X1014167Y839333D01*
X1014500Y839917D01*
Y843833D01*
G01Y843167D02*
X1014167Y843500D01*
X1013667Y843750D01*
X1013083Y843833D01*
X1012417Y843667D01*
X1012000Y843333D01*
X1011667Y842750D01*
X1011500Y842167D01*
X1011583Y841667D01*
X1011917Y841083D01*
X1012417Y840667D01*
X1013083Y840500D01*
X1013583Y840583D01*
X1014167Y840917D01*
X1014500Y841250D01*
G01X1017350Y842750D02*
X1020017D01*
X1019767Y843333D01*
X1019350Y843667D01*
X1018767Y843833D01*
X1018183Y843750D01*
X1017683Y843500D01*
X1017350Y842917D01*
X1017183Y842417D01*
Y841917D01*
X1017350Y841417D01*
X1017767Y840917D01*
X1018267Y840583D01*
X1018850Y840500D01*
X1019433Y840667D01*
X1020017Y841167D01*
G01X1026000Y336000D02*
Y86000D01*
G01X1033500Y370500D02*
Y375500D01*
G01Y373000D02*
X1033917Y373500D01*
X1034417Y373750D01*
X1034917Y373833D01*
X1035667Y373667D01*
X1036167Y373333D01*
X1036500Y372750D01*
Y372083D01*
X1036333Y371417D01*
X1036000Y370917D01*
X1035417Y370583D01*
X1034917Y370500D01*
X1034417Y370583D01*
X1033917Y370833D01*
X1033500Y371250D01*
G01X1039183Y373833D02*
Y371500D01*
X1039517Y370917D01*
X1040017Y370583D01*
X1040600Y370500D01*
X1041183Y370583D01*
X1041683Y370917D01*
X1042017Y371500D01*
G01Y370500D02*
Y373833D01*
G01X1044700Y370500D02*
Y375500D01*
G01Y373000D02*
X1045117Y373500D01*
X1045617Y373750D01*
X1046117Y373833D01*
X1046867Y373667D01*
X1047367Y373333D01*
X1047700Y372750D01*
Y372083D01*
X1047533Y371417D01*
X1047200Y370917D01*
X1046617Y370583D01*
X1046117Y370500D01*
X1045617Y370583D01*
X1045117Y370833D01*
X1044700Y371250D01*
G01X1050300Y370500D02*
Y375500D01*
G01Y373000D02*
X1050717Y373500D01*
X1051217Y373750D01*
X1051717Y373833D01*
X1052467Y373667D01*
X1052967Y373333D01*
X1053300Y372750D01*
Y372083D01*
X1053133Y371417D01*
X1052800Y370917D01*
X1052217Y370583D01*
X1051717Y370500D01*
X1051217Y370583D01*
X1050717Y370833D01*
X1050300Y371250D01*
G01X1057400Y370500D02*
Y375500D01*
G01X1061750Y372750D02*
X1064417D01*
X1064167Y373333D01*
X1063750Y373667D01*
X1063167Y373833D01*
X1062583Y373750D01*
X1062083Y373500D01*
X1061750Y372917D01*
X1061583Y372417D01*
Y371917D01*
X1061750Y371417D01*
X1062167Y370917D01*
X1062667Y370583D01*
X1063250Y370500D01*
X1063833Y370667D01*
X1064417Y371167D01*
G01X1074200Y373833D02*
Y370500D01*
G01Y375167D02*
X1074033Y375250D01*
Y375417D01*
X1074200Y375500D01*
X1074367Y375417D01*
Y375250D01*
X1074200Y375167D01*
G01X1078383Y370500D02*
Y373833D01*
G01Y373000D02*
X1078717Y373417D01*
X1079217Y373750D01*
X1079883Y373833D01*
X1080467Y373750D01*
X1080967Y373417D01*
X1081217Y372833D01*
Y370500D01*
G01X1084150Y371083D02*
X1084567Y370750D01*
X1085150Y370500D01*
X1085650D01*
X1086150Y370667D01*
X1086483Y370917D01*
X1086650Y371250D01*
X1086567Y371750D01*
X1086233Y372000D01*
X1084733Y372500D01*
X1084400Y373083D01*
X1084567Y373500D01*
X1084900Y373750D01*
X1085400Y373833D01*
X1085900Y373750D01*
X1086400Y373500D01*
G01X1091000Y373833D02*
Y370500D01*
G01Y375167D02*
X1090833Y375250D01*
Y375417D01*
X1091000Y375500D01*
X1091167Y375417D01*
Y375250D01*
X1091000Y375167D01*
G01X1098100Y375500D02*
Y370500D01*
G01Y371250D02*
X1097767Y370833D01*
X1097267Y370583D01*
X1096683Y370500D01*
X1096017Y370667D01*
X1095517Y371083D01*
X1095183Y371583D01*
X1095100Y372167D01*
X1095183Y372750D01*
X1095517Y373250D01*
X1096017Y373667D01*
X1096683Y373833D01*
X1097267Y373750D01*
X1097683Y373583D01*
X1098100Y373250D01*
G01X1100950Y372750D02*
X1103617D01*
X1103367Y373333D01*
X1102950Y373667D01*
X1102367Y373833D01*
X1101783Y373750D01*
X1101283Y373500D01*
X1100950Y372917D01*
X1100783Y372417D01*
Y371917D01*
X1100950Y371417D01*
X1101367Y370917D01*
X1101867Y370583D01*
X1102450Y370500D01*
X1103033Y370667D01*
X1103617Y371167D01*
G01X1113400Y375500D02*
Y370500D01*
G01X1112233Y373833D02*
X1114567D01*
G01X1117583Y370500D02*
Y375500D01*
G01Y373083D02*
X1118000Y373500D01*
X1118417Y373750D01*
X1119083Y373833D01*
X1119583Y373750D01*
X1120167Y373417D01*
X1120417Y372917D01*
Y370500D01*
G01X1123350Y372750D02*
X1126017D01*
X1125767Y373333D01*
X1125350Y373667D01*
X1124767Y373833D01*
X1124183Y373750D01*
X1123683Y373500D01*
X1123350Y372917D01*
X1123183Y372417D01*
Y371917D01*
X1123350Y371417D01*
X1123767Y370917D01*
X1124267Y370583D01*
X1124850Y370500D01*
X1125433Y370667D01*
X1126017Y371167D01*
G01X1134633Y370500D02*
Y373833D01*
G01Y373167D02*
X1135050Y373500D01*
X1135467Y373750D01*
X1136050Y373833D01*
X1136467Y373750D01*
X1136967Y373500D01*
G01X1140150Y372750D02*
X1142817D01*
X1142567Y373333D01*
X1142150Y373667D01*
X1141567Y373833D01*
X1140983Y373750D01*
X1140483Y373500D01*
X1140150Y372917D01*
X1139983Y372417D01*
Y371917D01*
X1140150Y371417D01*
X1140567Y370917D01*
X1141067Y370583D01*
X1141650Y370500D01*
X1142233Y370667D01*
X1142817Y371167D01*
G01X1145750Y371083D02*
X1146167Y370750D01*
X1146750Y370500D01*
X1147250D01*
X1147750Y370667D01*
X1148083Y370917D01*
X1148250Y371250D01*
X1148167Y371750D01*
X1147833Y372000D01*
X1146333Y372500D01*
X1146000Y373083D01*
X1146167Y373500D01*
X1146500Y373750D01*
X1147000Y373833D01*
X1147500Y373750D01*
X1148000Y373500D01*
G01X1152600Y373833D02*
Y370500D01*
G01Y375167D02*
X1152433Y375250D01*
Y375417D01*
X1152600Y375500D01*
X1152767Y375417D01*
Y375250D01*
X1152600Y375167D01*
G01X1156783Y370500D02*
Y373833D01*
G01Y373000D02*
X1157117Y373417D01*
X1157617Y373750D01*
X1158283Y373833D01*
X1158867Y373750D01*
X1159367Y373417D01*
X1159617Y372833D01*
Y370500D01*
G01X1163800Y370333D02*
X1163633Y370417D01*
Y370583D01*
X1163800Y370667D01*
X1163967Y370583D01*
Y370417D01*
X1163800Y370333D01*
G01X1021417Y383667D02*
X1021917Y384167D01*
X1022500Y384417D01*
X1023167Y384500D01*
X1024000Y384333D01*
X1024583Y383917D01*
X1024750Y383417D01*
X1024667Y382917D01*
X1024333Y382500D01*
X1022667Y381667D01*
X1021917Y381083D01*
X1021417Y380250D01*
X1021250Y379500D01*
X1024750D01*
G01X1028600Y379333D02*
X1028433Y379417D01*
Y379583D01*
X1028600Y379667D01*
X1028767Y379583D01*
Y379417D01*
X1028600Y379333D01*
G01X1032117Y384500D02*
X1034200Y379500D01*
X1036283Y384500D01*
G01X1039800Y382833D02*
Y379500D01*
G01Y384167D02*
X1039633Y384250D01*
Y384417D01*
X1039800Y384500D01*
X1039967Y384417D01*
Y384250D01*
X1039800Y384167D01*
G01X1046900Y379500D02*
Y382833D01*
G01Y382250D02*
X1046567Y382583D01*
X1046067Y382750D01*
X1045483Y382833D01*
X1044900Y382667D01*
X1044400Y382333D01*
X1044067Y381833D01*
X1043900Y381167D01*
X1044067Y380500D01*
X1044400Y380000D01*
X1044900Y379667D01*
X1045483Y379500D01*
X1046067Y379583D01*
X1046567Y379833D01*
X1046900Y380167D01*
G01X1055350Y380083D02*
X1055767Y379750D01*
X1056350Y379500D01*
X1056850D01*
X1057350Y379667D01*
X1057683Y379917D01*
X1057850Y380250D01*
X1057767Y380750D01*
X1057433Y381000D01*
X1055933Y381500D01*
X1055600Y382083D01*
X1055767Y382500D01*
X1056100Y382750D01*
X1056600Y382833D01*
X1057100Y382750D01*
X1057600Y382500D01*
G01X1060783Y379500D02*
Y384500D01*
G01Y382083D02*
X1061200Y382500D01*
X1061617Y382750D01*
X1062283Y382833D01*
X1062783Y382750D01*
X1063367Y382417D01*
X1063617Y381917D01*
Y379500D01*
G01X1067800D02*
X1067300Y379583D01*
X1066800Y379917D01*
X1066467Y380500D01*
X1066300Y381167D01*
X1066467Y381833D01*
X1066800Y382417D01*
X1067300Y382750D01*
X1067800Y382833D01*
X1068300Y382750D01*
X1068800Y382417D01*
X1069133Y381833D01*
X1069217Y381167D01*
X1069133Y380500D01*
X1068800Y379917D01*
X1068300Y379583D01*
X1067800Y379500D01*
G01X1071983Y382833D02*
Y380500D01*
X1072317Y379917D01*
X1072817Y379583D01*
X1073400Y379500D01*
X1073983Y379583D01*
X1074483Y379917D01*
X1074817Y380500D01*
G01Y379500D02*
Y382833D01*
G01X1079000Y379500D02*
Y384500D01*
G01X1086100D02*
Y379500D01*
G01Y380250D02*
X1085767Y379833D01*
X1085267Y379583D01*
X1084683Y379500D01*
X1084017Y379667D01*
X1083517Y380083D01*
X1083183Y380583D01*
X1083100Y381167D01*
X1083183Y381750D01*
X1083517Y382250D01*
X1084017Y382667D01*
X1084683Y382833D01*
X1085267Y382750D01*
X1085683Y382583D01*
X1086100Y382250D01*
G01X1094300Y379500D02*
Y384500D01*
G01Y382000D02*
X1094717Y382500D01*
X1095217Y382750D01*
X1095717Y382833D01*
X1096467Y382667D01*
X1096967Y382333D01*
X1097300Y381750D01*
Y381083D01*
X1097133Y380417D01*
X1096800Y379917D01*
X1096217Y379583D01*
X1095717Y379500D01*
X1095217Y379583D01*
X1094717Y379833D01*
X1094300Y380250D01*
G01X1100150Y381750D02*
X1102817D01*
X1102567Y382333D01*
X1102150Y382667D01*
X1101567Y382833D01*
X1100983Y382750D01*
X1100483Y382500D01*
X1100150Y381917D01*
X1099983Y381417D01*
Y380917D01*
X1100150Y380417D01*
X1100567Y379917D01*
X1101067Y379583D01*
X1101650Y379500D01*
X1102233Y379667D01*
X1102817Y380167D01*
G01X1111100Y377833D02*
Y382833D01*
G01Y382083D02*
X1111517Y382500D01*
X1111933Y382750D01*
X1112600Y382833D01*
X1113183Y382750D01*
X1113767Y382333D01*
X1114017Y381750D01*
X1114100Y381167D01*
X1114017Y380583D01*
X1113767Y380000D01*
X1113267Y379667D01*
X1112600Y379500D01*
X1112017Y379583D01*
X1111433Y379833D01*
X1111100Y380167D01*
G01X1118200Y379500D02*
Y384500D01*
G01X1122383Y382833D02*
Y380500D01*
X1122717Y379917D01*
X1123217Y379583D01*
X1123800Y379500D01*
X1124383Y379583D01*
X1124883Y379917D01*
X1125217Y380500D01*
G01Y379500D02*
Y382833D01*
G01X1128233Y378250D02*
X1128817Y377917D01*
X1129483Y377833D01*
X1130067Y377917D01*
X1130567Y378333D01*
X1130900Y378917D01*
Y382833D01*
G01Y382167D02*
X1130567Y382500D01*
X1130067Y382750D01*
X1129483Y382833D01*
X1128817Y382667D01*
X1128400Y382333D01*
X1128067Y381750D01*
X1127900Y381167D01*
X1127983Y380667D01*
X1128317Y380083D01*
X1128817Y379667D01*
X1129483Y379500D01*
X1129983Y379583D01*
X1130567Y379917D01*
X1130900Y380250D01*
G01X1133833Y378250D02*
X1134417Y377917D01*
X1135083Y377833D01*
X1135667Y377917D01*
X1136167Y378333D01*
X1136500Y378917D01*
Y382833D01*
G01Y382167D02*
X1136167Y382500D01*
X1135667Y382750D01*
X1135083Y382833D01*
X1134417Y382667D01*
X1134000Y382333D01*
X1133667Y381750D01*
X1133500Y381167D01*
X1133583Y380667D01*
X1133917Y380083D01*
X1134417Y379667D01*
X1135083Y379500D01*
X1135583Y379583D01*
X1136167Y379917D01*
X1136500Y380250D01*
G01X1139350Y381750D02*
X1142017D01*
X1141767Y382333D01*
X1141350Y382667D01*
X1140767Y382833D01*
X1140183Y382750D01*
X1139683Y382500D01*
X1139350Y381917D01*
X1139183Y381417D01*
Y380917D01*
X1139350Y380417D01*
X1139767Y379917D01*
X1140267Y379583D01*
X1140850Y379500D01*
X1141433Y379667D01*
X1142017Y380167D01*
G01X1147700Y384500D02*
Y379500D01*
G01Y380250D02*
X1147367Y379833D01*
X1146867Y379583D01*
X1146283Y379500D01*
X1145617Y379667D01*
X1145117Y380083D01*
X1144783Y380583D01*
X1144700Y381167D01*
X1144783Y381750D01*
X1145117Y382250D01*
X1145617Y382667D01*
X1146283Y382833D01*
X1146867Y382750D01*
X1147283Y382583D01*
X1147700Y382250D01*
G01X1155317Y382833D02*
X1156317Y379500D01*
X1157400Y382833D01*
X1158483Y379500D01*
X1159483Y382833D01*
G01X1163000D02*
Y379500D01*
G01Y384167D02*
X1162833Y384250D01*
Y384417D01*
X1163000Y384500D01*
X1163167Y384417D01*
Y384250D01*
X1163000Y384167D01*
G01X1168600Y384500D02*
Y379500D01*
G01X1167433Y382833D02*
X1169767D01*
G01X1172783Y379500D02*
Y384500D01*
G01Y382083D02*
X1173200Y382500D01*
X1173617Y382750D01*
X1174283Y382833D01*
X1174783Y382750D01*
X1175367Y382417D01*
X1175617Y381917D01*
Y379500D01*
G01X1183733D02*
X1187067Y381167D01*
X1183733Y382833D01*
G01X1189583Y380083D02*
X1190167Y379667D01*
X1190833Y379500D01*
X1191500Y379667D01*
X1192083Y380167D01*
X1192500Y380917D01*
X1192667Y381667D01*
Y382583D01*
X1192500Y383333D01*
X1192083Y384000D01*
X1191583Y384333D01*
X1191000Y384500D01*
X1190333Y384333D01*
X1189833Y384000D01*
X1189500Y383500D01*
X1189333Y382833D01*
X1189500Y382250D01*
X1189917Y381667D01*
X1190417Y381333D01*
X1191000Y381250D01*
X1191667Y381417D01*
X1192167Y381833D01*
X1192667Y382583D01*
G01X1196600Y384500D02*
X1195933Y384333D01*
X1195433Y383917D01*
X1195100Y383417D01*
X1194850Y382750D01*
X1194767Y382000D01*
X1194850Y381250D01*
X1195100Y380583D01*
X1195433Y380083D01*
X1195933Y379667D01*
X1196600Y379500D01*
X1197267Y379667D01*
X1197767Y380083D01*
X1198100Y380583D01*
X1198350Y381250D01*
X1198433Y382000D01*
X1198350Y382750D01*
X1198100Y383417D01*
X1197767Y383917D01*
X1197267Y384333D01*
X1196600Y384500D01*
G01X1200700Y379333D02*
X1203700Y384500D01*
G01X1200700D02*
X1200200Y384333D01*
X1199950Y384083D01*
X1199783Y383583D01*
X1199950Y383083D01*
X1200200Y382833D01*
X1200700Y382667D01*
X1201200Y382833D01*
X1201450Y383083D01*
X1201617Y383583D01*
X1201450Y384083D01*
X1201200Y384333D01*
X1200700Y384500D01*
G01X1203700Y381167D02*
X1203200Y381000D01*
X1202950Y380750D01*
X1202783Y380250D01*
X1202950Y379750D01*
X1203200Y379500D01*
X1203700Y379333D01*
X1204200Y379500D01*
X1204450Y379750D01*
X1204617Y380250D01*
X1204450Y380750D01*
X1204200Y381000D01*
X1203700Y381167D01*
G01X1212233Y379500D02*
Y382833D01*
G01Y382167D02*
X1212650Y382500D01*
X1213067Y382750D01*
X1213650Y382833D01*
X1214067Y382750D01*
X1214567Y382500D01*
G01X1217750Y381750D02*
X1220417D01*
X1220167Y382333D01*
X1219750Y382667D01*
X1219167Y382833D01*
X1218583Y382750D01*
X1218083Y382500D01*
X1217750Y381917D01*
X1217583Y381417D01*
Y380917D01*
X1217750Y380417D01*
X1218167Y379917D01*
X1218667Y379583D01*
X1219250Y379500D01*
X1219833Y379667D01*
X1220417Y380167D01*
G01X1223350Y380083D02*
X1223767Y379750D01*
X1224350Y379500D01*
X1224850D01*
X1225350Y379667D01*
X1225683Y379917D01*
X1225850Y380250D01*
X1225767Y380750D01*
X1225433Y381000D01*
X1223933Y381500D01*
X1223600Y382083D01*
X1223767Y382500D01*
X1224100Y382750D01*
X1224600Y382833D01*
X1225100Y382750D01*
X1225600Y382500D01*
G01X1230200Y382833D02*
Y379500D01*
G01Y384167D02*
X1230033Y384250D01*
Y384417D01*
X1230200Y384500D01*
X1230367Y384417D01*
Y384250D01*
X1230200Y384167D01*
G01X1234383Y379500D02*
Y382833D01*
G01Y382000D02*
X1234717Y382417D01*
X1235217Y382750D01*
X1235883Y382833D01*
X1236467Y382750D01*
X1236967Y382417D01*
X1237217Y381833D01*
Y379500D01*
G01X1246417Y378000D02*
X1247583Y379167D01*
Y380333D01*
X1246417D01*
Y379167D01*
X1247583D01*
G01Y381167D02*
Y382333D01*
X1246417D01*
Y381167D01*
X1247583D01*
G01X1250767Y379500D02*
Y384500D01*
X1252433D01*
X1253100Y384250D01*
X1253600Y383917D01*
X1254017Y383417D01*
X1254350Y382833D01*
X1254433Y382000D01*
X1254350Y381167D01*
X1254017Y380583D01*
X1253600Y380083D01*
X1253100Y379750D01*
X1252433Y379500D01*
X1250767D01*
G01X1258200D02*
X1257700Y379583D01*
X1257200Y379917D01*
X1256867Y380500D01*
X1256700Y381167D01*
X1256867Y381833D01*
X1257200Y382417D01*
X1257700Y382750D01*
X1258200Y382833D01*
X1258700Y382750D01*
X1259200Y382417D01*
X1259533Y381833D01*
X1259617Y381167D01*
X1259533Y380500D01*
X1259200Y379917D01*
X1258700Y379583D01*
X1258200Y379500D01*
G01X1267983D02*
Y382833D01*
G01Y382000D02*
X1268317Y382417D01*
X1268817Y382750D01*
X1269483Y382833D01*
X1270067Y382750D01*
X1270567Y382417D01*
X1270817Y381833D01*
Y379500D01*
G01X1275000D02*
X1274500Y379583D01*
X1274000Y379917D01*
X1273667Y380500D01*
X1273500Y381167D01*
X1273667Y381833D01*
X1274000Y382417D01*
X1274500Y382750D01*
X1275000Y382833D01*
X1275500Y382750D01*
X1276000Y382417D01*
X1276333Y381833D01*
X1276417Y381167D01*
X1276333Y380500D01*
X1276000Y379917D01*
X1275500Y379583D01*
X1275000Y379500D01*
G01X1280600Y384500D02*
Y379500D01*
G01X1279433Y382833D02*
X1281767D01*
G01X1293300Y379500D02*
Y382833D01*
G01Y382250D02*
X1292967Y382583D01*
X1292467Y382750D01*
X1291883Y382833D01*
X1291300Y382667D01*
X1290800Y382333D01*
X1290467Y381833D01*
X1290300Y381167D01*
X1290467Y380500D01*
X1290800Y380000D01*
X1291300Y379667D01*
X1291883Y379500D01*
X1292467Y379583D01*
X1292967Y379833D01*
X1293300Y380167D01*
G01X1297400Y379500D02*
Y384500D01*
G01X1303000Y379500D02*
Y384500D01*
G01X1308600Y379500D02*
X1308100Y379583D01*
X1307600Y379917D01*
X1307267Y380500D01*
X1307100Y381167D01*
X1307267Y381833D01*
X1307600Y382417D01*
X1308100Y382750D01*
X1308600Y382833D01*
X1309100Y382750D01*
X1309600Y382417D01*
X1309933Y381833D01*
X1310017Y381167D01*
X1309933Y380500D01*
X1309600Y379917D01*
X1309100Y379583D01*
X1308600Y379500D01*
G01X1312117Y382833D02*
X1313117Y379500D01*
X1314200Y382833D01*
X1315283Y379500D01*
X1316283Y382833D01*
G01X1023000Y390000D02*
Y395000D01*
X1022000Y394000D01*
G01Y390000D02*
X1024000D01*
G01X1028600Y389833D02*
X1028433Y389917D01*
Y390083D01*
X1028600Y390167D01*
X1028767Y390083D01*
Y389917D01*
X1028600Y389833D01*
G01X1032367Y390000D02*
Y395000D01*
X1034033D01*
X1034700Y394750D01*
X1035200Y394417D01*
X1035617Y393917D01*
X1035950Y393333D01*
X1036033Y392500D01*
X1035950Y391667D01*
X1035617Y391083D01*
X1035200Y390583D01*
X1034700Y390250D01*
X1034033Y390000D01*
X1032367D01*
G01X1039800Y393333D02*
Y390000D01*
G01Y394667D02*
X1039633Y394750D01*
Y394917D01*
X1039800Y395000D01*
X1039967Y394917D01*
Y394750D01*
X1039800Y394667D01*
G01X1042900Y390000D02*
Y393333D01*
G01Y392417D02*
X1043150Y392833D01*
X1043567Y393167D01*
X1044150Y393333D01*
X1044733Y393167D01*
X1045150Y392833D01*
X1045400Y392417D01*
Y390000D01*
G01Y392417D02*
X1045650Y392833D01*
X1046067Y393167D01*
X1046650Y393333D01*
X1047233Y393167D01*
X1047650Y392833D01*
X1047900Y392333D01*
Y390000D01*
G01X1049500Y388333D02*
Y393333D01*
G01Y392583D02*
X1049917Y393000D01*
X1050333Y393250D01*
X1051000Y393333D01*
X1051583Y393250D01*
X1052167Y392833D01*
X1052417Y392250D01*
X1052500Y391667D01*
X1052417Y391083D01*
X1052167Y390500D01*
X1051667Y390167D01*
X1051000Y390000D01*
X1050417Y390083D01*
X1049833Y390333D01*
X1049500Y390667D01*
G01X1056600Y390000D02*
Y395000D01*
G01X1060950Y392250D02*
X1063617D01*
X1063367Y392833D01*
X1062950Y393167D01*
X1062367Y393333D01*
X1061783Y393250D01*
X1061283Y393000D01*
X1060950Y392417D01*
X1060783Y391917D01*
Y391417D01*
X1060950Y390917D01*
X1061367Y390417D01*
X1061867Y390083D01*
X1062450Y390000D01*
X1063033Y390167D01*
X1063617Y390667D01*
G01X1075067Y390000D02*
X1071733Y391667D01*
X1075067Y393333D01*
G01X1084600Y390000D02*
Y395000D01*
X1083600Y394000D01*
G01Y390000D02*
X1085600D01*
G01X1093300D02*
Y393333D01*
G01Y392417D02*
X1093550Y392833D01*
X1093967Y393167D01*
X1094550Y393333D01*
X1095133Y393167D01*
X1095550Y392833D01*
X1095800Y392417D01*
Y390000D01*
G01Y392417D02*
X1096050Y392833D01*
X1096467Y393167D01*
X1097050Y393333D01*
X1097633Y393167D01*
X1098050Y392833D01*
X1098300Y392333D01*
Y390000D01*
G01X1101400Y393333D02*
Y390000D01*
G01Y394667D02*
X1101233Y394750D01*
Y394917D01*
X1101400Y395000D01*
X1101567Y394917D01*
Y394750D01*
X1101400Y394667D01*
G01X1107000Y390000D02*
Y395000D01*
G01X1117617Y388500D02*
X1118783Y389667D01*
Y390833D01*
X1117617D01*
Y389667D01*
X1118783D01*
G01Y391667D02*
Y392833D01*
X1117617D01*
Y391667D01*
X1118783D01*
G01X1016000Y604500D02*
Y366000D01*
G01X1033500Y413500D02*
Y418500D01*
G01Y416000D02*
X1033917Y416500D01*
X1034417Y416750D01*
X1034917Y416833D01*
X1035667Y416667D01*
X1036167Y416333D01*
X1036500Y415750D01*
Y415083D01*
X1036333Y414417D01*
X1036000Y413917D01*
X1035417Y413583D01*
X1034917Y413500D01*
X1034417Y413583D01*
X1033917Y413833D01*
X1033500Y414250D01*
G01X1039183Y416833D02*
Y414500D01*
X1039517Y413917D01*
X1040017Y413583D01*
X1040600Y413500D01*
X1041183Y413583D01*
X1041683Y413917D01*
X1042017Y414500D01*
G01Y413500D02*
Y416833D01*
G01X1044700Y413500D02*
Y418500D01*
G01Y416000D02*
X1045117Y416500D01*
X1045617Y416750D01*
X1046117Y416833D01*
X1046867Y416667D01*
X1047367Y416333D01*
X1047700Y415750D01*
Y415083D01*
X1047533Y414417D01*
X1047200Y413917D01*
X1046617Y413583D01*
X1046117Y413500D01*
X1045617Y413583D01*
X1045117Y413833D01*
X1044700Y414250D01*
G01X1050300Y413500D02*
Y418500D01*
G01Y416000D02*
X1050717Y416500D01*
X1051217Y416750D01*
X1051717Y416833D01*
X1052467Y416667D01*
X1052967Y416333D01*
X1053300Y415750D01*
Y415083D01*
X1053133Y414417D01*
X1052800Y413917D01*
X1052217Y413583D01*
X1051717Y413500D01*
X1051217Y413583D01*
X1050717Y413833D01*
X1050300Y414250D01*
G01X1057400Y413500D02*
Y418500D01*
G01X1061750Y415750D02*
X1064417D01*
X1064167Y416333D01*
X1063750Y416667D01*
X1063167Y416833D01*
X1062583Y416750D01*
X1062083Y416500D01*
X1061750Y415917D01*
X1061583Y415417D01*
Y414917D01*
X1061750Y414417D01*
X1062167Y413917D01*
X1062667Y413583D01*
X1063250Y413500D01*
X1063833Y413667D01*
X1064417Y414167D01*
G01X1074200Y416833D02*
Y413500D01*
G01Y418167D02*
X1074033Y418250D01*
Y418417D01*
X1074200Y418500D01*
X1074367Y418417D01*
Y418250D01*
X1074200Y418167D01*
G01X1078383Y413500D02*
Y416833D01*
G01Y416000D02*
X1078717Y416417D01*
X1079217Y416750D01*
X1079883Y416833D01*
X1080467Y416750D01*
X1080967Y416417D01*
X1081217Y415833D01*
Y413500D01*
G01X1084150Y414083D02*
X1084567Y413750D01*
X1085150Y413500D01*
X1085650D01*
X1086150Y413667D01*
X1086483Y413917D01*
X1086650Y414250D01*
X1086567Y414750D01*
X1086233Y415000D01*
X1084733Y415500D01*
X1084400Y416083D01*
X1084567Y416500D01*
X1084900Y416750D01*
X1085400Y416833D01*
X1085900Y416750D01*
X1086400Y416500D01*
G01X1091000Y416833D02*
Y413500D01*
G01Y418167D02*
X1090833Y418250D01*
Y418417D01*
X1091000Y418500D01*
X1091167Y418417D01*
Y418250D01*
X1091000Y418167D01*
G01X1098100Y418500D02*
Y413500D01*
G01Y414250D02*
X1097767Y413833D01*
X1097267Y413583D01*
X1096683Y413500D01*
X1096017Y413667D01*
X1095517Y414083D01*
X1095183Y414583D01*
X1095100Y415167D01*
X1095183Y415750D01*
X1095517Y416250D01*
X1096017Y416667D01*
X1096683Y416833D01*
X1097267Y416750D01*
X1097683Y416583D01*
X1098100Y416250D01*
G01X1100950Y415750D02*
X1103617D01*
X1103367Y416333D01*
X1102950Y416667D01*
X1102367Y416833D01*
X1101783Y416750D01*
X1101283Y416500D01*
X1100950Y415917D01*
X1100783Y415417D01*
Y414917D01*
X1100950Y414417D01*
X1101367Y413917D01*
X1101867Y413583D01*
X1102450Y413500D01*
X1103033Y413667D01*
X1103617Y414167D01*
G01X1113400Y418500D02*
Y413500D01*
G01X1112233Y416833D02*
X1114567D01*
G01X1117583Y413500D02*
Y418500D01*
G01Y416083D02*
X1118000Y416500D01*
X1118417Y416750D01*
X1119083Y416833D01*
X1119583Y416750D01*
X1120167Y416417D01*
X1120417Y415917D01*
Y413500D01*
G01X1123350Y415750D02*
X1126017D01*
X1125767Y416333D01*
X1125350Y416667D01*
X1124767Y416833D01*
X1124183Y416750D01*
X1123683Y416500D01*
X1123350Y415917D01*
X1123183Y415417D01*
Y414917D01*
X1123350Y414417D01*
X1123767Y413917D01*
X1124267Y413583D01*
X1124850Y413500D01*
X1125433Y413667D01*
X1126017Y414167D01*
G01X1134633Y413500D02*
Y416833D01*
G01Y416167D02*
X1135050Y416500D01*
X1135467Y416750D01*
X1136050Y416833D01*
X1136467Y416750D01*
X1136967Y416500D01*
G01X1140150Y415750D02*
X1142817D01*
X1142567Y416333D01*
X1142150Y416667D01*
X1141567Y416833D01*
X1140983Y416750D01*
X1140483Y416500D01*
X1140150Y415917D01*
X1139983Y415417D01*
Y414917D01*
X1140150Y414417D01*
X1140567Y413917D01*
X1141067Y413583D01*
X1141650Y413500D01*
X1142233Y413667D01*
X1142817Y414167D01*
G01X1145750Y414083D02*
X1146167Y413750D01*
X1146750Y413500D01*
X1147250D01*
X1147750Y413667D01*
X1148083Y413917D01*
X1148250Y414250D01*
X1148167Y414750D01*
X1147833Y415000D01*
X1146333Y415500D01*
X1146000Y416083D01*
X1146167Y416500D01*
X1146500Y416750D01*
X1147000Y416833D01*
X1147500Y416750D01*
X1148000Y416500D01*
G01X1152600Y416833D02*
Y413500D01*
G01Y418167D02*
X1152433Y418250D01*
Y418417D01*
X1152600Y418500D01*
X1152767Y418417D01*
Y418250D01*
X1152600Y418167D01*
G01X1156783Y413500D02*
Y416833D01*
G01Y416000D02*
X1157117Y416417D01*
X1157617Y416750D01*
X1158283Y416833D01*
X1158867Y416750D01*
X1159367Y416417D01*
X1159617Y415833D01*
Y413500D01*
G01X1163800Y413333D02*
X1163633Y413417D01*
Y413583D01*
X1163800Y413667D01*
X1163967Y413583D01*
Y413417D01*
X1163800Y413333D01*
G01X1023000Y424000D02*
Y429000D01*
X1022000Y428000D01*
G01Y424000D02*
X1024000D01*
G01X1028600Y423833D02*
X1028433Y423917D01*
Y424083D01*
X1028600Y424167D01*
X1028767Y424083D01*
Y423917D01*
X1028600Y423833D01*
G01X1032117Y429000D02*
X1034200Y424000D01*
X1036283Y429000D01*
G01X1039800Y427333D02*
Y424000D01*
G01Y428667D02*
X1039633Y428750D01*
Y428917D01*
X1039800Y429000D01*
X1039967Y428917D01*
Y428750D01*
X1039800Y428667D01*
G01X1046900Y424000D02*
Y427333D01*
G01Y426750D02*
X1046567Y427083D01*
X1046067Y427250D01*
X1045483Y427333D01*
X1044900Y427167D01*
X1044400Y426833D01*
X1044067Y426333D01*
X1043900Y425667D01*
X1044067Y425000D01*
X1044400Y424500D01*
X1044900Y424167D01*
X1045483Y424000D01*
X1046067Y424083D01*
X1046567Y424333D01*
X1046900Y424667D01*
G01X1055350Y424583D02*
X1055767Y424250D01*
X1056350Y424000D01*
X1056850D01*
X1057350Y424167D01*
X1057683Y424417D01*
X1057850Y424750D01*
X1057767Y425250D01*
X1057433Y425500D01*
X1055933Y426000D01*
X1055600Y426583D01*
X1055767Y427000D01*
X1056100Y427250D01*
X1056600Y427333D01*
X1057100Y427250D01*
X1057600Y427000D01*
G01X1060783Y424000D02*
Y429000D01*
G01Y426583D02*
X1061200Y427000D01*
X1061617Y427250D01*
X1062283Y427333D01*
X1062783Y427250D01*
X1063367Y426917D01*
X1063617Y426417D01*
Y424000D01*
G01X1067800D02*
X1067300Y424083D01*
X1066800Y424417D01*
X1066467Y425000D01*
X1066300Y425667D01*
X1066467Y426333D01*
X1066800Y426917D01*
X1067300Y427250D01*
X1067800Y427333D01*
X1068300Y427250D01*
X1068800Y426917D01*
X1069133Y426333D01*
X1069217Y425667D01*
X1069133Y425000D01*
X1068800Y424417D01*
X1068300Y424083D01*
X1067800Y424000D01*
G01X1071983Y427333D02*
Y425000D01*
X1072317Y424417D01*
X1072817Y424083D01*
X1073400Y424000D01*
X1073983Y424083D01*
X1074483Y424417D01*
X1074817Y425000D01*
G01Y424000D02*
Y427333D01*
G01X1079000Y424000D02*
Y429000D01*
G01X1086100D02*
Y424000D01*
G01Y424750D02*
X1085767Y424333D01*
X1085267Y424083D01*
X1084683Y424000D01*
X1084017Y424167D01*
X1083517Y424583D01*
X1083183Y425083D01*
X1083100Y425667D01*
X1083183Y426250D01*
X1083517Y426750D01*
X1084017Y427167D01*
X1084683Y427333D01*
X1085267Y427250D01*
X1085683Y427083D01*
X1086100Y426750D01*
G01X1094300Y424000D02*
Y429000D01*
G01Y426500D02*
X1094717Y427000D01*
X1095217Y427250D01*
X1095717Y427333D01*
X1096467Y427167D01*
X1096967Y426833D01*
X1097300Y426250D01*
Y425583D01*
X1097133Y424917D01*
X1096800Y424417D01*
X1096217Y424083D01*
X1095717Y424000D01*
X1095217Y424083D01*
X1094717Y424333D01*
X1094300Y424750D01*
G01X1100150Y426250D02*
X1102817D01*
X1102567Y426833D01*
X1102150Y427167D01*
X1101567Y427333D01*
X1100983Y427250D01*
X1100483Y427000D01*
X1100150Y426417D01*
X1099983Y425917D01*
Y425417D01*
X1100150Y424917D01*
X1100567Y424417D01*
X1101067Y424083D01*
X1101650Y424000D01*
X1102233Y424167D01*
X1102817Y424667D01*
G01X1111100Y422333D02*
Y427333D01*
G01Y426583D02*
X1111517Y427000D01*
X1111933Y427250D01*
X1112600Y427333D01*
X1113183Y427250D01*
X1113767Y426833D01*
X1114017Y426250D01*
X1114100Y425667D01*
X1114017Y425083D01*
X1113767Y424500D01*
X1113267Y424167D01*
X1112600Y424000D01*
X1112017Y424083D01*
X1111433Y424333D01*
X1111100Y424667D01*
G01X1118200Y424000D02*
Y429000D01*
G01X1122383Y427333D02*
Y425000D01*
X1122717Y424417D01*
X1123217Y424083D01*
X1123800Y424000D01*
X1124383Y424083D01*
X1124883Y424417D01*
X1125217Y425000D01*
G01Y424000D02*
Y427333D01*
G01X1128233Y422750D02*
X1128817Y422417D01*
X1129483Y422333D01*
X1130067Y422417D01*
X1130567Y422833D01*
X1130900Y423417D01*
Y427333D01*
G01Y426667D02*
X1130567Y427000D01*
X1130067Y427250D01*
X1129483Y427333D01*
X1128817Y427167D01*
X1128400Y426833D01*
X1128067Y426250D01*
X1127900Y425667D01*
X1127983Y425167D01*
X1128317Y424583D01*
X1128817Y424167D01*
X1129483Y424000D01*
X1129983Y424083D01*
X1130567Y424417D01*
X1130900Y424750D01*
G01X1133833Y422750D02*
X1134417Y422417D01*
X1135083Y422333D01*
X1135667Y422417D01*
X1136167Y422833D01*
X1136500Y423417D01*
Y427333D01*
G01Y426667D02*
X1136167Y427000D01*
X1135667Y427250D01*
X1135083Y427333D01*
X1134417Y427167D01*
X1134000Y426833D01*
X1133667Y426250D01*
X1133500Y425667D01*
X1133583Y425167D01*
X1133917Y424583D01*
X1134417Y424167D01*
X1135083Y424000D01*
X1135583Y424083D01*
X1136167Y424417D01*
X1136500Y424750D01*
G01X1139350Y426250D02*
X1142017D01*
X1141767Y426833D01*
X1141350Y427167D01*
X1140767Y427333D01*
X1140183Y427250D01*
X1139683Y427000D01*
X1139350Y426417D01*
X1139183Y425917D01*
Y425417D01*
X1139350Y424917D01*
X1139767Y424417D01*
X1140267Y424083D01*
X1140850Y424000D01*
X1141433Y424167D01*
X1142017Y424667D01*
G01X1147700Y429000D02*
Y424000D01*
G01Y424750D02*
X1147367Y424333D01*
X1146867Y424083D01*
X1146283Y424000D01*
X1145617Y424167D01*
X1145117Y424583D01*
X1144783Y425083D01*
X1144700Y425667D01*
X1144783Y426250D01*
X1145117Y426750D01*
X1145617Y427167D01*
X1146283Y427333D01*
X1146867Y427250D01*
X1147283Y427083D01*
X1147700Y426750D01*
G01X1155317Y427333D02*
X1156317Y424000D01*
X1157400Y427333D01*
X1158483Y424000D01*
X1159483Y427333D01*
G01X1163000D02*
Y424000D01*
G01Y428667D02*
X1162833Y428750D01*
Y428917D01*
X1163000Y429000D01*
X1163167Y428917D01*
Y428750D01*
X1163000Y428667D01*
G01X1168600Y429000D02*
Y424000D01*
G01X1167433Y427333D02*
X1169767D01*
G01X1172783Y424000D02*
Y429000D01*
G01Y426583D02*
X1173200Y427000D01*
X1173617Y427250D01*
X1174283Y427333D01*
X1174783Y427250D01*
X1175367Y426917D01*
X1175617Y426417D01*
Y424000D01*
G01X1183733D02*
X1187067Y425667D01*
X1183733Y427333D01*
G01X1189583Y424583D02*
X1190167Y424167D01*
X1190833Y424000D01*
X1191500Y424167D01*
X1192083Y424667D01*
X1192500Y425417D01*
X1192667Y426167D01*
Y427083D01*
X1192500Y427833D01*
X1192083Y428500D01*
X1191583Y428833D01*
X1191000Y429000D01*
X1190333Y428833D01*
X1189833Y428500D01*
X1189500Y428000D01*
X1189333Y427333D01*
X1189500Y426750D01*
X1189917Y426167D01*
X1190417Y425833D01*
X1191000Y425750D01*
X1191667Y425917D01*
X1192167Y426333D01*
X1192667Y427083D01*
G01X1196600Y429000D02*
X1195933Y428833D01*
X1195433Y428417D01*
X1195100Y427917D01*
X1194850Y427250D01*
X1194767Y426500D01*
X1194850Y425750D01*
X1195100Y425083D01*
X1195433Y424583D01*
X1195933Y424167D01*
X1196600Y424000D01*
X1197267Y424167D01*
X1197767Y424583D01*
X1198100Y425083D01*
X1198350Y425750D01*
X1198433Y426500D01*
X1198350Y427250D01*
X1198100Y427917D01*
X1197767Y428417D01*
X1197267Y428833D01*
X1196600Y429000D01*
G01X1200700Y423833D02*
X1203700Y429000D01*
G01X1200700D02*
X1200200Y428833D01*
X1199950Y428583D01*
X1199783Y428083D01*
X1199950Y427583D01*
X1200200Y427333D01*
X1200700Y427167D01*
X1201200Y427333D01*
X1201450Y427583D01*
X1201617Y428083D01*
X1201450Y428583D01*
X1201200Y428833D01*
X1200700Y429000D01*
G01X1203700Y425667D02*
X1203200Y425500D01*
X1202950Y425250D01*
X1202783Y424750D01*
X1202950Y424250D01*
X1203200Y424000D01*
X1203700Y423833D01*
X1204200Y424000D01*
X1204450Y424250D01*
X1204617Y424750D01*
X1204450Y425250D01*
X1204200Y425500D01*
X1203700Y425667D01*
G01X1212233Y424000D02*
Y427333D01*
G01Y426667D02*
X1212650Y427000D01*
X1213067Y427250D01*
X1213650Y427333D01*
X1214067Y427250D01*
X1214567Y427000D01*
G01X1217750Y426250D02*
X1220417D01*
X1220167Y426833D01*
X1219750Y427167D01*
X1219167Y427333D01*
X1218583Y427250D01*
X1218083Y427000D01*
X1217750Y426417D01*
X1217583Y425917D01*
Y425417D01*
X1217750Y424917D01*
X1218167Y424417D01*
X1218667Y424083D01*
X1219250Y424000D01*
X1219833Y424167D01*
X1220417Y424667D01*
G01X1223350Y424583D02*
X1223767Y424250D01*
X1224350Y424000D01*
X1224850D01*
X1225350Y424167D01*
X1225683Y424417D01*
X1225850Y424750D01*
X1225767Y425250D01*
X1225433Y425500D01*
X1223933Y426000D01*
X1223600Y426583D01*
X1223767Y427000D01*
X1224100Y427250D01*
X1224600Y427333D01*
X1225100Y427250D01*
X1225600Y427000D01*
G01X1230200Y427333D02*
Y424000D01*
G01Y428667D02*
X1230033Y428750D01*
Y428917D01*
X1230200Y429000D01*
X1230367Y428917D01*
Y428750D01*
X1230200Y428667D01*
G01X1234383Y424000D02*
Y427333D01*
G01Y426500D02*
X1234717Y426917D01*
X1235217Y427250D01*
X1235883Y427333D01*
X1236467Y427250D01*
X1236967Y426917D01*
X1237217Y426333D01*
Y424000D01*
G01X1246417Y422500D02*
X1247583Y423667D01*
Y424833D01*
X1246417D01*
Y423667D01*
X1247583D01*
G01Y425667D02*
Y426833D01*
X1246417D01*
Y425667D01*
X1247583D01*
G01X1250767Y424000D02*
Y429000D01*
X1252433D01*
X1253100Y428750D01*
X1253600Y428417D01*
X1254017Y427917D01*
X1254350Y427333D01*
X1254433Y426500D01*
X1254350Y425667D01*
X1254017Y425083D01*
X1253600Y424583D01*
X1253100Y424250D01*
X1252433Y424000D01*
X1250767D01*
G01X1258200D02*
X1257700Y424083D01*
X1257200Y424417D01*
X1256867Y425000D01*
X1256700Y425667D01*
X1256867Y426333D01*
X1257200Y426917D01*
X1257700Y427250D01*
X1258200Y427333D01*
X1258700Y427250D01*
X1259200Y426917D01*
X1259533Y426333D01*
X1259617Y425667D01*
X1259533Y425000D01*
X1259200Y424417D01*
X1258700Y424083D01*
X1258200Y424000D01*
G01X1267983D02*
Y427333D01*
G01Y426500D02*
X1268317Y426917D01*
X1268817Y427250D01*
X1269483Y427333D01*
X1270067Y427250D01*
X1270567Y426917D01*
X1270817Y426333D01*
Y424000D01*
G01X1275000D02*
X1274500Y424083D01*
X1274000Y424417D01*
X1273667Y425000D01*
X1273500Y425667D01*
X1273667Y426333D01*
X1274000Y426917D01*
X1274500Y427250D01*
X1275000Y427333D01*
X1275500Y427250D01*
X1276000Y426917D01*
X1276333Y426333D01*
X1276417Y425667D01*
X1276333Y425000D01*
X1276000Y424417D01*
X1275500Y424083D01*
X1275000Y424000D01*
G01X1280600Y429000D02*
Y424000D01*
G01X1279433Y427333D02*
X1281767D01*
G01X1293300Y424000D02*
Y427333D01*
G01Y426750D02*
X1292967Y427083D01*
X1292467Y427250D01*
X1291883Y427333D01*
X1291300Y427167D01*
X1290800Y426833D01*
X1290467Y426333D01*
X1290300Y425667D01*
X1290467Y425000D01*
X1290800Y424500D01*
X1291300Y424167D01*
X1291883Y424000D01*
X1292467Y424083D01*
X1292967Y424333D01*
X1293300Y424667D01*
G01X1297400Y424000D02*
Y429000D01*
G01X1303000Y424000D02*
Y429000D01*
G01X1308600Y424000D02*
X1308100Y424083D01*
X1307600Y424417D01*
X1307267Y425000D01*
X1307100Y425667D01*
X1307267Y426333D01*
X1307600Y426917D01*
X1308100Y427250D01*
X1308600Y427333D01*
X1309100Y427250D01*
X1309600Y426917D01*
X1309933Y426333D01*
X1310017Y425667D01*
X1309933Y425000D01*
X1309600Y424417D01*
X1309100Y424083D01*
X1308600Y424000D01*
G01X1312117Y427333D02*
X1313117Y424000D01*
X1314200Y427333D01*
X1315283Y424000D01*
X1316283Y427333D01*
G01X1025417Y445500D02*
X1027500Y440500D01*
X1029583Y445500D01*
G01X1033100Y443833D02*
Y440500D01*
G01Y445167D02*
X1032933Y445250D01*
Y445417D01*
X1033100Y445500D01*
X1033267Y445417D01*
Y445250D01*
X1033100Y445167D01*
G01X1040200Y440500D02*
Y443833D01*
G01Y443250D02*
X1039867Y443583D01*
X1039367Y443750D01*
X1038783Y443833D01*
X1038200Y443667D01*
X1037700Y443333D01*
X1037367Y442833D01*
X1037200Y442167D01*
X1037367Y441500D01*
X1037700Y441000D01*
X1038200Y440667D01*
X1038783Y440500D01*
X1039367Y440583D01*
X1039867Y440833D01*
X1040200Y441167D01*
G01X1048650Y441083D02*
X1049067Y440750D01*
X1049650Y440500D01*
X1050150D01*
X1050650Y440667D01*
X1050983Y440917D01*
X1051150Y441250D01*
X1051067Y441750D01*
X1050733Y442000D01*
X1049233Y442500D01*
X1048900Y443083D01*
X1049067Y443500D01*
X1049400Y443750D01*
X1049900Y443833D01*
X1050400Y443750D01*
X1050900Y443500D01*
G01X1054083Y440500D02*
Y445500D01*
G01Y443083D02*
X1054500Y443500D01*
X1054917Y443750D01*
X1055583Y443833D01*
X1056083Y443750D01*
X1056667Y443417D01*
X1056917Y442917D01*
Y440500D01*
G01X1061100D02*
X1060600Y440583D01*
X1060100Y440917D01*
X1059767Y441500D01*
X1059600Y442167D01*
X1059767Y442833D01*
X1060100Y443417D01*
X1060600Y443750D01*
X1061100Y443833D01*
X1061600Y443750D01*
X1062100Y443417D01*
X1062433Y442833D01*
X1062517Y442167D01*
X1062433Y441500D01*
X1062100Y440917D01*
X1061600Y440583D01*
X1061100Y440500D01*
G01X1065283Y443833D02*
Y441500D01*
X1065617Y440917D01*
X1066117Y440583D01*
X1066700Y440500D01*
X1067283Y440583D01*
X1067783Y440917D01*
X1068117Y441500D01*
G01Y440500D02*
Y443833D01*
G01X1072300Y440500D02*
Y445500D01*
G01X1079400D02*
Y440500D01*
G01Y441250D02*
X1079067Y440833D01*
X1078567Y440583D01*
X1077983Y440500D01*
X1077317Y440667D01*
X1076817Y441083D01*
X1076483Y441583D01*
X1076400Y442167D01*
X1076483Y442750D01*
X1076817Y443250D01*
X1077317Y443667D01*
X1077983Y443833D01*
X1078567Y443750D01*
X1078983Y443583D01*
X1079400Y443250D01*
G01X1087600Y440500D02*
Y445500D01*
G01Y443000D02*
X1088017Y443500D01*
X1088517Y443750D01*
X1089017Y443833D01*
X1089767Y443667D01*
X1090267Y443333D01*
X1090600Y442750D01*
Y442083D01*
X1090433Y441417D01*
X1090100Y440917D01*
X1089517Y440583D01*
X1089017Y440500D01*
X1088517Y440583D01*
X1088017Y440833D01*
X1087600Y441250D01*
G01X1093450Y442750D02*
X1096117D01*
X1095867Y443333D01*
X1095450Y443667D01*
X1094867Y443833D01*
X1094283Y443750D01*
X1093783Y443500D01*
X1093450Y442917D01*
X1093283Y442417D01*
Y441917D01*
X1093450Y441417D01*
X1093867Y440917D01*
X1094367Y440583D01*
X1094950Y440500D01*
X1095533Y440667D01*
X1096117Y441167D01*
G01X1104400Y438833D02*
Y443833D01*
G01Y443083D02*
X1104817Y443500D01*
X1105233Y443750D01*
X1105900Y443833D01*
X1106483Y443750D01*
X1107067Y443333D01*
X1107317Y442750D01*
X1107400Y442167D01*
X1107317Y441583D01*
X1107067Y441000D01*
X1106567Y440667D01*
X1105900Y440500D01*
X1105317Y440583D01*
X1104733Y440833D01*
X1104400Y441167D01*
G01X1111500Y440500D02*
Y445500D01*
G01X1115683Y443833D02*
Y441500D01*
X1116017Y440917D01*
X1116517Y440583D01*
X1117100Y440500D01*
X1117683Y440583D01*
X1118183Y440917D01*
X1118517Y441500D01*
G01Y440500D02*
Y443833D01*
G01X1121533Y439250D02*
X1122117Y438917D01*
X1122783Y438833D01*
X1123367Y438917D01*
X1123867Y439333D01*
X1124200Y439917D01*
Y443833D01*
G01Y443167D02*
X1123867Y443500D01*
X1123367Y443750D01*
X1122783Y443833D01*
X1122117Y443667D01*
X1121700Y443333D01*
X1121367Y442750D01*
X1121200Y442167D01*
X1121283Y441667D01*
X1121617Y441083D01*
X1122117Y440667D01*
X1122783Y440500D01*
X1123283Y440583D01*
X1123867Y440917D01*
X1124200Y441250D01*
G01X1127133Y439250D02*
X1127717Y438917D01*
X1128383Y438833D01*
X1128967Y438917D01*
X1129467Y439333D01*
X1129800Y439917D01*
Y443833D01*
G01Y443167D02*
X1129467Y443500D01*
X1128967Y443750D01*
X1128383Y443833D01*
X1127717Y443667D01*
X1127300Y443333D01*
X1126967Y442750D01*
X1126800Y442167D01*
X1126883Y441667D01*
X1127217Y441083D01*
X1127717Y440667D01*
X1128383Y440500D01*
X1128883Y440583D01*
X1129467Y440917D01*
X1129800Y441250D01*
G01X1132650Y442750D02*
X1135317D01*
X1135067Y443333D01*
X1134650Y443667D01*
X1134067Y443833D01*
X1133483Y443750D01*
X1132983Y443500D01*
X1132650Y442917D01*
X1132483Y442417D01*
Y441917D01*
X1132650Y441417D01*
X1133067Y440917D01*
X1133567Y440583D01*
X1134150Y440500D01*
X1134733Y440667D01*
X1135317Y441167D01*
G01X1141000Y445500D02*
Y440500D01*
G01Y441250D02*
X1140667Y440833D01*
X1140167Y440583D01*
X1139583Y440500D01*
X1138917Y440667D01*
X1138417Y441083D01*
X1138083Y441583D01*
X1138000Y442167D01*
X1138083Y442750D01*
X1138417Y443250D01*
X1138917Y443667D01*
X1139583Y443833D01*
X1140167Y443750D01*
X1140583Y443583D01*
X1141000Y443250D01*
G01X1148617Y443833D02*
X1149617Y440500D01*
X1150700Y443833D01*
X1151783Y440500D01*
X1152783Y443833D01*
G01X1156300D02*
Y440500D01*
G01Y445167D02*
X1156133Y445250D01*
Y445417D01*
X1156300Y445500D01*
X1156467Y445417D01*
Y445250D01*
X1156300Y445167D01*
G01X1161900Y445500D02*
Y440500D01*
G01X1160733Y443833D02*
X1163067D01*
G01X1166083Y440500D02*
Y445500D01*
G01Y443083D02*
X1166500Y443500D01*
X1166917Y443750D01*
X1167583Y443833D01*
X1168083Y443750D01*
X1168667Y443417D01*
X1168917Y442917D01*
Y440500D01*
G01X1177033D02*
X1180367Y442167D01*
X1177033Y443833D01*
G01X1182883Y441083D02*
X1183467Y440667D01*
X1184133Y440500D01*
X1184800Y440667D01*
X1185383Y441167D01*
X1185800Y441917D01*
X1185967Y442667D01*
Y443583D01*
X1185800Y444333D01*
X1185383Y445000D01*
X1184883Y445333D01*
X1184300Y445500D01*
X1183633Y445333D01*
X1183133Y445000D01*
X1182800Y444500D01*
X1182633Y443833D01*
X1182800Y443250D01*
X1183217Y442667D01*
X1183717Y442333D01*
X1184300Y442250D01*
X1184967Y442417D01*
X1185467Y442833D01*
X1185967Y443583D01*
G01X1189900Y445500D02*
X1189233Y445333D01*
X1188733Y444917D01*
X1188400Y444417D01*
X1188150Y443750D01*
X1188067Y443000D01*
X1188150Y442250D01*
X1188400Y441583D01*
X1188733Y441083D01*
X1189233Y440667D01*
X1189900Y440500D01*
X1190567Y440667D01*
X1191067Y441083D01*
X1191400Y441583D01*
X1191650Y442250D01*
X1191733Y443000D01*
X1191650Y443750D01*
X1191400Y444417D01*
X1191067Y444917D01*
X1190567Y445333D01*
X1189900Y445500D01*
G01X1194000Y440333D02*
X1197000Y445500D01*
G01X1194000D02*
X1193500Y445333D01*
X1193250Y445083D01*
X1193083Y444583D01*
X1193250Y444083D01*
X1193500Y443833D01*
X1194000Y443667D01*
X1194500Y443833D01*
X1194750Y444083D01*
X1194917Y444583D01*
X1194750Y445083D01*
X1194500Y445333D01*
X1194000Y445500D01*
G01X1197000Y442167D02*
X1196500Y442000D01*
X1196250Y441750D01*
X1196083Y441250D01*
X1196250Y440750D01*
X1196500Y440500D01*
X1197000Y440333D01*
X1197500Y440500D01*
X1197750Y440750D01*
X1197917Y441250D01*
X1197750Y441750D01*
X1197500Y442000D01*
X1197000Y442167D01*
G01X1205533Y440500D02*
Y443833D01*
G01Y443167D02*
X1205950Y443500D01*
X1206367Y443750D01*
X1206950Y443833D01*
X1207367Y443750D01*
X1207867Y443500D01*
G01X1211050Y442750D02*
X1213717D01*
X1213467Y443333D01*
X1213050Y443667D01*
X1212467Y443833D01*
X1211883Y443750D01*
X1211383Y443500D01*
X1211050Y442917D01*
X1210883Y442417D01*
Y441917D01*
X1211050Y441417D01*
X1211467Y440917D01*
X1211967Y440583D01*
X1212550Y440500D01*
X1213133Y440667D01*
X1213717Y441167D01*
G01X1216650Y441083D02*
X1217067Y440750D01*
X1217650Y440500D01*
X1218150D01*
X1218650Y440667D01*
X1218983Y440917D01*
X1219150Y441250D01*
X1219067Y441750D01*
X1218733Y442000D01*
X1217233Y442500D01*
X1216900Y443083D01*
X1217067Y443500D01*
X1217400Y443750D01*
X1217900Y443833D01*
X1218400Y443750D01*
X1218900Y443500D01*
G01X1223500Y443833D02*
Y440500D01*
G01Y445167D02*
X1223333Y445250D01*
Y445417D01*
X1223500Y445500D01*
X1223667Y445417D01*
Y445250D01*
X1223500Y445167D01*
G01X1227683Y440500D02*
Y443833D01*
G01Y443000D02*
X1228017Y443417D01*
X1228517Y443750D01*
X1229183Y443833D01*
X1229767Y443750D01*
X1230267Y443417D01*
X1230517Y442833D01*
Y440500D01*
G01X1023917Y466500D02*
X1026000Y461500D01*
X1028083Y466500D01*
G01X1031600Y464833D02*
Y461500D01*
G01Y466167D02*
X1031433Y466250D01*
Y466417D01*
X1031600Y466500D01*
X1031767Y466417D01*
Y466250D01*
X1031600Y466167D01*
G01X1038700Y461500D02*
Y464833D01*
G01Y464250D02*
X1038367Y464583D01*
X1037867Y464750D01*
X1037283Y464833D01*
X1036700Y464667D01*
X1036200Y464333D01*
X1035867Y463833D01*
X1035700Y463167D01*
X1035867Y462500D01*
X1036200Y462000D01*
X1036700Y461667D01*
X1037283Y461500D01*
X1037867Y461583D01*
X1038367Y461833D01*
X1038700Y462167D01*
G01X1047150Y462083D02*
X1047567Y461750D01*
X1048150Y461500D01*
X1048650D01*
X1049150Y461667D01*
X1049483Y461917D01*
X1049650Y462250D01*
X1049567Y462750D01*
X1049233Y463000D01*
X1047733Y463500D01*
X1047400Y464083D01*
X1047567Y464500D01*
X1047900Y464750D01*
X1048400Y464833D01*
X1048900Y464750D01*
X1049400Y464500D01*
G01X1052583Y461500D02*
Y466500D01*
G01Y464083D02*
X1053000Y464500D01*
X1053417Y464750D01*
X1054083Y464833D01*
X1054583Y464750D01*
X1055167Y464417D01*
X1055417Y463917D01*
Y461500D01*
G01X1059600D02*
X1059100Y461583D01*
X1058600Y461917D01*
X1058267Y462500D01*
X1058100Y463167D01*
X1058267Y463833D01*
X1058600Y464417D01*
X1059100Y464750D01*
X1059600Y464833D01*
X1060100Y464750D01*
X1060600Y464417D01*
X1060933Y463833D01*
X1061017Y463167D01*
X1060933Y462500D01*
X1060600Y461917D01*
X1060100Y461583D01*
X1059600Y461500D01*
G01X1063783Y464833D02*
Y462500D01*
X1064117Y461917D01*
X1064617Y461583D01*
X1065200Y461500D01*
X1065783Y461583D01*
X1066283Y461917D01*
X1066617Y462500D01*
G01Y461500D02*
Y464833D01*
G01X1070800Y461500D02*
Y466500D01*
G01X1077900D02*
Y461500D01*
G01Y462250D02*
X1077567Y461833D01*
X1077067Y461583D01*
X1076483Y461500D01*
X1075817Y461667D01*
X1075317Y462083D01*
X1074983Y462583D01*
X1074900Y463167D01*
X1074983Y463750D01*
X1075317Y464250D01*
X1075817Y464667D01*
X1076483Y464833D01*
X1077067Y464750D01*
X1077483Y464583D01*
X1077900Y464250D01*
G01X1086100Y461500D02*
Y466500D01*
G01Y464000D02*
X1086517Y464500D01*
X1087017Y464750D01*
X1087517Y464833D01*
X1088267Y464667D01*
X1088767Y464333D01*
X1089100Y463750D01*
Y463083D01*
X1088933Y462417D01*
X1088600Y461917D01*
X1088017Y461583D01*
X1087517Y461500D01*
X1087017Y461583D01*
X1086517Y461833D01*
X1086100Y462250D01*
G01X1091950Y463750D02*
X1094617D01*
X1094367Y464333D01*
X1093950Y464667D01*
X1093367Y464833D01*
X1092783Y464750D01*
X1092283Y464500D01*
X1091950Y463917D01*
X1091783Y463417D01*
Y462917D01*
X1091950Y462417D01*
X1092367Y461917D01*
X1092867Y461583D01*
X1093450Y461500D01*
X1094033Y461667D01*
X1094617Y462167D01*
G01X1102900Y459833D02*
Y464833D01*
G01Y464083D02*
X1103317Y464500D01*
X1103733Y464750D01*
X1104400Y464833D01*
X1104983Y464750D01*
X1105567Y464333D01*
X1105817Y463750D01*
X1105900Y463167D01*
X1105817Y462583D01*
X1105567Y462000D01*
X1105067Y461667D01*
X1104400Y461500D01*
X1103817Y461583D01*
X1103233Y461833D01*
X1102900Y462167D01*
G01X1110000Y461500D02*
Y466500D01*
G01X1114183Y464833D02*
Y462500D01*
X1114517Y461917D01*
X1115017Y461583D01*
X1115600Y461500D01*
X1116183Y461583D01*
X1116683Y461917D01*
X1117017Y462500D01*
G01Y461500D02*
Y464833D01*
G01X1120033Y460250D02*
X1120617Y459917D01*
X1121283Y459833D01*
X1121867Y459917D01*
X1122367Y460333D01*
X1122700Y460917D01*
Y464833D01*
G01Y464167D02*
X1122367Y464500D01*
X1121867Y464750D01*
X1121283Y464833D01*
X1120617Y464667D01*
X1120200Y464333D01*
X1119867Y463750D01*
X1119700Y463167D01*
X1119783Y462667D01*
X1120117Y462083D01*
X1120617Y461667D01*
X1121283Y461500D01*
X1121783Y461583D01*
X1122367Y461917D01*
X1122700Y462250D01*
G01X1125633Y460250D02*
X1126217Y459917D01*
X1126883Y459833D01*
X1127467Y459917D01*
X1127967Y460333D01*
X1128300Y460917D01*
Y464833D01*
G01Y464167D02*
X1127967Y464500D01*
X1127467Y464750D01*
X1126883Y464833D01*
X1126217Y464667D01*
X1125800Y464333D01*
X1125467Y463750D01*
X1125300Y463167D01*
X1125383Y462667D01*
X1125717Y462083D01*
X1126217Y461667D01*
X1126883Y461500D01*
X1127383Y461583D01*
X1127967Y461917D01*
X1128300Y462250D01*
G01X1131150Y463750D02*
X1133817D01*
X1133567Y464333D01*
X1133150Y464667D01*
X1132567Y464833D01*
X1131983Y464750D01*
X1131483Y464500D01*
X1131150Y463917D01*
X1130983Y463417D01*
Y462917D01*
X1131150Y462417D01*
X1131567Y461917D01*
X1132067Y461583D01*
X1132650Y461500D01*
X1133233Y461667D01*
X1133817Y462167D01*
G01X1139500Y466500D02*
Y461500D01*
G01Y462250D02*
X1139167Y461833D01*
X1138667Y461583D01*
X1138083Y461500D01*
X1137417Y461667D01*
X1136917Y462083D01*
X1136583Y462583D01*
X1136500Y463167D01*
X1136583Y463750D01*
X1136917Y464250D01*
X1137417Y464667D01*
X1138083Y464833D01*
X1138667Y464750D01*
X1139083Y464583D01*
X1139500Y464250D01*
G01X1150200Y461500D02*
Y466500D01*
X1147117Y462917D01*
X1151283D01*
G01X1154800Y466500D02*
X1154133Y466333D01*
X1153633Y465917D01*
X1153300Y465417D01*
X1153050Y464750D01*
X1152967Y464000D01*
X1153050Y463250D01*
X1153300Y462583D01*
X1153633Y462083D01*
X1154133Y461667D01*
X1154800Y461500D01*
X1155467Y461667D01*
X1155967Y462083D01*
X1156300Y462583D01*
X1156550Y463250D01*
X1156633Y464000D01*
X1156550Y464750D01*
X1156300Y465417D01*
X1155967Y465917D01*
X1155467Y466333D01*
X1154800Y466500D01*
G01X1158900Y461333D02*
X1161900Y466500D01*
G01X1158900D02*
X1158400Y466333D01*
X1158150Y466083D01*
X1157983Y465583D01*
X1158150Y465083D01*
X1158400Y464833D01*
X1158900Y464667D01*
X1159400Y464833D01*
X1159650Y465083D01*
X1159817Y465583D01*
X1159650Y466083D01*
X1159400Y466333D01*
X1158900Y466500D01*
G01X1161900Y463167D02*
X1161400Y463000D01*
X1161150Y462750D01*
X1160983Y462250D01*
X1161150Y461750D01*
X1161400Y461500D01*
X1161900Y461333D01*
X1162400Y461500D01*
X1162650Y461750D01*
X1162817Y462250D01*
X1162650Y462750D01*
X1162400Y463000D01*
X1161900Y463167D01*
G01X1169100D02*
X1169933Y464833D01*
X1170767D01*
X1172433Y461500D01*
X1173267D01*
X1174100Y463167D01*
G01X1182800Y461500D02*
Y466500D01*
X1181800Y465500D01*
G01Y461500D02*
X1183800D01*
G01X1188400Y466500D02*
X1187733Y466333D01*
X1187233Y465917D01*
X1186900Y465417D01*
X1186650Y464750D01*
X1186567Y464000D01*
X1186650Y463250D01*
X1186900Y462583D01*
X1187233Y462083D01*
X1187733Y461667D01*
X1188400Y461500D01*
X1189067Y461667D01*
X1189567Y462083D01*
X1189900Y462583D01*
X1190150Y463250D01*
X1190233Y464000D01*
X1190150Y464750D01*
X1189900Y465417D01*
X1189567Y465917D01*
X1189067Y466333D01*
X1188400Y466500D01*
G01X1194000D02*
X1193333Y466333D01*
X1192833Y465917D01*
X1192500Y465417D01*
X1192250Y464750D01*
X1192167Y464000D01*
X1192250Y463250D01*
X1192500Y462583D01*
X1192833Y462083D01*
X1193333Y461667D01*
X1194000Y461500D01*
X1194667Y461667D01*
X1195167Y462083D01*
X1195500Y462583D01*
X1195750Y463250D01*
X1195833Y464000D01*
X1195750Y464750D01*
X1195500Y465417D01*
X1195167Y465917D01*
X1194667Y466333D01*
X1194000Y466500D01*
G01X1198100Y461333D02*
X1201100Y466500D01*
G01X1198100D02*
X1197600Y466333D01*
X1197350Y466083D01*
X1197183Y465583D01*
X1197350Y465083D01*
X1197600Y464833D01*
X1198100Y464667D01*
X1198600Y464833D01*
X1198850Y465083D01*
X1199017Y465583D01*
X1198850Y466083D01*
X1198600Y466333D01*
X1198100Y466500D01*
G01X1201100Y463167D02*
X1200600Y463000D01*
X1200350Y462750D01*
X1200183Y462250D01*
X1200350Y461750D01*
X1200600Y461500D01*
X1201100Y461333D01*
X1201600Y461500D01*
X1201850Y461750D01*
X1202017Y462250D01*
X1201850Y462750D01*
X1201600Y463000D01*
X1201100Y463167D01*
G01X1209550Y462083D02*
X1209967Y461750D01*
X1210550Y461500D01*
X1211050D01*
X1211550Y461667D01*
X1211883Y461917D01*
X1212050Y462250D01*
X1211967Y462750D01*
X1211633Y463000D01*
X1210133Y463500D01*
X1209800Y464083D01*
X1209967Y464500D01*
X1210300Y464750D01*
X1210800Y464833D01*
X1211300Y464750D01*
X1211800Y464500D01*
G01X1216400Y461500D02*
X1215900Y461583D01*
X1215400Y461917D01*
X1215067Y462500D01*
X1214900Y463167D01*
X1215067Y463833D01*
X1215400Y464417D01*
X1215900Y464750D01*
X1216400Y464833D01*
X1216900Y464750D01*
X1217400Y464417D01*
X1217733Y463833D01*
X1217817Y463167D01*
X1217733Y462500D01*
X1217400Y461917D01*
X1216900Y461583D01*
X1216400Y461500D01*
G01X1222000D02*
Y466500D01*
G01X1229100D02*
Y461500D01*
G01Y462250D02*
X1228767Y461833D01*
X1228267Y461583D01*
X1227683Y461500D01*
X1227017Y461667D01*
X1226517Y462083D01*
X1226183Y462583D01*
X1226100Y463167D01*
X1226183Y463750D01*
X1226517Y464250D01*
X1227017Y464667D01*
X1227683Y464833D01*
X1228267Y464750D01*
X1228683Y464583D01*
X1229100Y464250D01*
G01X1231950Y463750D02*
X1234617D01*
X1234367Y464333D01*
X1233950Y464667D01*
X1233367Y464833D01*
X1232783Y464750D01*
X1232283Y464500D01*
X1231950Y463917D01*
X1231783Y463417D01*
Y462917D01*
X1231950Y462417D01*
X1232367Y461917D01*
X1232867Y461583D01*
X1233450Y461500D01*
X1234033Y461667D01*
X1234617Y462167D01*
G01X1237633Y461500D02*
Y464833D01*
G01Y464167D02*
X1238050Y464500D01*
X1238467Y464750D01*
X1239050Y464833D01*
X1239467Y464750D01*
X1239967Y464500D01*
G01X1247500Y461500D02*
Y464833D01*
G01Y463917D02*
X1247750Y464333D01*
X1248167Y464667D01*
X1248750Y464833D01*
X1249333Y464667D01*
X1249750Y464333D01*
X1250000Y463917D01*
Y461500D01*
G01Y463917D02*
X1250250Y464333D01*
X1250667Y464667D01*
X1251250Y464833D01*
X1251833Y464667D01*
X1252250Y464333D01*
X1252500Y463833D01*
Y461500D01*
G01X1257100D02*
Y464833D01*
G01Y464250D02*
X1256767Y464583D01*
X1256267Y464750D01*
X1255683Y464833D01*
X1255100Y464667D01*
X1254600Y464333D01*
X1254267Y463833D01*
X1254100Y463167D01*
X1254267Y462500D01*
X1254600Y462000D01*
X1255100Y461667D01*
X1255683Y461500D01*
X1256267Y461583D01*
X1256767Y461833D01*
X1257100Y462167D01*
G01X1259950Y462083D02*
X1260367Y461750D01*
X1260950Y461500D01*
X1261450D01*
X1261950Y461667D01*
X1262283Y461917D01*
X1262450Y462250D01*
X1262367Y462750D01*
X1262033Y463000D01*
X1260533Y463500D01*
X1260200Y464083D01*
X1260367Y464500D01*
X1260700Y464750D01*
X1261200Y464833D01*
X1261700Y464750D01*
X1262200Y464500D01*
G01X1265383Y461500D02*
Y466500D01*
G01X1268050Y464833D02*
X1265383Y462917D01*
G01X1266467Y463667D02*
X1268217Y461500D01*
G01X1035500Y491500D02*
Y496500D01*
G01Y494000D02*
X1035917Y494500D01*
X1036417Y494750D01*
X1036917Y494833D01*
X1037667Y494667D01*
X1038167Y494333D01*
X1038500Y493750D01*
Y493083D01*
X1038333Y492417D01*
X1038000Y491917D01*
X1037417Y491583D01*
X1036917Y491500D01*
X1036417Y491583D01*
X1035917Y491833D01*
X1035500Y492250D01*
G01X1042600Y491333D02*
X1042433Y491417D01*
Y491583D01*
X1042600Y491667D01*
X1042767Y491583D01*
Y491417D01*
X1042600Y491333D01*
G01X1048867Y494167D02*
X1049200Y494417D01*
X1049450Y494833D01*
X1049617Y495417D01*
X1049450Y495917D01*
X1049117Y496250D01*
X1048533Y496500D01*
X1046283D01*
Y491500D01*
X1049033D01*
X1049617Y491833D01*
X1049950Y492333D01*
X1050117Y492917D01*
X1049950Y493500D01*
X1049450Y494000D01*
X1048867Y494167D01*
X1046283D01*
G01X1053800Y491500D02*
X1053300Y491583D01*
X1052800Y491917D01*
X1052467Y492500D01*
X1052300Y493167D01*
X1052467Y493833D01*
X1052800Y494417D01*
X1053300Y494750D01*
X1053800Y494833D01*
X1054300Y494750D01*
X1054800Y494417D01*
X1055133Y493833D01*
X1055217Y493167D01*
X1055133Y492500D01*
X1054800Y491917D01*
X1054300Y491583D01*
X1053800Y491500D01*
G01X1060900D02*
Y494833D01*
G01Y494250D02*
X1060567Y494583D01*
X1060067Y494750D01*
X1059483Y494833D01*
X1058900Y494667D01*
X1058400Y494333D01*
X1058067Y493833D01*
X1057900Y493167D01*
X1058067Y492500D01*
X1058400Y492000D01*
X1058900Y491667D01*
X1059483Y491500D01*
X1060067Y491583D01*
X1060567Y491833D01*
X1060900Y492167D01*
G01X1063833Y491500D02*
Y494833D01*
G01Y494167D02*
X1064250Y494500D01*
X1064667Y494750D01*
X1065250Y494833D01*
X1065667Y494750D01*
X1066167Y494500D01*
G01X1072100Y496500D02*
Y491500D01*
G01Y492250D02*
X1071767Y491833D01*
X1071267Y491583D01*
X1070683Y491500D01*
X1070017Y491667D01*
X1069517Y492083D01*
X1069183Y492583D01*
X1069100Y493167D01*
X1069183Y493750D01*
X1069517Y494250D01*
X1070017Y494667D01*
X1070683Y494833D01*
X1071267Y494750D01*
X1071683Y494583D01*
X1072100Y494250D01*
G01X1081800Y496500D02*
Y491500D01*
G01X1080633Y494833D02*
X1082967D01*
G01X1085983Y491500D02*
Y496500D01*
G01Y494083D02*
X1086400Y494500D01*
X1086817Y494750D01*
X1087483Y494833D01*
X1087983Y494750D01*
X1088567Y494417D01*
X1088817Y493917D01*
Y491500D01*
G01X1093000Y494833D02*
Y491500D01*
G01Y496167D02*
X1092833Y496250D01*
Y496417D01*
X1093000Y496500D01*
X1093167Y496417D01*
Y496250D01*
X1093000Y496167D01*
G01X1099933Y494417D02*
X1099350Y494750D01*
X1098850Y494833D01*
X1098183Y494667D01*
X1097683Y494333D01*
X1097350Y493750D01*
X1097267Y493167D01*
X1097350Y492583D01*
X1097683Y492083D01*
X1098183Y491667D01*
X1098850Y491500D01*
X1099433Y491667D01*
X1099933Y492000D01*
G01X1102783Y491500D02*
Y496500D01*
G01X1105450Y494833D02*
X1102783Y492917D01*
G01X1103867Y493667D02*
X1105617Y491500D01*
G01X1108383D02*
Y494833D01*
G01Y494000D02*
X1108717Y494417D01*
X1109217Y494750D01*
X1109883Y494833D01*
X1110467Y494750D01*
X1110967Y494417D01*
X1111217Y493833D01*
Y491500D01*
G01X1114150Y493750D02*
X1116817D01*
X1116567Y494333D01*
X1116150Y494667D01*
X1115567Y494833D01*
X1114983Y494750D01*
X1114483Y494500D01*
X1114150Y493917D01*
X1113983Y493417D01*
Y492917D01*
X1114150Y492417D01*
X1114567Y491917D01*
X1115067Y491583D01*
X1115650Y491500D01*
X1116233Y491667D01*
X1116817Y492167D01*
G01X1119750Y492083D02*
X1120167Y491750D01*
X1120750Y491500D01*
X1121250D01*
X1121750Y491667D01*
X1122083Y491917D01*
X1122250Y492250D01*
X1122167Y492750D01*
X1121833Y493000D01*
X1120333Y493500D01*
X1120000Y494083D01*
X1120167Y494500D01*
X1120500Y494750D01*
X1121000Y494833D01*
X1121500Y494750D01*
X1122000Y494500D01*
G01X1125350Y492083D02*
X1125767Y491750D01*
X1126350Y491500D01*
X1126850D01*
X1127350Y491667D01*
X1127683Y491917D01*
X1127850Y492250D01*
X1127767Y492750D01*
X1127433Y493000D01*
X1125933Y493500D01*
X1125600Y494083D01*
X1125767Y494500D01*
X1126100Y494750D01*
X1126600Y494833D01*
X1127100Y494750D01*
X1127600Y494500D01*
G01X1139467Y491500D02*
X1136133Y493167D01*
X1139467Y494833D01*
G01X1149000Y496500D02*
X1148333Y496333D01*
X1147833Y495917D01*
X1147500Y495417D01*
X1147250Y494750D01*
X1147167Y494000D01*
X1147250Y493250D01*
X1147500Y492583D01*
X1147833Y492083D01*
X1148333Y491667D01*
X1149000Y491500D01*
X1149667Y491667D01*
X1150167Y492083D01*
X1150500Y492583D01*
X1150750Y493250D01*
X1150833Y494000D01*
X1150750Y494750D01*
X1150500Y495417D01*
X1150167Y495917D01*
X1149667Y496333D01*
X1149000Y496500D01*
G01X1154600Y491333D02*
X1154433Y491417D01*
Y491583D01*
X1154600Y491667D01*
X1154767Y491583D01*
Y491417D01*
X1154600Y491333D01*
G01X1158783Y492083D02*
X1159367Y491667D01*
X1160033Y491500D01*
X1160700Y491667D01*
X1161283Y492167D01*
X1161700Y492917D01*
X1161867Y493667D01*
Y494583D01*
X1161700Y495333D01*
X1161283Y496000D01*
X1160783Y496333D01*
X1160200Y496500D01*
X1159533Y496333D01*
X1159033Y496000D01*
X1158700Y495500D01*
X1158533Y494833D01*
X1158700Y494250D01*
X1159117Y493667D01*
X1159617Y493333D01*
X1160200Y493250D01*
X1160867Y493417D01*
X1161367Y493833D01*
X1161867Y494583D01*
G01X1163300Y491500D02*
Y494833D01*
G01Y493917D02*
X1163550Y494333D01*
X1163967Y494667D01*
X1164550Y494833D01*
X1165133Y494667D01*
X1165550Y494333D01*
X1165800Y493917D01*
Y491500D01*
G01Y493917D02*
X1166050Y494333D01*
X1166467Y494667D01*
X1167050Y494833D01*
X1167633Y494667D01*
X1168050Y494333D01*
X1168300Y493833D01*
Y491500D01*
G01X1168900D02*
Y494833D01*
G01Y493917D02*
X1169150Y494333D01*
X1169567Y494667D01*
X1170150Y494833D01*
X1170733Y494667D01*
X1171150Y494333D01*
X1171400Y493917D01*
Y491500D01*
G01Y493917D02*
X1171650Y494333D01*
X1172067Y494667D01*
X1172650Y494833D01*
X1173233Y494667D01*
X1173650Y494333D01*
X1173900Y493833D01*
Y491500D01*
G01X1177000Y491333D02*
X1176833Y491417D01*
Y491583D01*
X1177000Y491667D01*
X1177167Y491583D01*
Y491417D01*
X1177000Y491333D01*
G01Y493583D02*
X1176833Y493667D01*
Y493833D01*
X1177000Y493917D01*
X1177167Y493833D01*
Y493667D01*
X1177000Y493583D01*
G01X1038500Y510500D02*
Y513833D01*
G01Y513250D02*
X1038167Y513583D01*
X1037667Y513750D01*
X1037083Y513833D01*
X1036500Y513667D01*
X1036000Y513333D01*
X1035667Y512833D01*
X1035500Y512167D01*
X1035667Y511500D01*
X1036000Y511000D01*
X1036500Y510667D01*
X1037083Y510500D01*
X1037667Y510583D01*
X1038167Y510833D01*
X1038500Y511167D01*
G01X1042600Y510333D02*
X1042433Y510417D01*
Y510583D01*
X1042600Y510667D01*
X1042767Y510583D01*
Y510417D01*
X1042600Y510333D01*
G01X1048867Y513167D02*
X1049200Y513417D01*
X1049450Y513833D01*
X1049617Y514417D01*
X1049450Y514917D01*
X1049117Y515250D01*
X1048533Y515500D01*
X1046283D01*
Y510500D01*
X1049033D01*
X1049617Y510833D01*
X1049950Y511333D01*
X1050117Y511917D01*
X1049950Y512500D01*
X1049450Y513000D01*
X1048867Y513167D01*
X1046283D01*
G01X1053800Y510500D02*
X1053300Y510583D01*
X1052800Y510917D01*
X1052467Y511500D01*
X1052300Y512167D01*
X1052467Y512833D01*
X1052800Y513417D01*
X1053300Y513750D01*
X1053800Y513833D01*
X1054300Y513750D01*
X1054800Y513417D01*
X1055133Y512833D01*
X1055217Y512167D01*
X1055133Y511500D01*
X1054800Y510917D01*
X1054300Y510583D01*
X1053800Y510500D01*
G01X1060900D02*
Y513833D01*
G01Y513250D02*
X1060567Y513583D01*
X1060067Y513750D01*
X1059483Y513833D01*
X1058900Y513667D01*
X1058400Y513333D01*
X1058067Y512833D01*
X1057900Y512167D01*
X1058067Y511500D01*
X1058400Y511000D01*
X1058900Y510667D01*
X1059483Y510500D01*
X1060067Y510583D01*
X1060567Y510833D01*
X1060900Y511167D01*
G01X1063833Y510500D02*
Y513833D01*
G01Y513167D02*
X1064250Y513500D01*
X1064667Y513750D01*
X1065250Y513833D01*
X1065667Y513750D01*
X1066167Y513500D01*
G01X1072100Y515500D02*
Y510500D01*
G01Y511250D02*
X1071767Y510833D01*
X1071267Y510583D01*
X1070683Y510500D01*
X1070017Y510667D01*
X1069517Y511083D01*
X1069183Y511583D01*
X1069100Y512167D01*
X1069183Y512750D01*
X1069517Y513250D01*
X1070017Y513667D01*
X1070683Y513833D01*
X1071267Y513750D01*
X1071683Y513583D01*
X1072100Y513250D01*
G01X1081800Y515500D02*
Y510500D01*
G01X1080633Y513833D02*
X1082967D01*
G01X1085983Y510500D02*
Y515500D01*
G01Y513083D02*
X1086400Y513500D01*
X1086817Y513750D01*
X1087483Y513833D01*
X1087983Y513750D01*
X1088567Y513417D01*
X1088817Y512917D01*
Y510500D01*
G01X1093000Y513833D02*
Y510500D01*
G01Y515167D02*
X1092833Y515250D01*
Y515417D01*
X1093000Y515500D01*
X1093167Y515417D01*
Y515250D01*
X1093000Y515167D01*
G01X1099933Y513417D02*
X1099350Y513750D01*
X1098850Y513833D01*
X1098183Y513667D01*
X1097683Y513333D01*
X1097350Y512750D01*
X1097267Y512167D01*
X1097350Y511583D01*
X1097683Y511083D01*
X1098183Y510667D01*
X1098850Y510500D01*
X1099433Y510667D01*
X1099933Y511000D01*
G01X1102783Y510500D02*
Y515500D01*
G01X1105450Y513833D02*
X1102783Y511917D01*
G01X1103867Y512667D02*
X1105617Y510500D01*
G01X1108383D02*
Y513833D01*
G01Y513000D02*
X1108717Y513417D01*
X1109217Y513750D01*
X1109883Y513833D01*
X1110467Y513750D01*
X1110967Y513417D01*
X1111217Y512833D01*
Y510500D01*
G01X1114150Y512750D02*
X1116817D01*
X1116567Y513333D01*
X1116150Y513667D01*
X1115567Y513833D01*
X1114983Y513750D01*
X1114483Y513500D01*
X1114150Y512917D01*
X1113983Y512417D01*
Y511917D01*
X1114150Y511417D01*
X1114567Y510917D01*
X1115067Y510583D01*
X1115650Y510500D01*
X1116233Y510667D01*
X1116817Y511167D01*
G01X1119750Y511083D02*
X1120167Y510750D01*
X1120750Y510500D01*
X1121250D01*
X1121750Y510667D01*
X1122083Y510917D01*
X1122250Y511250D01*
X1122167Y511750D01*
X1121833Y512000D01*
X1120333Y512500D01*
X1120000Y513083D01*
X1120167Y513500D01*
X1120500Y513750D01*
X1121000Y513833D01*
X1121500Y513750D01*
X1122000Y513500D01*
G01X1125350Y511083D02*
X1125767Y510750D01*
X1126350Y510500D01*
X1126850D01*
X1127350Y510667D01*
X1127683Y510917D01*
X1127850Y511250D01*
X1127767Y511750D01*
X1127433Y512000D01*
X1125933Y512500D01*
X1125600Y513083D01*
X1125767Y513500D01*
X1126100Y513750D01*
X1126600Y513833D01*
X1127100Y513750D01*
X1127600Y513500D01*
G01X1130533Y510500D02*
X1133867Y512167D01*
X1130533Y513833D01*
G01X1136717Y511417D02*
X1138883D01*
G01Y512917D02*
X1136717D01*
G01X1149000Y515500D02*
X1148333Y515333D01*
X1147833Y514917D01*
X1147500Y514417D01*
X1147250Y513750D01*
X1147167Y513000D01*
X1147250Y512250D01*
X1147500Y511583D01*
X1147833Y511083D01*
X1148333Y510667D01*
X1149000Y510500D01*
X1149667Y510667D01*
X1150167Y511083D01*
X1150500Y511583D01*
X1150750Y512250D01*
X1150833Y513000D01*
X1150750Y513750D01*
X1150500Y514417D01*
X1150167Y514917D01*
X1149667Y515333D01*
X1149000Y515500D01*
G01X1154600Y510333D02*
X1154433Y510417D01*
Y510583D01*
X1154600Y510667D01*
X1154767Y510583D01*
Y510417D01*
X1154600Y510333D01*
G01X1158783Y511083D02*
X1159367Y510667D01*
X1160033Y510500D01*
X1160700Y510667D01*
X1161283Y511167D01*
X1161700Y511917D01*
X1161867Y512667D01*
Y513583D01*
X1161700Y514333D01*
X1161283Y515000D01*
X1160783Y515333D01*
X1160200Y515500D01*
X1159533Y515333D01*
X1159033Y515000D01*
X1158700Y514500D01*
X1158533Y513833D01*
X1158700Y513250D01*
X1159117Y512667D01*
X1159617Y512333D01*
X1160200Y512250D01*
X1160867Y512417D01*
X1161367Y512833D01*
X1161867Y513583D01*
G01X1163300Y510500D02*
Y513833D01*
G01Y512917D02*
X1163550Y513333D01*
X1163967Y513667D01*
X1164550Y513833D01*
X1165133Y513667D01*
X1165550Y513333D01*
X1165800Y512917D01*
Y510500D01*
G01Y512917D02*
X1166050Y513333D01*
X1166467Y513667D01*
X1167050Y513833D01*
X1167633Y513667D01*
X1168050Y513333D01*
X1168300Y512833D01*
Y510500D01*
G01X1171400Y510333D02*
X1171233Y510417D01*
Y510583D01*
X1171400Y510667D01*
X1171567Y510583D01*
Y510417D01*
X1171400Y510333D01*
G01Y512583D02*
X1171233Y512667D01*
Y512833D01*
X1171400Y512917D01*
X1171567Y512833D01*
Y512667D01*
X1171400Y512583D01*
G01X1034250Y520500D02*
Y525500D01*
G01X1037750D02*
Y520500D01*
G01Y523000D02*
X1034250D01*
G01X1043100Y520500D02*
Y523833D01*
G01Y523250D02*
X1042767Y523583D01*
X1042267Y523750D01*
X1041683Y523833D01*
X1041100Y523667D01*
X1040600Y523333D01*
X1040267Y522833D01*
X1040100Y522167D01*
X1040267Y521500D01*
X1040600Y521000D01*
X1041100Y520667D01*
X1041683Y520500D01*
X1042267Y520583D01*
X1042767Y520833D01*
X1043100Y521167D01*
G01X1047200Y520500D02*
Y525500D01*
G01X1052300Y520500D02*
Y524750D01*
X1052467Y525167D01*
X1052800Y525417D01*
X1053300Y525500D01*
X1053800Y525333D01*
X1054050Y524917D01*
G01X1053050Y523500D02*
X1051383D01*
G01X1057317Y522167D02*
X1059483D01*
G01X1062500Y518833D02*
Y523833D01*
G01Y523083D02*
X1062917Y523500D01*
X1063333Y523750D01*
X1064000Y523833D01*
X1064583Y523750D01*
X1065167Y523333D01*
X1065417Y522750D01*
X1065500Y522167D01*
X1065417Y521583D01*
X1065167Y521000D01*
X1064667Y520667D01*
X1064000Y520500D01*
X1063417Y520583D01*
X1062833Y520833D01*
X1062500Y521167D01*
G01X1069600Y520500D02*
Y525500D01*
G01X1073783Y523833D02*
Y521500D01*
X1074117Y520917D01*
X1074617Y520583D01*
X1075200Y520500D01*
X1075783Y520583D01*
X1076283Y520917D01*
X1076617Y521500D01*
G01Y520500D02*
Y523833D01*
G01X1079633Y519250D02*
X1080217Y518917D01*
X1080883Y518833D01*
X1081467Y518917D01*
X1081967Y519333D01*
X1082300Y519917D01*
Y523833D01*
G01Y523167D02*
X1081967Y523500D01*
X1081467Y523750D01*
X1080883Y523833D01*
X1080217Y523667D01*
X1079800Y523333D01*
X1079467Y522750D01*
X1079300Y522167D01*
X1079383Y521667D01*
X1079717Y521083D01*
X1080217Y520667D01*
X1080883Y520500D01*
X1081383Y520583D01*
X1081967Y520917D01*
X1082300Y521250D01*
G01X1085233Y519250D02*
X1085817Y518917D01*
X1086483Y518833D01*
X1087067Y518917D01*
X1087567Y519333D01*
X1087900Y519917D01*
Y523833D01*
G01Y523167D02*
X1087567Y523500D01*
X1087067Y523750D01*
X1086483Y523833D01*
X1085817Y523667D01*
X1085400Y523333D01*
X1085067Y522750D01*
X1084900Y522167D01*
X1084983Y521667D01*
X1085317Y521083D01*
X1085817Y520667D01*
X1086483Y520500D01*
X1086983Y520583D01*
X1087567Y520917D01*
X1087900Y521250D01*
G01X1092000Y523833D02*
Y520500D01*
G01Y525167D02*
X1091833Y525250D01*
Y525417D01*
X1092000Y525500D01*
X1092167Y525417D01*
Y525250D01*
X1092000Y525167D01*
G01X1096183Y520500D02*
Y523833D01*
G01Y523000D02*
X1096517Y523417D01*
X1097017Y523750D01*
X1097683Y523833D01*
X1098267Y523750D01*
X1098767Y523417D01*
X1099017Y522833D01*
Y520500D01*
G01X1102033Y519250D02*
X1102617Y518917D01*
X1103283Y518833D01*
X1103867Y518917D01*
X1104367Y519333D01*
X1104700Y519917D01*
Y523833D01*
G01Y523167D02*
X1104367Y523500D01*
X1103867Y523750D01*
X1103283Y523833D01*
X1102617Y523667D01*
X1102200Y523333D01*
X1101867Y522750D01*
X1101700Y522167D01*
X1101783Y521667D01*
X1102117Y521083D01*
X1102617Y520667D01*
X1103283Y520500D01*
X1103783Y520583D01*
X1104367Y520917D01*
X1104700Y521250D01*
G01X1114400Y520333D02*
X1114233Y520417D01*
Y520583D01*
X1114400Y520667D01*
X1114567Y520583D01*
Y520417D01*
X1114400Y520333D01*
G01Y522583D02*
X1114233Y522667D01*
Y522833D01*
X1114400Y522917D01*
X1114567Y522833D01*
Y522667D01*
X1114400Y522583D01*
G01X1125600Y525500D02*
Y520500D01*
G01X1124433Y523833D02*
X1126767D01*
G01X1129783Y520500D02*
Y525500D01*
G01Y523083D02*
X1130200Y523500D01*
X1130617Y523750D01*
X1131283Y523833D01*
X1131783Y523750D01*
X1132367Y523417D01*
X1132617Y522917D01*
Y520500D01*
G01X1135550Y522750D02*
X1138217D01*
X1137967Y523333D01*
X1137550Y523667D01*
X1136967Y523833D01*
X1136383Y523750D01*
X1135883Y523500D01*
X1135550Y522917D01*
X1135383Y522417D01*
Y521917D01*
X1135550Y521417D01*
X1135967Y520917D01*
X1136467Y520583D01*
X1137050Y520500D01*
X1137633Y520667D01*
X1138217Y521167D01*
G01X1146500Y518833D02*
Y523833D01*
G01Y523083D02*
X1146917Y523500D01*
X1147333Y523750D01*
X1148000Y523833D01*
X1148583Y523750D01*
X1149167Y523333D01*
X1149417Y522750D01*
X1149500Y522167D01*
X1149417Y521583D01*
X1149167Y521000D01*
X1148667Y520667D01*
X1148000Y520500D01*
X1147417Y520583D01*
X1146833Y520833D01*
X1146500Y521167D01*
G01X1153600Y520500D02*
Y525500D01*
G01X1157783Y523833D02*
Y521500D01*
X1158117Y520917D01*
X1158617Y520583D01*
X1159200Y520500D01*
X1159783Y520583D01*
X1160283Y520917D01*
X1160617Y521500D01*
G01Y520500D02*
Y523833D01*
G01X1163633Y519250D02*
X1164217Y518917D01*
X1164883Y518833D01*
X1165467Y518917D01*
X1165967Y519333D01*
X1166300Y519917D01*
Y523833D01*
G01Y523167D02*
X1165967Y523500D01*
X1165467Y523750D01*
X1164883Y523833D01*
X1164217Y523667D01*
X1163800Y523333D01*
X1163467Y522750D01*
X1163300Y522167D01*
X1163383Y521667D01*
X1163717Y521083D01*
X1164217Y520667D01*
X1164883Y520500D01*
X1165383Y520583D01*
X1165967Y520917D01*
X1166300Y521250D01*
G01X1169233Y519250D02*
X1169817Y518917D01*
X1170483Y518833D01*
X1171067Y518917D01*
X1171567Y519333D01*
X1171900Y519917D01*
Y523833D01*
G01Y523167D02*
X1171567Y523500D01*
X1171067Y523750D01*
X1170483Y523833D01*
X1169817Y523667D01*
X1169400Y523333D01*
X1169067Y522750D01*
X1168900Y522167D01*
X1168983Y521667D01*
X1169317Y521083D01*
X1169817Y520667D01*
X1170483Y520500D01*
X1170983Y520583D01*
X1171567Y520917D01*
X1171900Y521250D01*
G01X1176000Y523833D02*
Y520500D01*
G01Y525167D02*
X1175833Y525250D01*
Y525417D01*
X1176000Y525500D01*
X1176167Y525417D01*
Y525250D01*
X1176000Y525167D01*
G01X1180183Y520500D02*
Y523833D01*
G01Y523000D02*
X1180517Y523417D01*
X1181017Y523750D01*
X1181683Y523833D01*
X1182267Y523750D01*
X1182767Y523417D01*
X1183017Y522833D01*
Y520500D01*
G01X1186033Y519250D02*
X1186617Y518917D01*
X1187283Y518833D01*
X1187867Y518917D01*
X1188367Y519333D01*
X1188700Y519917D01*
Y523833D01*
G01Y523167D02*
X1188367Y523500D01*
X1187867Y523750D01*
X1187283Y523833D01*
X1186617Y523667D01*
X1186200Y523333D01*
X1185867Y522750D01*
X1185700Y522167D01*
X1185783Y521667D01*
X1186117Y521083D01*
X1186617Y520667D01*
X1187283Y520500D01*
X1187783Y520583D01*
X1188367Y520917D01*
X1188700Y521250D01*
G01X1197233Y520500D02*
Y523833D01*
G01Y523167D02*
X1197650Y523500D01*
X1198067Y523750D01*
X1198650Y523833D01*
X1199067Y523750D01*
X1199567Y523500D01*
G01X1205500Y520500D02*
Y523833D01*
G01Y523250D02*
X1205167Y523583D01*
X1204667Y523750D01*
X1204083Y523833D01*
X1203500Y523667D01*
X1203000Y523333D01*
X1202667Y522833D01*
X1202500Y522167D01*
X1202667Y521500D01*
X1203000Y521000D01*
X1203500Y520667D01*
X1204083Y520500D01*
X1204667Y520583D01*
X1205167Y520833D01*
X1205500Y521167D01*
G01X1209600Y525500D02*
Y520500D01*
G01X1208433Y523833D02*
X1210767D01*
G01X1215200D02*
Y520500D01*
G01Y525167D02*
X1215033Y525250D01*
Y525417D01*
X1215200Y525500D01*
X1215367Y525417D01*
Y525250D01*
X1215200Y525167D01*
G01X1220800Y520500D02*
X1220300Y520583D01*
X1219800Y520917D01*
X1219467Y521500D01*
X1219300Y522167D01*
X1219467Y522833D01*
X1219800Y523417D01*
X1220300Y523750D01*
X1220800Y523833D01*
X1221300Y523750D01*
X1221800Y523417D01*
X1222133Y522833D01*
X1222217Y522167D01*
X1222133Y521500D01*
X1221800Y520917D01*
X1221300Y520583D01*
X1220800Y520500D01*
G01X1230500Y518833D02*
Y523833D01*
G01Y523083D02*
X1230917Y523500D01*
X1231333Y523750D01*
X1232000Y523833D01*
X1232583Y523750D01*
X1233167Y523333D01*
X1233417Y522750D01*
X1233500Y522167D01*
X1233417Y521583D01*
X1233167Y521000D01*
X1232667Y520667D01*
X1232000Y520500D01*
X1231417Y520583D01*
X1230833Y520833D01*
X1230500Y521167D01*
G01X1236350Y522750D02*
X1239017D01*
X1238767Y523333D01*
X1238350Y523667D01*
X1237767Y523833D01*
X1237183Y523750D01*
X1236683Y523500D01*
X1236350Y522917D01*
X1236183Y522417D01*
Y521917D01*
X1236350Y521417D01*
X1236767Y520917D01*
X1237267Y520583D01*
X1237850Y520500D01*
X1238433Y520667D01*
X1239017Y521167D01*
G01X1242033Y520500D02*
Y523833D01*
G01Y523167D02*
X1242450Y523500D01*
X1242867Y523750D01*
X1243450Y523833D01*
X1243867Y523750D01*
X1244367Y523500D01*
G01X1253900Y520500D02*
Y524750D01*
X1254067Y525167D01*
X1254400Y525417D01*
X1254900Y525500D01*
X1255400Y525333D01*
X1255650Y524917D01*
G01X1254650Y523500D02*
X1252983D01*
G01X1260000Y520500D02*
X1259500Y520583D01*
X1259000Y520917D01*
X1258667Y521500D01*
X1258500Y522167D01*
X1258667Y522833D01*
X1259000Y523417D01*
X1259500Y523750D01*
X1260000Y523833D01*
X1260500Y523750D01*
X1261000Y523417D01*
X1261333Y522833D01*
X1261417Y522167D01*
X1261333Y521500D01*
X1261000Y520917D01*
X1260500Y520583D01*
X1260000Y520500D01*
G01X1265600D02*
Y525500D01*
G01X1271200Y520500D02*
Y525500D01*
G01X1276800Y520500D02*
X1276300Y520583D01*
X1275800Y520917D01*
X1275467Y521500D01*
X1275300Y522167D01*
X1275467Y522833D01*
X1275800Y523417D01*
X1276300Y523750D01*
X1276800Y523833D01*
X1277300Y523750D01*
X1277800Y523417D01*
X1278133Y522833D01*
X1278217Y522167D01*
X1278133Y521500D01*
X1277800Y520917D01*
X1277300Y520583D01*
X1276800Y520500D01*
G01X1280317Y523833D02*
X1281317Y520500D01*
X1282400Y523833D01*
X1283483Y520500D01*
X1284483Y523833D01*
G01X1288000D02*
Y520500D01*
G01Y525167D02*
X1287833Y525250D01*
Y525417D01*
X1288000Y525500D01*
X1288167Y525417D01*
Y525250D01*
X1288000Y525167D01*
G01X1292183Y520500D02*
Y523833D01*
G01Y523000D02*
X1292517Y523417D01*
X1293017Y523750D01*
X1293683Y523833D01*
X1294267Y523750D01*
X1294767Y523417D01*
X1295017Y522833D01*
Y520500D01*
G01X1298033Y519250D02*
X1298617Y518917D01*
X1299283Y518833D01*
X1299867Y518917D01*
X1300367Y519333D01*
X1300700Y519917D01*
Y523833D01*
G01Y523167D02*
X1300367Y523500D01*
X1299867Y523750D01*
X1299283Y523833D01*
X1298617Y523667D01*
X1298200Y523333D01*
X1297867Y522750D01*
X1297700Y522167D01*
X1297783Y521667D01*
X1298117Y521083D01*
X1298617Y520667D01*
X1299283Y520500D01*
X1299783Y520583D01*
X1300367Y520917D01*
X1300700Y521250D01*
G01X1304800Y520333D02*
X1304633Y520417D01*
Y520583D01*
X1304800Y520667D01*
X1304967Y520583D01*
Y520417D01*
X1304800Y520333D01*
G01Y522583D02*
X1304633Y522667D01*
Y522833D01*
X1304800Y522917D01*
X1304967Y522833D01*
Y522667D01*
X1304800Y522583D01*
G01X1033500Y529500D02*
Y534500D01*
G01Y532000D02*
X1033917Y532500D01*
X1034417Y532750D01*
X1034917Y532833D01*
X1035667Y532667D01*
X1036167Y532333D01*
X1036500Y531750D01*
Y531083D01*
X1036333Y530417D01*
X1036000Y529917D01*
X1035417Y529583D01*
X1034917Y529500D01*
X1034417Y529583D01*
X1033917Y529833D01*
X1033500Y530250D01*
G01X1039350Y531750D02*
X1042017D01*
X1041767Y532333D01*
X1041350Y532667D01*
X1040767Y532833D01*
X1040183Y532750D01*
X1039683Y532500D01*
X1039350Y531917D01*
X1039183Y531417D01*
Y530917D01*
X1039350Y530417D01*
X1039767Y529917D01*
X1040267Y529583D01*
X1040850Y529500D01*
X1041433Y529667D01*
X1042017Y530167D01*
G01X1051300Y529500D02*
Y533750D01*
X1051467Y534167D01*
X1051800Y534417D01*
X1052300Y534500D01*
X1052800Y534333D01*
X1053050Y533917D01*
G01X1052050Y532500D02*
X1050383D01*
G01X1056233Y529500D02*
Y532833D01*
G01Y532167D02*
X1056650Y532500D01*
X1057067Y532750D01*
X1057650Y532833D01*
X1058067Y532750D01*
X1058567Y532500D01*
G01X1061750Y531750D02*
X1064417D01*
X1064167Y532333D01*
X1063750Y532667D01*
X1063167Y532833D01*
X1062583Y532750D01*
X1062083Y532500D01*
X1061750Y531917D01*
X1061583Y531417D01*
Y530917D01*
X1061750Y530417D01*
X1062167Y529917D01*
X1062667Y529583D01*
X1063250Y529500D01*
X1063833Y529667D01*
X1064417Y530167D01*
G01X1067350Y531750D02*
X1070017D01*
X1069767Y532333D01*
X1069350Y532667D01*
X1068767Y532833D01*
X1068183Y532750D01*
X1067683Y532500D01*
X1067350Y531917D01*
X1067183Y531417D01*
Y530917D01*
X1067350Y530417D01*
X1067767Y529917D01*
X1068267Y529583D01*
X1068850Y529500D01*
X1069433Y529667D01*
X1070017Y530167D01*
G01X1079300Y529500D02*
Y533750D01*
X1079467Y534167D01*
X1079800Y534417D01*
X1080300Y534500D01*
X1080800Y534333D01*
X1081050Y533917D01*
G01X1080050Y532500D02*
X1078383D01*
G01X1084233Y529500D02*
Y532833D01*
G01Y532167D02*
X1084650Y532500D01*
X1085067Y532750D01*
X1085650Y532833D01*
X1086067Y532750D01*
X1086567Y532500D01*
G01X1091000Y529500D02*
X1090500Y529583D01*
X1090000Y529917D01*
X1089667Y530500D01*
X1089500Y531167D01*
X1089667Y531833D01*
X1090000Y532417D01*
X1090500Y532750D01*
X1091000Y532833D01*
X1091500Y532750D01*
X1092000Y532417D01*
X1092333Y531833D01*
X1092417Y531167D01*
X1092333Y530500D01*
X1092000Y529917D01*
X1091500Y529583D01*
X1091000Y529500D01*
G01X1094100D02*
Y532833D01*
G01Y531917D02*
X1094350Y532333D01*
X1094767Y532667D01*
X1095350Y532833D01*
X1095933Y532667D01*
X1096350Y532333D01*
X1096600Y531917D01*
Y529500D01*
G01Y531917D02*
X1096850Y532333D01*
X1097267Y532667D01*
X1097850Y532833D01*
X1098433Y532667D01*
X1098850Y532333D01*
X1099100Y531833D01*
Y529500D01*
G01X1106550Y530083D02*
X1106967Y529750D01*
X1107550Y529500D01*
X1108050D01*
X1108550Y529667D01*
X1108883Y529917D01*
X1109050Y530250D01*
X1108967Y530750D01*
X1108633Y531000D01*
X1107133Y531500D01*
X1106800Y532083D01*
X1106967Y532500D01*
X1107300Y532750D01*
X1107800Y532833D01*
X1108300Y532750D01*
X1108800Y532500D01*
G01X1113400Y529500D02*
X1112900Y529583D01*
X1112400Y529917D01*
X1112067Y530500D01*
X1111900Y531167D01*
X1112067Y531833D01*
X1112400Y532417D01*
X1112900Y532750D01*
X1113400Y532833D01*
X1113900Y532750D01*
X1114400Y532417D01*
X1114733Y531833D01*
X1114817Y531167D01*
X1114733Y530500D01*
X1114400Y529917D01*
X1113900Y529583D01*
X1113400Y529500D01*
G01X1119000D02*
Y534500D01*
G01X1126100D02*
Y529500D01*
G01Y530250D02*
X1125767Y529833D01*
X1125267Y529583D01*
X1124683Y529500D01*
X1124017Y529667D01*
X1123517Y530083D01*
X1123183Y530583D01*
X1123100Y531167D01*
X1123183Y531750D01*
X1123517Y532250D01*
X1124017Y532667D01*
X1124683Y532833D01*
X1125267Y532750D01*
X1125683Y532583D01*
X1126100Y532250D01*
G01X1128950Y531750D02*
X1131617D01*
X1131367Y532333D01*
X1130950Y532667D01*
X1130367Y532833D01*
X1129783Y532750D01*
X1129283Y532500D01*
X1128950Y531917D01*
X1128783Y531417D01*
Y530917D01*
X1128950Y530417D01*
X1129367Y529917D01*
X1129867Y529583D01*
X1130450Y529500D01*
X1131033Y529667D01*
X1131617Y530167D01*
G01X1134633Y529500D02*
Y532833D01*
G01Y532167D02*
X1135050Y532500D01*
X1135467Y532750D01*
X1136050Y532833D01*
X1136467Y532750D01*
X1136967Y532500D01*
G01X1144500Y529500D02*
Y532833D01*
G01Y531917D02*
X1144750Y532333D01*
X1145167Y532667D01*
X1145750Y532833D01*
X1146333Y532667D01*
X1146750Y532333D01*
X1147000Y531917D01*
Y529500D01*
G01Y531917D02*
X1147250Y532333D01*
X1147667Y532667D01*
X1148250Y532833D01*
X1148833Y532667D01*
X1149250Y532333D01*
X1149500Y531833D01*
Y529500D01*
G01X1154100D02*
Y532833D01*
G01Y532250D02*
X1153767Y532583D01*
X1153267Y532750D01*
X1152683Y532833D01*
X1152100Y532667D01*
X1151600Y532333D01*
X1151267Y531833D01*
X1151100Y531167D01*
X1151267Y530500D01*
X1151600Y530000D01*
X1152100Y529667D01*
X1152683Y529500D01*
X1153267Y529583D01*
X1153767Y529833D01*
X1154100Y530167D01*
G01X1156950Y530083D02*
X1157367Y529750D01*
X1157950Y529500D01*
X1158450D01*
X1158950Y529667D01*
X1159283Y529917D01*
X1159450Y530250D01*
X1159367Y530750D01*
X1159033Y531000D01*
X1157533Y531500D01*
X1157200Y532083D01*
X1157367Y532500D01*
X1157700Y532750D01*
X1158200Y532833D01*
X1158700Y532750D01*
X1159200Y532500D01*
G01X1162383Y529500D02*
Y534500D01*
G01X1165050Y532833D02*
X1162383Y530917D01*
G01X1163467Y531667D02*
X1165217Y529500D01*
G01X1169400Y529333D02*
X1169233Y529417D01*
Y529583D01*
X1169400Y529667D01*
X1169567Y529583D01*
Y529417D01*
X1169400Y529333D01*
G01X1020417Y542667D02*
X1020917Y543167D01*
X1021500Y543417D01*
X1022167Y543500D01*
X1023000Y543333D01*
X1023583Y542917D01*
X1023750Y542417D01*
X1023667Y541917D01*
X1023333Y541500D01*
X1021667Y540667D01*
X1020917Y540083D01*
X1020417Y539250D01*
X1020250Y538500D01*
X1023750D01*
G01X1027600Y538333D02*
X1027433Y538417D01*
Y538583D01*
X1027600Y538667D01*
X1027767Y538583D01*
Y538417D01*
X1027600Y538333D01*
G01X1033200Y543500D02*
Y538500D01*
G01X1031283Y543500D02*
X1035117D01*
G01X1037383Y538500D02*
Y543500D01*
G01Y541083D02*
X1037800Y541500D01*
X1038217Y541750D01*
X1038883Y541833D01*
X1039383Y541750D01*
X1039967Y541417D01*
X1040217Y540917D01*
Y538500D01*
G01X1043150Y540750D02*
X1045817D01*
X1045567Y541333D01*
X1045150Y541667D01*
X1044567Y541833D01*
X1043983Y541750D01*
X1043483Y541500D01*
X1043150Y540917D01*
X1042983Y540417D01*
Y539917D01*
X1043150Y539417D01*
X1043567Y538917D01*
X1044067Y538583D01*
X1044650Y538500D01*
X1045233Y538667D01*
X1045817Y539167D01*
G01X1054350Y539083D02*
X1054767Y538750D01*
X1055350Y538500D01*
X1055850D01*
X1056350Y538667D01*
X1056683Y538917D01*
X1056850Y539250D01*
X1056767Y539750D01*
X1056433Y540000D01*
X1054933Y540500D01*
X1054600Y541083D01*
X1054767Y541500D01*
X1055100Y541750D01*
X1055600Y541833D01*
X1056100Y541750D01*
X1056600Y541500D01*
G01X1061200Y541833D02*
Y538500D01*
G01Y543167D02*
X1061033Y543250D01*
Y543417D01*
X1061200Y543500D01*
X1061367Y543417D01*
Y543250D01*
X1061200Y543167D01*
G01X1068300Y543500D02*
Y538500D01*
G01Y539250D02*
X1067967Y538833D01*
X1067467Y538583D01*
X1066883Y538500D01*
X1066217Y538667D01*
X1065717Y539083D01*
X1065383Y539583D01*
X1065300Y540167D01*
X1065383Y540750D01*
X1065717Y541250D01*
X1066217Y541667D01*
X1066883Y541833D01*
X1067467Y541750D01*
X1067883Y541583D01*
X1068300Y541250D01*
G01X1071150Y540750D02*
X1073817D01*
X1073567Y541333D01*
X1073150Y541667D01*
X1072567Y541833D01*
X1071983Y541750D01*
X1071483Y541500D01*
X1071150Y540917D01*
X1070983Y540417D01*
Y539917D01*
X1071150Y539417D01*
X1071567Y538917D01*
X1072067Y538583D01*
X1072650Y538500D01*
X1073233Y538667D01*
X1073817Y539167D01*
G01X1081517Y541833D02*
X1082517Y538500D01*
X1083600Y541833D01*
X1084683Y538500D01*
X1085683Y541833D01*
G01X1089200D02*
Y538500D01*
G01Y543167D02*
X1089033Y543250D01*
Y543417D01*
X1089200Y543500D01*
X1089367Y543417D01*
Y543250D01*
X1089200Y543167D01*
G01X1094800Y543500D02*
Y538500D01*
G01X1093633Y541833D02*
X1095967D01*
G01X1098983Y538500D02*
Y543500D01*
G01Y541083D02*
X1099400Y541500D01*
X1099817Y541750D01*
X1100483Y541833D01*
X1100983Y541750D01*
X1101567Y541417D01*
X1101817Y540917D01*
Y538500D01*
G01X1110350Y539083D02*
X1110767Y538750D01*
X1111350Y538500D01*
X1111850D01*
X1112350Y538667D01*
X1112683Y538917D01*
X1112850Y539250D01*
X1112767Y539750D01*
X1112433Y540000D01*
X1110933Y540500D01*
X1110600Y541083D01*
X1110767Y541500D01*
X1111100Y541750D01*
X1111600Y541833D01*
X1112100Y541750D01*
X1112600Y541500D01*
G01X1117200Y538500D02*
X1116700Y538583D01*
X1116200Y538917D01*
X1115867Y539500D01*
X1115700Y540167D01*
X1115867Y540833D01*
X1116200Y541417D01*
X1116700Y541750D01*
X1117200Y541833D01*
X1117700Y541750D01*
X1118200Y541417D01*
X1118533Y540833D01*
X1118617Y540167D01*
X1118533Y539500D01*
X1118200Y538917D01*
X1117700Y538583D01*
X1117200Y538500D01*
G01X1122800D02*
Y543500D01*
G01X1129900D02*
Y538500D01*
G01Y539250D02*
X1129567Y538833D01*
X1129067Y538583D01*
X1128483Y538500D01*
X1127817Y538667D01*
X1127317Y539083D01*
X1126983Y539583D01*
X1126900Y540167D01*
X1126983Y540750D01*
X1127317Y541250D01*
X1127817Y541667D01*
X1128483Y541833D01*
X1129067Y541750D01*
X1129483Y541583D01*
X1129900Y541250D01*
G01X1132750Y540750D02*
X1135417D01*
X1135167Y541333D01*
X1134750Y541667D01*
X1134167Y541833D01*
X1133583Y541750D01*
X1133083Y541500D01*
X1132750Y540917D01*
X1132583Y540417D01*
Y539917D01*
X1132750Y539417D01*
X1133167Y538917D01*
X1133667Y538583D01*
X1134250Y538500D01*
X1134833Y538667D01*
X1135417Y539167D01*
G01X1138433Y538500D02*
Y541833D01*
G01Y541167D02*
X1138850Y541500D01*
X1139267Y541750D01*
X1139850Y541833D01*
X1140267Y541750D01*
X1140767Y541500D01*
G01X1148300Y538500D02*
Y541833D01*
G01Y540917D02*
X1148550Y541333D01*
X1148967Y541667D01*
X1149550Y541833D01*
X1150133Y541667D01*
X1150550Y541333D01*
X1150800Y540917D01*
Y538500D01*
G01Y540917D02*
X1151050Y541333D01*
X1151467Y541667D01*
X1152050Y541833D01*
X1152633Y541667D01*
X1153050Y541333D01*
X1153300Y540833D01*
Y538500D01*
G01X1157900D02*
Y541833D01*
G01Y541250D02*
X1157567Y541583D01*
X1157067Y541750D01*
X1156483Y541833D01*
X1155900Y541667D01*
X1155400Y541333D01*
X1155067Y540833D01*
X1154900Y540167D01*
X1155067Y539500D01*
X1155400Y539000D01*
X1155900Y538667D01*
X1156483Y538500D01*
X1157067Y538583D01*
X1157567Y538833D01*
X1157900Y539167D01*
G01X1160750Y539083D02*
X1161167Y538750D01*
X1161750Y538500D01*
X1162250D01*
X1162750Y538667D01*
X1163083Y538917D01*
X1163250Y539250D01*
X1163167Y539750D01*
X1162833Y540000D01*
X1161333Y540500D01*
X1161000Y541083D01*
X1161167Y541500D01*
X1161500Y541750D01*
X1162000Y541833D01*
X1162500Y541750D01*
X1163000Y541500D01*
G01X1166183Y538500D02*
Y543500D01*
G01X1168850Y541833D02*
X1166183Y539917D01*
G01X1167267Y540667D02*
X1169017Y538500D01*
G01X1177300Y536833D02*
Y541833D01*
G01Y541083D02*
X1177717Y541500D01*
X1178133Y541750D01*
X1178800Y541833D01*
X1179383Y541750D01*
X1179967Y541333D01*
X1180217Y540750D01*
X1180300Y540167D01*
X1180217Y539583D01*
X1179967Y539000D01*
X1179467Y538667D01*
X1178800Y538500D01*
X1178217Y538583D01*
X1177633Y538833D01*
X1177300Y539167D01*
G01X1185900Y538500D02*
Y541833D01*
G01Y541250D02*
X1185567Y541583D01*
X1185067Y541750D01*
X1184483Y541833D01*
X1183900Y541667D01*
X1183400Y541333D01*
X1183067Y540833D01*
X1182900Y540167D01*
X1183067Y539500D01*
X1183400Y539000D01*
X1183900Y538667D01*
X1184483Y538500D01*
X1185067Y538583D01*
X1185567Y538833D01*
X1185900Y539167D01*
G01X1191500Y543500D02*
Y538500D01*
G01Y539250D02*
X1191167Y538833D01*
X1190667Y538583D01*
X1190083Y538500D01*
X1189417Y538667D01*
X1188917Y539083D01*
X1188583Y539583D01*
X1188500Y540167D01*
X1188583Y540750D01*
X1188917Y541250D01*
X1189417Y541667D01*
X1190083Y541833D01*
X1190667Y541750D01*
X1191083Y541583D01*
X1191500Y541250D01*
G01X1195433Y537583D02*
X1195767Y538667D01*
G01X1206800Y543500D02*
Y538500D01*
G01X1205633Y541833D02*
X1207967D01*
G01X1210983Y538500D02*
Y543500D01*
G01Y541083D02*
X1211400Y541500D01*
X1211817Y541750D01*
X1212483Y541833D01*
X1212983Y541750D01*
X1213567Y541417D01*
X1213817Y540917D01*
Y538500D01*
G01X1216750Y540750D02*
X1219417D01*
X1219167Y541333D01*
X1218750Y541667D01*
X1218167Y541833D01*
X1217583Y541750D01*
X1217083Y541500D01*
X1216750Y540917D01*
X1216583Y540417D01*
Y539917D01*
X1216750Y539417D01*
X1217167Y538917D01*
X1217667Y538583D01*
X1218250Y538500D01*
X1218833Y538667D01*
X1219417Y539167D01*
G01X1230700Y538500D02*
Y541833D01*
G01Y541250D02*
X1230367Y541583D01*
X1229867Y541750D01*
X1229283Y541833D01*
X1228700Y541667D01*
X1228200Y541333D01*
X1227867Y540833D01*
X1227700Y540167D01*
X1227867Y539500D01*
X1228200Y539000D01*
X1228700Y538667D01*
X1229283Y538500D01*
X1229867Y538583D01*
X1230367Y538833D01*
X1230700Y539167D01*
G01X1233383Y538500D02*
Y541833D01*
G01Y541000D02*
X1233717Y541417D01*
X1234217Y541750D01*
X1234883Y541833D01*
X1235467Y541750D01*
X1235967Y541417D01*
X1236217Y540833D01*
Y538500D01*
G01X1238983D02*
Y541833D01*
G01Y541000D02*
X1239317Y541417D01*
X1239817Y541750D01*
X1240483Y541833D01*
X1241067Y541750D01*
X1241567Y541417D01*
X1241817Y540833D01*
Y538500D01*
G01X1244583Y541833D02*
Y539500D01*
X1244917Y538917D01*
X1245417Y538583D01*
X1246000Y538500D01*
X1246583Y538583D01*
X1247083Y538917D01*
X1247417Y539500D01*
G01Y538500D02*
Y541833D01*
G01X1253100Y538500D02*
Y541833D01*
G01Y541250D02*
X1252767Y541583D01*
X1252267Y541750D01*
X1251683Y541833D01*
X1251100Y541667D01*
X1250600Y541333D01*
X1250267Y540833D01*
X1250100Y540167D01*
X1250267Y539500D01*
X1250600Y539000D01*
X1251100Y538667D01*
X1251683Y538500D01*
X1252267Y538583D01*
X1252767Y538833D01*
X1253100Y539167D01*
G01X1257200Y538500D02*
Y543500D01*
G01X1267233Y538500D02*
Y541833D01*
G01Y541167D02*
X1267650Y541500D01*
X1268067Y541750D01*
X1268650Y541833D01*
X1269067Y541750D01*
X1269567Y541500D01*
G01X1274000Y541833D02*
Y538500D01*
G01Y543167D02*
X1273833Y543250D01*
Y543417D01*
X1274000Y543500D01*
X1274167Y543417D01*
Y543250D01*
X1274000Y543167D01*
G01X1278183Y538500D02*
Y541833D01*
G01Y541000D02*
X1278517Y541417D01*
X1279017Y541750D01*
X1279683Y541833D01*
X1280267Y541750D01*
X1280767Y541417D01*
X1281017Y540833D01*
Y538500D01*
G01X1284033Y537250D02*
X1284617Y536917D01*
X1285283Y536833D01*
X1285867Y536917D01*
X1286367Y537333D01*
X1286700Y537917D01*
Y541833D01*
G01Y541167D02*
X1286367Y541500D01*
X1285867Y541750D01*
X1285283Y541833D01*
X1284617Y541667D01*
X1284200Y541333D01*
X1283867Y540750D01*
X1283700Y540167D01*
X1283783Y539667D01*
X1284117Y539083D01*
X1284617Y538667D01*
X1285283Y538500D01*
X1285783Y538583D01*
X1286367Y538917D01*
X1286700Y539250D01*
G01X1295150Y539083D02*
X1295567Y538750D01*
X1296150Y538500D01*
X1296650D01*
X1297150Y538667D01*
X1297483Y538917D01*
X1297650Y539250D01*
X1297567Y539750D01*
X1297233Y540000D01*
X1295733Y540500D01*
X1295400Y541083D01*
X1295567Y541500D01*
X1295900Y541750D01*
X1296400Y541833D01*
X1296900Y541750D01*
X1297400Y541500D01*
G01X1300583Y538500D02*
Y543500D01*
G01Y541083D02*
X1301000Y541500D01*
X1301417Y541750D01*
X1302083Y541833D01*
X1302583Y541750D01*
X1303167Y541417D01*
X1303417Y540917D01*
Y538500D01*
G01X1307600D02*
X1307100Y538583D01*
X1306600Y538917D01*
X1306267Y539500D01*
X1306100Y540167D01*
X1306267Y540833D01*
X1306600Y541417D01*
X1307100Y541750D01*
X1307600Y541833D01*
X1308100Y541750D01*
X1308600Y541417D01*
X1308933Y540833D01*
X1309017Y540167D01*
X1308933Y539500D01*
X1308600Y538917D01*
X1308100Y538583D01*
X1307600Y538500D01*
G01X1311783Y541833D02*
Y539500D01*
X1312117Y538917D01*
X1312617Y538583D01*
X1313200Y538500D01*
X1313783Y538583D01*
X1314283Y538917D01*
X1314617Y539500D01*
G01Y538500D02*
Y541833D01*
G01X1318800Y538500D02*
Y543500D01*
G01X1325900D02*
Y538500D01*
G01Y539250D02*
X1325567Y538833D01*
X1325067Y538583D01*
X1324483Y538500D01*
X1323817Y538667D01*
X1323317Y539083D01*
X1322983Y539583D01*
X1322900Y540167D01*
X1322983Y540750D01*
X1323317Y541250D01*
X1323817Y541667D01*
X1324483Y541833D01*
X1325067Y541750D01*
X1325483Y541583D01*
X1325900Y541250D01*
G01X1032500Y552500D02*
Y557500D01*
G01Y555000D02*
X1032917Y555500D01*
X1033417Y555750D01*
X1033917Y555833D01*
X1034667Y555667D01*
X1035167Y555333D01*
X1035500Y554750D01*
Y554083D01*
X1035333Y553417D01*
X1035000Y552917D01*
X1034417Y552583D01*
X1033917Y552500D01*
X1033417Y552583D01*
X1032917Y552833D01*
X1032500Y553250D01*
G01X1038350Y554750D02*
X1041017D01*
X1040767Y555333D01*
X1040350Y555667D01*
X1039767Y555833D01*
X1039183Y555750D01*
X1038683Y555500D01*
X1038350Y554917D01*
X1038183Y554417D01*
Y553917D01*
X1038350Y553417D01*
X1038767Y552917D01*
X1039267Y552583D01*
X1039850Y552500D01*
X1040433Y552667D01*
X1041017Y553167D01*
G01X1050800Y557500D02*
Y552500D01*
G01X1049633Y555833D02*
X1051967D01*
G01X1055150Y554750D02*
X1057817D01*
X1057567Y555333D01*
X1057150Y555667D01*
X1056567Y555833D01*
X1055983Y555750D01*
X1055483Y555500D01*
X1055150Y554917D01*
X1054983Y554417D01*
Y553917D01*
X1055150Y553417D01*
X1055567Y552917D01*
X1056067Y552583D01*
X1056650Y552500D01*
X1057233Y552667D01*
X1057817Y553167D01*
G01X1060583Y552500D02*
Y555833D01*
G01Y555000D02*
X1060917Y555417D01*
X1061417Y555750D01*
X1062083Y555833D01*
X1062667Y555750D01*
X1063167Y555417D01*
X1063417Y554833D01*
Y552500D01*
G01X1067600Y557500D02*
Y552500D01*
G01X1066433Y555833D02*
X1068767D01*
G01X1071950Y554750D02*
X1074617D01*
X1074367Y555333D01*
X1073950Y555667D01*
X1073367Y555833D01*
X1072783Y555750D01*
X1072283Y555500D01*
X1071950Y554917D01*
X1071783Y554417D01*
Y553917D01*
X1071950Y553417D01*
X1072367Y552917D01*
X1072867Y552583D01*
X1073450Y552500D01*
X1074033Y552667D01*
X1074617Y553167D01*
G01X1080300Y557500D02*
Y552500D01*
G01Y553250D02*
X1079967Y552833D01*
X1079467Y552583D01*
X1078883Y552500D01*
X1078217Y552667D01*
X1077717Y553083D01*
X1077383Y553583D01*
X1077300Y554167D01*
X1077383Y554750D01*
X1077717Y555250D01*
X1078217Y555667D01*
X1078883Y555833D01*
X1079467Y555750D01*
X1079883Y555583D01*
X1080300Y555250D01*
G01X1087917Y555833D02*
X1088917Y552500D01*
X1090000Y555833D01*
X1091083Y552500D01*
X1092083Y555833D01*
G01X1095600D02*
Y552500D01*
G01Y557167D02*
X1095433Y557250D01*
Y557417D01*
X1095600Y557500D01*
X1095767Y557417D01*
Y557250D01*
X1095600Y557167D01*
G01X1101200Y557500D02*
Y552500D01*
G01X1100033Y555833D02*
X1102367D01*
G01X1105383Y552500D02*
Y557500D01*
G01Y555083D02*
X1105800Y555500D01*
X1106217Y555750D01*
X1106883Y555833D01*
X1107383Y555750D01*
X1107967Y555417D01*
X1108217Y554917D01*
Y552500D01*
G01X1116750Y553083D02*
X1117167Y552750D01*
X1117750Y552500D01*
X1118250D01*
X1118750Y552667D01*
X1119083Y552917D01*
X1119250Y553250D01*
X1119167Y553750D01*
X1118833Y554000D01*
X1117333Y554500D01*
X1117000Y555083D01*
X1117167Y555500D01*
X1117500Y555750D01*
X1118000Y555833D01*
X1118500Y555750D01*
X1119000Y555500D01*
G01X1123600Y552500D02*
X1123100Y552583D01*
X1122600Y552917D01*
X1122267Y553500D01*
X1122100Y554167D01*
X1122267Y554833D01*
X1122600Y555417D01*
X1123100Y555750D01*
X1123600Y555833D01*
X1124100Y555750D01*
X1124600Y555417D01*
X1124933Y554833D01*
X1125017Y554167D01*
X1124933Y553500D01*
X1124600Y552917D01*
X1124100Y552583D01*
X1123600Y552500D01*
G01X1129200D02*
Y557500D01*
G01X1136300D02*
Y552500D01*
G01Y553250D02*
X1135967Y552833D01*
X1135467Y552583D01*
X1134883Y552500D01*
X1134217Y552667D01*
X1133717Y553083D01*
X1133383Y553583D01*
X1133300Y554167D01*
X1133383Y554750D01*
X1133717Y555250D01*
X1134217Y555667D01*
X1134883Y555833D01*
X1135467Y555750D01*
X1135883Y555583D01*
X1136300Y555250D01*
G01X1139150Y554750D02*
X1141817D01*
X1141567Y555333D01*
X1141150Y555667D01*
X1140567Y555833D01*
X1139983Y555750D01*
X1139483Y555500D01*
X1139150Y554917D01*
X1138983Y554417D01*
Y553917D01*
X1139150Y553417D01*
X1139567Y552917D01*
X1140067Y552583D01*
X1140650Y552500D01*
X1141233Y552667D01*
X1141817Y553167D01*
G01X1144833Y552500D02*
Y555833D01*
G01Y555167D02*
X1145250Y555500D01*
X1145667Y555750D01*
X1146250Y555833D01*
X1146667Y555750D01*
X1147167Y555500D01*
G01X1154700Y552500D02*
Y555833D01*
G01Y554917D02*
X1154950Y555333D01*
X1155367Y555667D01*
X1155950Y555833D01*
X1156533Y555667D01*
X1156950Y555333D01*
X1157200Y554917D01*
Y552500D01*
G01Y554917D02*
X1157450Y555333D01*
X1157867Y555667D01*
X1158450Y555833D01*
X1159033Y555667D01*
X1159450Y555333D01*
X1159700Y554833D01*
Y552500D01*
G01X1164300D02*
Y555833D01*
G01Y555250D02*
X1163967Y555583D01*
X1163467Y555750D01*
X1162883Y555833D01*
X1162300Y555667D01*
X1161800Y555333D01*
X1161467Y554833D01*
X1161300Y554167D01*
X1161467Y553500D01*
X1161800Y553000D01*
X1162300Y552667D01*
X1162883Y552500D01*
X1163467Y552583D01*
X1163967Y552833D01*
X1164300Y553167D01*
G01X1167150Y553083D02*
X1167567Y552750D01*
X1168150Y552500D01*
X1168650D01*
X1169150Y552667D01*
X1169483Y552917D01*
X1169650Y553250D01*
X1169567Y553750D01*
X1169233Y554000D01*
X1167733Y554500D01*
X1167400Y555083D01*
X1167567Y555500D01*
X1167900Y555750D01*
X1168400Y555833D01*
X1168900Y555750D01*
X1169400Y555500D01*
G01X1172583Y552500D02*
Y557500D01*
G01X1175250Y555833D02*
X1172583Y553917D01*
G01X1173667Y554667D02*
X1175417Y552500D01*
G01X1179600Y552333D02*
X1179433Y552417D01*
Y552583D01*
X1179600Y552667D01*
X1179767Y552583D01*
Y552417D01*
X1179600Y552333D01*
G01X1034000Y566500D02*
Y561500D01*
G01X1032833Y564833D02*
X1035167D01*
G01X1039600Y561500D02*
X1039100Y561583D01*
X1038600Y561917D01*
X1038267Y562500D01*
X1038100Y563167D01*
X1038267Y563833D01*
X1038600Y564417D01*
X1039100Y564750D01*
X1039600Y564833D01*
X1040100Y564750D01*
X1040600Y564417D01*
X1040933Y563833D01*
X1041017Y563167D01*
X1040933Y562500D01*
X1040600Y561917D01*
X1040100Y561583D01*
X1039600Y561500D01*
G01X1049300D02*
Y566500D01*
G01Y564000D02*
X1049717Y564500D01*
X1050217Y564750D01*
X1050717Y564833D01*
X1051467Y564667D01*
X1051967Y564333D01*
X1052300Y563750D01*
Y563083D01*
X1052133Y562417D01*
X1051800Y561917D01*
X1051217Y561583D01*
X1050717Y561500D01*
X1050217Y561583D01*
X1049717Y561833D01*
X1049300Y562250D01*
G01X1055150Y563750D02*
X1057817D01*
X1057567Y564333D01*
X1057150Y564667D01*
X1056567Y564833D01*
X1055983Y564750D01*
X1055483Y564500D01*
X1055150Y563917D01*
X1054983Y563417D01*
Y562917D01*
X1055150Y562417D01*
X1055567Y561917D01*
X1056067Y561583D01*
X1056650Y561500D01*
X1057233Y561667D01*
X1057817Y562167D01*
G01X1068933Y564417D02*
X1068350Y564750D01*
X1067850Y564833D01*
X1067183Y564667D01*
X1066683Y564333D01*
X1066350Y563750D01*
X1066267Y563167D01*
X1066350Y562583D01*
X1066683Y562083D01*
X1067183Y561667D01*
X1067850Y561500D01*
X1068433Y561667D01*
X1068933Y562000D01*
G01X1073200Y561500D02*
X1072700Y561583D01*
X1072200Y561917D01*
X1071867Y562500D01*
X1071700Y563167D01*
X1071867Y563833D01*
X1072200Y564417D01*
X1072700Y564750D01*
X1073200Y564833D01*
X1073700Y564750D01*
X1074200Y564417D01*
X1074533Y563833D01*
X1074617Y563167D01*
X1074533Y562500D01*
X1074200Y561917D01*
X1073700Y561583D01*
X1073200Y561500D01*
G01X1077300Y564833D02*
X1078800Y561500D01*
X1080300Y564833D01*
G01X1083150Y563750D02*
X1085817D01*
X1085567Y564333D01*
X1085150Y564667D01*
X1084567Y564833D01*
X1083983Y564750D01*
X1083483Y564500D01*
X1083150Y563917D01*
X1082983Y563417D01*
Y562917D01*
X1083150Y562417D01*
X1083567Y561917D01*
X1084067Y561583D01*
X1084650Y561500D01*
X1085233Y561667D01*
X1085817Y562167D01*
G01X1088833Y561500D02*
Y564833D01*
G01Y564167D02*
X1089250Y564500D01*
X1089667Y564750D01*
X1090250Y564833D01*
X1090667Y564750D01*
X1091167Y564500D01*
G01X1094350Y563750D02*
X1097017D01*
X1096767Y564333D01*
X1096350Y564667D01*
X1095767Y564833D01*
X1095183Y564750D01*
X1094683Y564500D01*
X1094350Y563917D01*
X1094183Y563417D01*
Y562917D01*
X1094350Y562417D01*
X1094767Y561917D01*
X1095267Y561583D01*
X1095850Y561500D01*
X1096433Y561667D01*
X1097017Y562167D01*
G01X1102700Y566500D02*
Y561500D01*
G01Y562250D02*
X1102367Y561833D01*
X1101867Y561583D01*
X1101283Y561500D01*
X1100617Y561667D01*
X1100117Y562083D01*
X1099783Y562583D01*
X1099700Y563167D01*
X1099783Y563750D01*
X1100117Y564250D01*
X1100617Y564667D01*
X1101283Y564833D01*
X1101867Y564750D01*
X1102283Y564583D01*
X1102700Y564250D01*
G01X1110900Y561500D02*
Y566500D01*
G01Y564000D02*
X1111317Y564500D01*
X1111817Y564750D01*
X1112317Y564833D01*
X1113067Y564667D01*
X1113567Y564333D01*
X1113900Y563750D01*
Y563083D01*
X1113733Y562417D01*
X1113400Y561917D01*
X1112817Y561583D01*
X1112317Y561500D01*
X1111817Y561583D01*
X1111317Y561833D01*
X1110900Y562250D01*
G01X1116250Y560000D02*
X1116750Y559833D01*
X1117417Y560000D01*
X1117833Y560333D01*
X1118167Y560750D01*
X1118667Y562083D01*
X1119750Y564833D01*
G01X1117083D02*
X1118667Y562083D01*
G01X1127950D02*
X1128367Y561750D01*
X1128950Y561500D01*
X1129450D01*
X1129950Y561667D01*
X1130283Y561917D01*
X1130450Y562250D01*
X1130367Y562750D01*
X1130033Y563000D01*
X1128533Y563500D01*
X1128200Y564083D01*
X1128367Y564500D01*
X1128700Y564750D01*
X1129200Y564833D01*
X1129700Y564750D01*
X1130200Y564500D01*
G01X1134800Y561500D02*
X1134300Y561583D01*
X1133800Y561917D01*
X1133467Y562500D01*
X1133300Y563167D01*
X1133467Y563833D01*
X1133800Y564417D01*
X1134300Y564750D01*
X1134800Y564833D01*
X1135300Y564750D01*
X1135800Y564417D01*
X1136133Y563833D01*
X1136217Y563167D01*
X1136133Y562500D01*
X1135800Y561917D01*
X1135300Y561583D01*
X1134800Y561500D01*
G01X1140400D02*
Y566500D01*
G01X1147500D02*
Y561500D01*
G01Y562250D02*
X1147167Y561833D01*
X1146667Y561583D01*
X1146083Y561500D01*
X1145417Y561667D01*
X1144917Y562083D01*
X1144583Y562583D01*
X1144500Y563167D01*
X1144583Y563750D01*
X1144917Y564250D01*
X1145417Y564667D01*
X1146083Y564833D01*
X1146667Y564750D01*
X1147083Y564583D01*
X1147500Y564250D01*
G01X1150350Y563750D02*
X1153017D01*
X1152767Y564333D01*
X1152350Y564667D01*
X1151767Y564833D01*
X1151183Y564750D01*
X1150683Y564500D01*
X1150350Y563917D01*
X1150183Y563417D01*
Y562917D01*
X1150350Y562417D01*
X1150767Y561917D01*
X1151267Y561583D01*
X1151850Y561500D01*
X1152433Y561667D01*
X1153017Y562167D01*
G01X1156033Y561500D02*
Y564833D01*
G01Y564167D02*
X1156450Y564500D01*
X1156867Y564750D01*
X1157450Y564833D01*
X1157867Y564750D01*
X1158367Y564500D01*
G01X1165900Y561500D02*
Y564833D01*
G01Y563917D02*
X1166150Y564333D01*
X1166567Y564667D01*
X1167150Y564833D01*
X1167733Y564667D01*
X1168150Y564333D01*
X1168400Y563917D01*
Y561500D01*
G01Y563917D02*
X1168650Y564333D01*
X1169067Y564667D01*
X1169650Y564833D01*
X1170233Y564667D01*
X1170650Y564333D01*
X1170900Y563833D01*
Y561500D01*
G01X1175500D02*
Y564833D01*
G01Y564250D02*
X1175167Y564583D01*
X1174667Y564750D01*
X1174083Y564833D01*
X1173500Y564667D01*
X1173000Y564333D01*
X1172667Y563833D01*
X1172500Y563167D01*
X1172667Y562500D01*
X1173000Y562000D01*
X1173500Y561667D01*
X1174083Y561500D01*
X1174667Y561583D01*
X1175167Y561833D01*
X1175500Y562167D01*
G01X1178350Y562083D02*
X1178767Y561750D01*
X1179350Y561500D01*
X1179850D01*
X1180350Y561667D01*
X1180683Y561917D01*
X1180850Y562250D01*
X1180767Y562750D01*
X1180433Y563000D01*
X1178933Y563500D01*
X1178600Y564083D01*
X1178767Y564500D01*
X1179100Y564750D01*
X1179600Y564833D01*
X1180100Y564750D01*
X1180600Y564500D01*
G01X1183783Y561500D02*
Y566500D01*
G01X1186450Y564833D02*
X1183783Y562917D01*
G01X1184867Y563667D02*
X1186617Y561500D01*
G01X1197900D02*
Y564833D01*
G01Y564250D02*
X1197567Y564583D01*
X1197067Y564750D01*
X1196483Y564833D01*
X1195900Y564667D01*
X1195400Y564333D01*
X1195067Y563833D01*
X1194900Y563167D01*
X1195067Y562500D01*
X1195400Y562000D01*
X1195900Y561667D01*
X1196483Y561500D01*
X1197067Y561583D01*
X1197567Y561833D01*
X1197900Y562167D01*
G01X1200583Y561500D02*
Y564833D01*
G01Y564000D02*
X1200917Y564417D01*
X1201417Y564750D01*
X1202083Y564833D01*
X1202667Y564750D01*
X1203167Y564417D01*
X1203417Y563833D01*
Y561500D01*
G01X1209100Y566500D02*
Y561500D01*
G01Y562250D02*
X1208767Y561833D01*
X1208267Y561583D01*
X1207683Y561500D01*
X1207017Y561667D01*
X1206517Y562083D01*
X1206183Y562583D01*
X1206100Y563167D01*
X1206183Y563750D01*
X1206517Y564250D01*
X1207017Y564667D01*
X1207683Y564833D01*
X1208267Y564750D01*
X1208683Y564583D01*
X1209100Y564250D01*
G01X1217383Y561500D02*
Y566500D01*
G01Y564083D02*
X1217800Y564500D01*
X1218217Y564750D01*
X1218883Y564833D01*
X1219383Y564750D01*
X1219967Y564417D01*
X1220217Y563917D01*
Y561500D01*
G01X1224400D02*
X1223900Y561583D01*
X1223400Y561917D01*
X1223067Y562500D01*
X1222900Y563167D01*
X1223067Y563833D01*
X1223400Y564417D01*
X1223900Y564750D01*
X1224400Y564833D01*
X1224900Y564750D01*
X1225400Y564417D01*
X1225733Y563833D01*
X1225817Y563167D01*
X1225733Y562500D01*
X1225400Y561917D01*
X1224900Y561583D01*
X1224400Y561500D01*
G01X1230000D02*
Y566500D01*
G01X1234350Y563750D02*
X1237017D01*
X1236767Y564333D01*
X1236350Y564667D01*
X1235767Y564833D01*
X1235183Y564750D01*
X1234683Y564500D01*
X1234350Y563917D01*
X1234183Y563417D01*
Y562917D01*
X1234350Y562417D01*
X1234767Y561917D01*
X1235267Y561583D01*
X1235850Y561500D01*
X1236433Y561667D01*
X1237017Y562167D01*
G01X1248300Y561500D02*
Y564833D01*
G01Y564250D02*
X1247967Y564583D01*
X1247467Y564750D01*
X1246883Y564833D01*
X1246300Y564667D01*
X1245800Y564333D01*
X1245467Y563833D01*
X1245300Y563167D01*
X1245467Y562500D01*
X1245800Y562000D01*
X1246300Y561667D01*
X1246883Y561500D01*
X1247467Y561583D01*
X1247967Y561833D01*
X1248300Y562167D01*
G01X1252400Y561500D02*
Y566500D01*
G01X1256750Y562083D02*
X1257167Y561750D01*
X1257750Y561500D01*
X1258250D01*
X1258750Y561667D01*
X1259083Y561917D01*
X1259250Y562250D01*
X1259167Y562750D01*
X1258833Y563000D01*
X1257333Y563500D01*
X1257000Y564083D01*
X1257167Y564500D01*
X1257500Y564750D01*
X1258000Y564833D01*
X1258500Y564750D01*
X1259000Y564500D01*
G01X1263600Y561500D02*
X1263100Y561583D01*
X1262600Y561917D01*
X1262267Y562500D01*
X1262100Y563167D01*
X1262267Y563833D01*
X1262600Y564417D01*
X1263100Y564750D01*
X1263600Y564833D01*
X1264100Y564750D01*
X1264600Y564417D01*
X1264933Y563833D01*
X1265017Y563167D01*
X1264933Y562500D01*
X1264600Y561917D01*
X1264100Y561583D01*
X1263600Y561500D01*
G01X1273383D02*
Y564833D01*
G01Y564000D02*
X1273717Y564417D01*
X1274217Y564750D01*
X1274883Y564833D01*
X1275467Y564750D01*
X1275967Y564417D01*
X1276217Y563833D01*
Y561500D01*
G01X1279150Y563750D02*
X1281817D01*
X1281567Y564333D01*
X1281150Y564667D01*
X1280567Y564833D01*
X1279983Y564750D01*
X1279483Y564500D01*
X1279150Y563917D01*
X1278983Y563417D01*
Y562917D01*
X1279150Y562417D01*
X1279567Y561917D01*
X1280067Y561583D01*
X1280650Y561500D01*
X1281233Y561667D01*
X1281817Y562167D01*
G01X1284750Y563750D02*
X1287417D01*
X1287167Y564333D01*
X1286750Y564667D01*
X1286167Y564833D01*
X1285583Y564750D01*
X1285083Y564500D01*
X1284750Y563917D01*
X1284583Y563417D01*
Y562917D01*
X1284750Y562417D01*
X1285167Y561917D01*
X1285667Y561583D01*
X1286250Y561500D01*
X1286833Y561667D01*
X1287417Y562167D01*
G01X1293100Y566500D02*
Y561500D01*
G01Y562250D02*
X1292767Y561833D01*
X1292267Y561583D01*
X1291683Y561500D01*
X1291017Y561667D01*
X1290517Y562083D01*
X1290183Y562583D01*
X1290100Y563167D01*
X1290183Y563750D01*
X1290517Y564250D01*
X1291017Y564667D01*
X1291683Y564833D01*
X1292267Y564750D01*
X1292683Y564583D01*
X1293100Y564250D01*
G01X1302800Y566500D02*
Y561500D01*
G01X1301633Y564833D02*
X1303967D01*
G01X1308400Y561500D02*
X1307900Y561583D01*
X1307400Y561917D01*
X1307067Y562500D01*
X1306900Y563167D01*
X1307067Y563833D01*
X1307400Y564417D01*
X1307900Y564750D01*
X1308400Y564833D01*
X1308900Y564750D01*
X1309400Y564417D01*
X1309733Y563833D01*
X1309817Y563167D01*
X1309733Y562500D01*
X1309400Y561917D01*
X1308900Y561583D01*
X1308400Y561500D01*
G01X1022000Y569500D02*
Y574500D01*
X1021000Y573500D01*
G01Y569500D02*
X1023000D01*
G01X1027600Y569333D02*
X1027433Y569417D01*
Y569583D01*
X1027600Y569667D01*
X1027767Y569583D01*
Y569417D01*
X1027600Y569333D01*
G01X1033200Y574500D02*
Y569500D01*
G01X1031283Y574500D02*
X1035117D01*
G01X1037383Y569500D02*
Y574500D01*
G01Y572083D02*
X1037800Y572500D01*
X1038217Y572750D01*
X1038883Y572833D01*
X1039383Y572750D01*
X1039967Y572417D01*
X1040217Y571917D01*
Y569500D01*
G01X1043150Y571750D02*
X1045817D01*
X1045567Y572333D01*
X1045150Y572667D01*
X1044567Y572833D01*
X1043983Y572750D01*
X1043483Y572500D01*
X1043150Y571917D01*
X1042983Y571417D01*
Y570917D01*
X1043150Y570417D01*
X1043567Y569917D01*
X1044067Y569583D01*
X1044650Y569500D01*
X1045233Y569667D01*
X1045817Y570167D01*
G01X1054350Y570083D02*
X1054767Y569750D01*
X1055350Y569500D01*
X1055850D01*
X1056350Y569667D01*
X1056683Y569917D01*
X1056850Y570250D01*
X1056767Y570750D01*
X1056433Y571000D01*
X1054933Y571500D01*
X1054600Y572083D01*
X1054767Y572500D01*
X1055100Y572750D01*
X1055600Y572833D01*
X1056100Y572750D01*
X1056600Y572500D01*
G01X1061200Y572833D02*
Y569500D01*
G01Y574167D02*
X1061033Y574250D01*
Y574417D01*
X1061200Y574500D01*
X1061367Y574417D01*
Y574250D01*
X1061200Y574167D01*
G01X1068300Y574500D02*
Y569500D01*
G01Y570250D02*
X1067967Y569833D01*
X1067467Y569583D01*
X1066883Y569500D01*
X1066217Y569667D01*
X1065717Y570083D01*
X1065383Y570583D01*
X1065300Y571167D01*
X1065383Y571750D01*
X1065717Y572250D01*
X1066217Y572667D01*
X1066883Y572833D01*
X1067467Y572750D01*
X1067883Y572583D01*
X1068300Y572250D01*
G01X1071150Y571750D02*
X1073817D01*
X1073567Y572333D01*
X1073150Y572667D01*
X1072567Y572833D01*
X1071983Y572750D01*
X1071483Y572500D01*
X1071150Y571917D01*
X1070983Y571417D01*
Y570917D01*
X1071150Y570417D01*
X1071567Y569917D01*
X1072067Y569583D01*
X1072650Y569500D01*
X1073233Y569667D01*
X1073817Y570167D01*
G01X1081517Y572833D02*
X1082517Y569500D01*
X1083600Y572833D01*
X1084683Y569500D01*
X1085683Y572833D01*
G01X1089200D02*
Y569500D01*
G01Y574167D02*
X1089033Y574250D01*
Y574417D01*
X1089200Y574500D01*
X1089367Y574417D01*
Y574250D01*
X1089200Y574167D01*
G01X1094800Y574500D02*
Y569500D01*
G01X1093633Y572833D02*
X1095967D01*
G01X1098983Y569500D02*
Y574500D01*
G01Y572083D02*
X1099400Y572500D01*
X1099817Y572750D01*
X1100483Y572833D01*
X1100983Y572750D01*
X1101567Y572417D01*
X1101817Y571917D01*
Y569500D01*
G01X1106000D02*
X1105500Y569583D01*
X1105000Y569917D01*
X1104667Y570500D01*
X1104500Y571167D01*
X1104667Y571833D01*
X1105000Y572417D01*
X1105500Y572750D01*
X1106000Y572833D01*
X1106500Y572750D01*
X1107000Y572417D01*
X1107333Y571833D01*
X1107417Y571167D01*
X1107333Y570500D01*
X1107000Y569917D01*
X1106500Y569583D01*
X1106000Y569500D01*
G01X1110183Y572833D02*
Y570500D01*
X1110517Y569917D01*
X1111017Y569583D01*
X1111600Y569500D01*
X1112183Y569583D01*
X1112683Y569917D01*
X1113017Y570500D01*
G01Y569500D02*
Y572833D01*
G01X1117200Y574500D02*
Y569500D01*
G01X1116033Y572833D02*
X1118367D01*
G01X1127150Y570083D02*
X1127567Y569750D01*
X1128150Y569500D01*
X1128650D01*
X1129150Y569667D01*
X1129483Y569917D01*
X1129650Y570250D01*
X1129567Y570750D01*
X1129233Y571000D01*
X1127733Y571500D01*
X1127400Y572083D01*
X1127567Y572500D01*
X1127900Y572750D01*
X1128400Y572833D01*
X1128900Y572750D01*
X1129400Y572500D01*
G01X1134000Y569500D02*
X1133500Y569583D01*
X1133000Y569917D01*
X1132667Y570500D01*
X1132500Y571167D01*
X1132667Y571833D01*
X1133000Y572417D01*
X1133500Y572750D01*
X1134000Y572833D01*
X1134500Y572750D01*
X1135000Y572417D01*
X1135333Y571833D01*
X1135417Y571167D01*
X1135333Y570500D01*
X1135000Y569917D01*
X1134500Y569583D01*
X1134000Y569500D01*
G01X1139600D02*
Y574500D01*
G01X1146700D02*
Y569500D01*
G01Y570250D02*
X1146367Y569833D01*
X1145867Y569583D01*
X1145283Y569500D01*
X1144617Y569667D01*
X1144117Y570083D01*
X1143783Y570583D01*
X1143700Y571167D01*
X1143783Y571750D01*
X1144117Y572250D01*
X1144617Y572667D01*
X1145283Y572833D01*
X1145867Y572750D01*
X1146283Y572583D01*
X1146700Y572250D01*
G01X1149550Y571750D02*
X1152217D01*
X1151967Y572333D01*
X1151550Y572667D01*
X1150967Y572833D01*
X1150383Y572750D01*
X1149883Y572500D01*
X1149550Y571917D01*
X1149383Y571417D01*
Y570917D01*
X1149550Y570417D01*
X1149967Y569917D01*
X1150467Y569583D01*
X1151050Y569500D01*
X1151633Y569667D01*
X1152217Y570167D01*
G01X1155233Y569500D02*
Y572833D01*
G01Y572167D02*
X1155650Y572500D01*
X1156067Y572750D01*
X1156650Y572833D01*
X1157067Y572750D01*
X1157567Y572500D01*
G01X1165100Y569500D02*
Y572833D01*
G01Y571917D02*
X1165350Y572333D01*
X1165767Y572667D01*
X1166350Y572833D01*
X1166933Y572667D01*
X1167350Y572333D01*
X1167600Y571917D01*
Y569500D01*
G01Y571917D02*
X1167850Y572333D01*
X1168267Y572667D01*
X1168850Y572833D01*
X1169433Y572667D01*
X1169850Y572333D01*
X1170100Y571833D01*
Y569500D01*
G01X1174700D02*
Y572833D01*
G01Y572250D02*
X1174367Y572583D01*
X1173867Y572750D01*
X1173283Y572833D01*
X1172700Y572667D01*
X1172200Y572333D01*
X1171867Y571833D01*
X1171700Y571167D01*
X1171867Y570500D01*
X1172200Y570000D01*
X1172700Y569667D01*
X1173283Y569500D01*
X1173867Y569583D01*
X1174367Y569833D01*
X1174700Y570167D01*
G01X1177550Y570083D02*
X1177967Y569750D01*
X1178550Y569500D01*
X1179050D01*
X1179550Y569667D01*
X1179883Y569917D01*
X1180050Y570250D01*
X1179967Y570750D01*
X1179633Y571000D01*
X1178133Y571500D01*
X1177800Y572083D01*
X1177967Y572500D01*
X1178300Y572750D01*
X1178800Y572833D01*
X1179300Y572750D01*
X1179800Y572500D01*
G01X1182983Y569500D02*
Y574500D01*
G01X1185650Y572833D02*
X1182983Y570917D01*
G01X1184067Y571667D02*
X1185817Y569500D01*
G01X1194100Y567833D02*
Y572833D01*
G01Y572083D02*
X1194517Y572500D01*
X1194933Y572750D01*
X1195600Y572833D01*
X1196183Y572750D01*
X1196767Y572333D01*
X1197017Y571750D01*
X1197100Y571167D01*
X1197017Y570583D01*
X1196767Y570000D01*
X1196267Y569667D01*
X1195600Y569500D01*
X1195017Y569583D01*
X1194433Y569833D01*
X1194100Y570167D01*
G01X1202700Y569500D02*
Y572833D01*
G01Y572250D02*
X1202367Y572583D01*
X1201867Y572750D01*
X1201283Y572833D01*
X1200700Y572667D01*
X1200200Y572333D01*
X1199867Y571833D01*
X1199700Y571167D01*
X1199867Y570500D01*
X1200200Y570000D01*
X1200700Y569667D01*
X1201283Y569500D01*
X1201867Y569583D01*
X1202367Y569833D01*
X1202700Y570167D01*
G01X1208300Y574500D02*
Y569500D01*
G01Y570250D02*
X1207967Y569833D01*
X1207467Y569583D01*
X1206883Y569500D01*
X1206217Y569667D01*
X1205717Y570083D01*
X1205383Y570583D01*
X1205300Y571167D01*
X1205383Y571750D01*
X1205717Y572250D01*
X1206217Y572667D01*
X1206883Y572833D01*
X1207467Y572750D01*
X1207883Y572583D01*
X1208300Y572250D01*
G01X1217833Y568583D02*
X1218167Y569667D01*
G01X1230700Y569500D02*
Y572833D01*
G01Y572250D02*
X1230367Y572583D01*
X1229867Y572750D01*
X1229283Y572833D01*
X1228700Y572667D01*
X1228200Y572333D01*
X1227867Y571833D01*
X1227700Y571167D01*
X1227867Y570500D01*
X1228200Y570000D01*
X1228700Y569667D01*
X1229283Y569500D01*
X1229867Y569583D01*
X1230367Y569833D01*
X1230700Y570167D01*
G01X1233383Y569500D02*
Y572833D01*
G01Y572000D02*
X1233717Y572417D01*
X1234217Y572750D01*
X1234883Y572833D01*
X1235467Y572750D01*
X1235967Y572417D01*
X1236217Y571833D01*
Y569500D01*
G01X1238983D02*
Y572833D01*
G01Y572000D02*
X1239317Y572417D01*
X1239817Y572750D01*
X1240483Y572833D01*
X1241067Y572750D01*
X1241567Y572417D01*
X1241817Y571833D01*
Y569500D01*
G01X1244583Y572833D02*
Y570500D01*
X1244917Y569917D01*
X1245417Y569583D01*
X1246000Y569500D01*
X1246583Y569583D01*
X1247083Y569917D01*
X1247417Y570500D01*
G01Y569500D02*
Y572833D01*
G01X1253100Y569500D02*
Y572833D01*
G01Y572250D02*
X1252767Y572583D01*
X1252267Y572750D01*
X1251683Y572833D01*
X1251100Y572667D01*
X1250600Y572333D01*
X1250267Y571833D01*
X1250100Y571167D01*
X1250267Y570500D01*
X1250600Y570000D01*
X1251100Y569667D01*
X1251683Y569500D01*
X1252267Y569583D01*
X1252767Y569833D01*
X1253100Y570167D01*
G01X1257200Y569500D02*
Y574500D01*
G01X1267233Y569500D02*
Y572833D01*
G01Y572167D02*
X1267650Y572500D01*
X1268067Y572750D01*
X1268650Y572833D01*
X1269067Y572750D01*
X1269567Y572500D01*
G01X1274000Y572833D02*
Y569500D01*
G01Y574167D02*
X1273833Y574250D01*
Y574417D01*
X1274000Y574500D01*
X1274167Y574417D01*
Y574250D01*
X1274000Y574167D01*
G01X1278183Y569500D02*
Y572833D01*
G01Y572000D02*
X1278517Y572417D01*
X1279017Y572750D01*
X1279683Y572833D01*
X1280267Y572750D01*
X1280767Y572417D01*
X1281017Y571833D01*
Y569500D01*
G01X1284033Y568250D02*
X1284617Y567917D01*
X1285283Y567833D01*
X1285867Y567917D01*
X1286367Y568333D01*
X1286700Y568917D01*
Y572833D01*
G01Y572167D02*
X1286367Y572500D01*
X1285867Y572750D01*
X1285283Y572833D01*
X1284617Y572667D01*
X1284200Y572333D01*
X1283867Y571750D01*
X1283700Y571167D01*
X1283783Y570667D01*
X1284117Y570083D01*
X1284617Y569667D01*
X1285283Y569500D01*
X1285783Y569583D01*
X1286367Y569917D01*
X1286700Y570250D01*
G01X1294983Y569500D02*
Y572833D01*
G01Y572000D02*
X1295317Y572417D01*
X1295817Y572750D01*
X1296483Y572833D01*
X1297067Y572750D01*
X1297567Y572417D01*
X1297817Y571833D01*
Y569500D01*
G01X1300750Y571750D02*
X1303417D01*
X1303167Y572333D01*
X1302750Y572667D01*
X1302167Y572833D01*
X1301583Y572750D01*
X1301083Y572500D01*
X1300750Y571917D01*
X1300583Y571417D01*
Y570917D01*
X1300750Y570417D01*
X1301167Y569917D01*
X1301667Y569583D01*
X1302250Y569500D01*
X1302833Y569667D01*
X1303417Y570167D01*
G01X1306350Y571750D02*
X1309017D01*
X1308767Y572333D01*
X1308350Y572667D01*
X1307767Y572833D01*
X1307183Y572750D01*
X1306683Y572500D01*
X1306350Y571917D01*
X1306183Y571417D01*
Y570917D01*
X1306350Y570417D01*
X1306767Y569917D01*
X1307267Y569583D01*
X1307850Y569500D01*
X1308433Y569667D01*
X1309017Y570167D01*
G01X1314700Y574500D02*
Y569500D01*
G01Y570250D02*
X1314367Y569833D01*
X1313867Y569583D01*
X1313283Y569500D01*
X1312617Y569667D01*
X1312117Y570083D01*
X1311783Y570583D01*
X1311700Y571167D01*
X1311783Y571750D01*
X1312117Y572250D01*
X1312617Y572667D01*
X1313283Y572833D01*
X1313867Y572750D01*
X1314283Y572583D01*
X1314700Y572250D01*
G01X1012083Y730500D02*
Y733833D01*
G01Y733000D02*
X1012417Y733417D01*
X1012917Y733750D01*
X1013583Y733833D01*
X1014167Y733750D01*
X1014667Y733417D01*
X1014917Y732833D01*
Y730500D01*
G01X1019100D02*
X1018600Y730583D01*
X1018100Y730917D01*
X1017767Y731500D01*
X1017600Y732167D01*
X1017767Y732833D01*
X1018100Y733417D01*
X1018600Y733750D01*
X1019100Y733833D01*
X1019600Y733750D01*
X1020100Y733417D01*
X1020433Y732833D01*
X1020517Y732167D01*
X1020433Y731500D01*
X1020100Y730917D01*
X1019600Y730583D01*
X1019100Y730500D01*
G01X1028800Y728833D02*
Y733833D01*
G01Y733083D02*
X1029217Y733500D01*
X1029633Y733750D01*
X1030300Y733833D01*
X1030883Y733750D01*
X1031467Y733333D01*
X1031717Y732750D01*
X1031800Y732167D01*
X1031717Y731583D01*
X1031467Y731000D01*
X1030967Y730667D01*
X1030300Y730500D01*
X1029717Y730583D01*
X1029133Y730833D01*
X1028800Y731167D01*
G01X1035900Y730500D02*
Y735500D01*
G01X1040083Y733833D02*
Y731500D01*
X1040417Y730917D01*
X1040917Y730583D01*
X1041500Y730500D01*
X1042083Y730583D01*
X1042583Y730917D01*
X1042917Y731500D01*
G01Y730500D02*
Y733833D01*
G01X1045933Y729250D02*
X1046517Y728917D01*
X1047183Y728833D01*
X1047767Y728917D01*
X1048267Y729333D01*
X1048600Y729917D01*
Y733833D01*
G01Y733167D02*
X1048267Y733500D01*
X1047767Y733750D01*
X1047183Y733833D01*
X1046517Y733667D01*
X1046100Y733333D01*
X1045767Y732750D01*
X1045600Y732167D01*
X1045683Y731667D01*
X1046017Y731083D01*
X1046517Y730667D01*
X1047183Y730500D01*
X1047683Y730583D01*
X1048267Y730917D01*
X1048600Y731250D01*
G01X1051533Y729250D02*
X1052117Y728917D01*
X1052783Y728833D01*
X1053367Y728917D01*
X1053867Y729333D01*
X1054200Y729917D01*
Y733833D01*
G01Y733167D02*
X1053867Y733500D01*
X1053367Y733750D01*
X1052783Y733833D01*
X1052117Y733667D01*
X1051700Y733333D01*
X1051367Y732750D01*
X1051200Y732167D01*
X1051283Y731667D01*
X1051617Y731083D01*
X1052117Y730667D01*
X1052783Y730500D01*
X1053283Y730583D01*
X1053867Y730917D01*
X1054200Y731250D01*
G01X1058300Y733833D02*
Y730500D01*
G01Y735167D02*
X1058133Y735250D01*
Y735417D01*
X1058300Y735500D01*
X1058467Y735417D01*
Y735250D01*
X1058300Y735167D01*
G01X1062483Y730500D02*
Y733833D01*
G01Y733000D02*
X1062817Y733417D01*
X1063317Y733750D01*
X1063983Y733833D01*
X1064567Y733750D01*
X1065067Y733417D01*
X1065317Y732833D01*
Y730500D01*
G01X1068333Y729250D02*
X1068917Y728917D01*
X1069583Y728833D01*
X1070167Y728917D01*
X1070667Y729333D01*
X1071000Y729917D01*
Y733833D01*
G01Y733167D02*
X1070667Y733500D01*
X1070167Y733750D01*
X1069583Y733833D01*
X1068917Y733667D01*
X1068500Y733333D01*
X1068167Y732750D01*
X1068000Y732167D01*
X1068083Y731667D01*
X1068417Y731083D01*
X1068917Y730667D01*
X1069583Y730500D01*
X1070083Y730583D01*
X1070667Y730917D01*
X1071000Y731250D01*
G01X1089493Y104700D02*
Y99700D01*
X1092827D01*
G01X1095510Y103033D02*
X1098010Y99700D01*
G01Y103033D02*
X1095510Y99700D01*
G01X1102360Y99533D02*
X1102193Y99617D01*
Y99783D01*
X1102360Y99867D01*
X1102527Y99783D01*
Y99617D01*
X1102360Y99533D01*
G01Y101783D02*
X1102193Y101867D01*
Y102033D01*
X1102360Y102117D01*
X1102527Y102033D01*
Y101867D01*
X1102360Y101783D01*
G01X1111060Y99700D02*
Y103033D01*
G01Y102117D02*
X1111310Y102533D01*
X1111727Y102867D01*
X1112310Y103033D01*
X1112893Y102867D01*
X1113310Y102533D01*
X1113560Y102117D01*
Y99700D01*
G01Y102117D02*
X1113810Y102533D01*
X1114227Y102867D01*
X1114810Y103033D01*
X1115393Y102867D01*
X1115810Y102533D01*
X1116060Y102033D01*
Y99700D01*
G01X1117743Y103033D02*
Y100700D01*
X1118077Y100117D01*
X1118577Y99783D01*
X1119160Y99700D01*
X1119743Y99783D01*
X1120243Y100117D01*
X1120577Y100700D01*
G01Y99700D02*
Y103033D01*
G01X1123510Y100283D02*
X1123927Y99950D01*
X1124510Y99700D01*
X1125010D01*
X1125510Y99867D01*
X1125843Y100117D01*
X1126010Y100450D01*
X1125927Y100950D01*
X1125593Y101200D01*
X1124093Y101700D01*
X1123760Y102283D01*
X1123927Y102700D01*
X1124260Y102950D01*
X1124760Y103033D01*
X1125260Y102950D01*
X1125760Y102700D01*
G01X1130360Y104700D02*
Y99700D01*
G01X1129193Y103033D02*
X1131527D01*
G01X1140060Y99700D02*
Y104700D01*
G01Y102200D02*
X1140477Y102700D01*
X1140977Y102950D01*
X1141477Y103033D01*
X1142227Y102867D01*
X1142727Y102533D01*
X1143060Y101950D01*
Y101283D01*
X1142893Y100617D01*
X1142560Y100117D01*
X1141977Y99783D01*
X1141477Y99700D01*
X1140977Y99783D01*
X1140477Y100033D01*
X1140060Y100450D01*
G01X1145910Y101950D02*
X1148577D01*
X1148327Y102533D01*
X1147910Y102867D01*
X1147327Y103033D01*
X1146743Y102950D01*
X1146243Y102700D01*
X1145910Y102117D01*
X1145743Y101617D01*
Y101117D01*
X1145910Y100617D01*
X1146327Y100117D01*
X1146827Y99783D01*
X1147410Y99700D01*
X1147993Y99867D01*
X1148577Y100367D01*
G01X1156860Y99700D02*
Y104700D01*
G01Y102200D02*
X1157277Y102700D01*
X1157777Y102950D01*
X1158277Y103033D01*
X1159027Y102867D01*
X1159527Y102533D01*
X1159860Y101950D01*
Y101283D01*
X1159693Y100617D01*
X1159360Y100117D01*
X1158777Y99783D01*
X1158277Y99700D01*
X1157777Y99783D01*
X1157277Y100033D01*
X1156860Y100450D01*
G01X1162793Y99700D02*
Y103033D01*
G01Y102367D02*
X1163210Y102700D01*
X1163627Y102950D01*
X1164210Y103033D01*
X1164627Y102950D01*
X1165127Y102700D01*
G01X1169560Y99700D02*
X1169060Y99783D01*
X1168560Y100117D01*
X1168227Y100700D01*
X1168060Y101367D01*
X1168227Y102033D01*
X1168560Y102617D01*
X1169060Y102950D01*
X1169560Y103033D01*
X1170060Y102950D01*
X1170560Y102617D01*
X1170893Y102033D01*
X1170977Y101367D01*
X1170893Y100700D01*
X1170560Y100117D01*
X1170060Y99783D01*
X1169560Y99700D01*
G01X1173743D02*
Y104700D01*
G01X1176410Y103033D02*
X1173743Y101117D01*
G01X1174827Y101867D02*
X1176577Y99700D01*
G01X1179510Y101950D02*
X1182177D01*
X1181927Y102533D01*
X1181510Y102867D01*
X1180927Y103033D01*
X1180343Y102950D01*
X1179843Y102700D01*
X1179510Y102117D01*
X1179343Y101617D01*
Y101117D01*
X1179510Y100617D01*
X1179927Y100117D01*
X1180427Y99783D01*
X1181010Y99700D01*
X1181593Y99867D01*
X1182177Y100367D01*
G01X1184943Y99700D02*
Y103033D01*
G01Y102200D02*
X1185277Y102617D01*
X1185777Y102950D01*
X1186443Y103033D01*
X1187027Y102950D01*
X1187527Y102617D01*
X1187777Y102033D01*
Y99700D01*
G01X1197560D02*
Y104700D01*
G01X1204660Y99700D02*
Y103033D01*
G01Y102450D02*
X1204327Y102783D01*
X1203827Y102950D01*
X1203243Y103033D01*
X1202660Y102867D01*
X1202160Y102533D01*
X1201827Y102033D01*
X1201660Y101367D01*
X1201827Y100700D01*
X1202160Y100200D01*
X1202660Y99867D01*
X1203243Y99700D01*
X1203827Y99783D01*
X1204327Y100033D01*
X1204660Y100367D01*
G01X1207010Y98200D02*
X1207510Y98033D01*
X1208177Y98200D01*
X1208593Y98533D01*
X1208927Y98950D01*
X1209427Y100283D01*
X1210510Y103033D01*
G01X1207843D02*
X1209427Y100283D01*
G01X1213110Y101950D02*
X1215777D01*
X1215527Y102533D01*
X1215110Y102867D01*
X1214527Y103033D01*
X1213943Y102950D01*
X1213443Y102700D01*
X1213110Y102117D01*
X1212943Y101617D01*
Y101117D01*
X1213110Y100617D01*
X1213527Y100117D01*
X1214027Y99783D01*
X1214610Y99700D01*
X1215193Y99867D01*
X1215777Y100367D01*
G01X1218793Y99700D02*
Y103033D01*
G01Y102367D02*
X1219210Y102700D01*
X1219627Y102950D01*
X1220210Y103033D01*
X1220627Y102950D01*
X1221127Y102700D01*
G01X1088893Y117200D02*
Y112200D01*
X1092227D01*
G01X1094743D02*
Y115533D01*
G01Y114700D02*
X1095077Y115117D01*
X1095577Y115450D01*
X1096243Y115533D01*
X1096827Y115450D01*
X1097327Y115117D01*
X1097577Y114533D01*
Y112200D01*
G01X1101760Y112033D02*
X1101593Y112117D01*
Y112283D01*
X1101760Y112367D01*
X1101927Y112283D01*
Y112117D01*
X1101760Y112033D01*
G01Y114283D02*
X1101593Y114367D01*
Y114533D01*
X1101760Y114617D01*
X1101927Y114533D01*
Y114367D01*
X1101760Y114283D01*
G01X1114293Y115117D02*
X1113710Y115450D01*
X1113210Y115533D01*
X1112543Y115367D01*
X1112043Y115033D01*
X1111710Y114450D01*
X1111627Y113867D01*
X1111710Y113283D01*
X1112043Y112783D01*
X1112543Y112367D01*
X1113210Y112200D01*
X1113793Y112367D01*
X1114293Y112700D01*
G01X1120060Y112200D02*
Y115533D01*
G01Y114950D02*
X1119727Y115283D01*
X1119227Y115450D01*
X1118643Y115533D01*
X1118060Y115367D01*
X1117560Y115033D01*
X1117227Y114533D01*
X1117060Y113867D01*
X1117227Y113200D01*
X1117560Y112700D01*
X1118060Y112367D01*
X1118643Y112200D01*
X1119227Y112283D01*
X1119727Y112533D01*
X1120060Y112867D01*
G01X1122743Y112200D02*
Y115533D01*
G01Y114700D02*
X1123077Y115117D01*
X1123577Y115450D01*
X1124243Y115533D01*
X1124827Y115450D01*
X1125327Y115117D01*
X1125577Y114533D01*
Y112200D01*
G01X1129760Y115533D02*
X1130593Y116575D01*
Y117200D01*
X1129968D01*
Y116575D01*
X1130593D01*
G01X1135360Y117200D02*
Y112200D01*
G01X1134193Y115533D02*
X1136527D01*
G01X1145060Y112200D02*
Y117200D01*
G01Y114700D02*
X1145477Y115200D01*
X1145977Y115450D01*
X1146477Y115533D01*
X1147227Y115367D01*
X1147727Y115033D01*
X1148060Y114450D01*
Y113783D01*
X1147893Y113117D01*
X1147560Y112617D01*
X1146977Y112283D01*
X1146477Y112200D01*
X1145977Y112283D01*
X1145477Y112533D01*
X1145060Y112950D01*
G01X1150910Y114450D02*
X1153577D01*
X1153327Y115033D01*
X1152910Y115367D01*
X1152327Y115533D01*
X1151743Y115450D01*
X1151243Y115200D01*
X1150910Y114617D01*
X1150743Y114117D01*
Y113617D01*
X1150910Y113117D01*
X1151327Y112617D01*
X1151827Y112283D01*
X1152410Y112200D01*
X1152993Y112367D01*
X1153577Y112867D01*
G01X1161860Y112200D02*
Y117200D01*
G01Y114700D02*
X1162277Y115200D01*
X1162777Y115450D01*
X1163277Y115533D01*
X1164027Y115367D01*
X1164527Y115033D01*
X1164860Y114450D01*
Y113783D01*
X1164693Y113117D01*
X1164360Y112617D01*
X1163777Y112283D01*
X1163277Y112200D01*
X1162777Y112283D01*
X1162277Y112533D01*
X1161860Y112950D01*
G01X1167793Y112200D02*
Y115533D01*
G01Y114867D02*
X1168210Y115200D01*
X1168627Y115450D01*
X1169210Y115533D01*
X1169627Y115450D01*
X1170127Y115200D01*
G01X1174560Y112200D02*
X1174060Y112283D01*
X1173560Y112617D01*
X1173227Y113200D01*
X1173060Y113867D01*
X1173227Y114533D01*
X1173560Y115117D01*
X1174060Y115450D01*
X1174560Y115533D01*
X1175060Y115450D01*
X1175560Y115117D01*
X1175893Y114533D01*
X1175977Y113867D01*
X1175893Y113200D01*
X1175560Y112617D01*
X1175060Y112283D01*
X1174560Y112200D01*
G01X1178743D02*
Y117200D01*
G01X1181410Y115533D02*
X1178743Y113617D01*
G01X1179827Y114367D02*
X1181577Y112200D01*
G01X1184510Y114450D02*
X1187177D01*
X1186927Y115033D01*
X1186510Y115367D01*
X1185927Y115533D01*
X1185343Y115450D01*
X1184843Y115200D01*
X1184510Y114617D01*
X1184343Y114117D01*
Y113617D01*
X1184510Y113117D01*
X1184927Y112617D01*
X1185427Y112283D01*
X1186010Y112200D01*
X1186593Y112367D01*
X1187177Y112867D01*
G01X1189943Y112200D02*
Y115533D01*
G01Y114700D02*
X1190277Y115117D01*
X1190777Y115450D01*
X1191443Y115533D01*
X1192027Y115450D01*
X1192527Y115117D01*
X1192777Y114533D01*
Y112200D01*
G01X1202560D02*
Y117200D01*
G01X1209660Y112200D02*
Y115533D01*
G01Y114950D02*
X1209327Y115283D01*
X1208827Y115450D01*
X1208243Y115533D01*
X1207660Y115367D01*
X1207160Y115033D01*
X1206827Y114533D01*
X1206660Y113867D01*
X1206827Y113200D01*
X1207160Y112700D01*
X1207660Y112367D01*
X1208243Y112200D01*
X1208827Y112283D01*
X1209327Y112533D01*
X1209660Y112867D01*
G01X1212010Y110700D02*
X1212510Y110533D01*
X1213177Y110700D01*
X1213593Y111033D01*
X1213927Y111450D01*
X1214427Y112783D01*
X1215510Y115533D01*
G01X1212843D02*
X1214427Y112783D01*
G01X1218110Y114450D02*
X1220777D01*
X1220527Y115033D01*
X1220110Y115367D01*
X1219527Y115533D01*
X1218943Y115450D01*
X1218443Y115200D01*
X1218110Y114617D01*
X1217943Y114117D01*
Y113617D01*
X1218110Y113117D01*
X1218527Y112617D01*
X1219027Y112283D01*
X1219610Y112200D01*
X1220193Y112367D01*
X1220777Y112867D01*
G01X1223793Y112200D02*
Y115533D01*
G01Y114867D02*
X1224210Y115200D01*
X1224627Y115450D01*
X1225210Y115533D01*
X1225627Y115450D01*
X1226127Y115200D01*
G01X1087667Y124000D02*
Y129000D01*
X1089333D01*
X1090000Y128750D01*
X1090500Y128417D01*
X1090917Y127917D01*
X1091250Y127333D01*
X1091333Y126500D01*
X1091250Y125667D01*
X1090917Y125083D01*
X1090500Y124583D01*
X1090000Y124250D01*
X1089333Y124000D01*
X1087667D01*
G01X1093933D02*
Y127333D01*
G01Y126667D02*
X1094350Y127000D01*
X1094767Y127250D01*
X1095350Y127333D01*
X1095767Y127250D01*
X1096267Y127000D01*
G01X1100700Y127333D02*
Y124000D01*
G01Y128667D02*
X1100533Y128750D01*
Y128917D01*
X1100700Y129000D01*
X1100867Y128917D01*
Y128750D01*
X1100700Y128667D01*
G01X1106300Y124000D02*
Y129000D01*
G01X1111900Y124000D02*
Y129000D01*
G01X1121517Y124000D02*
Y129000D01*
X1124683D01*
G01X1123517Y126583D02*
X1121517D01*
G01X1127533Y124000D02*
Y127333D01*
G01Y126667D02*
X1127950Y127000D01*
X1128367Y127250D01*
X1128950Y127333D01*
X1129367Y127250D01*
X1129867Y127000D01*
G01X1134300Y124000D02*
X1133800Y124083D01*
X1133300Y124417D01*
X1132967Y125000D01*
X1132800Y125667D01*
X1132967Y126333D01*
X1133300Y126917D01*
X1133800Y127250D01*
X1134300Y127333D01*
X1134800Y127250D01*
X1135300Y126917D01*
X1135633Y126333D01*
X1135717Y125667D01*
X1135633Y125000D01*
X1135300Y124417D01*
X1134800Y124083D01*
X1134300Y124000D01*
G01X1137400D02*
Y127333D01*
G01Y126417D02*
X1137650Y126833D01*
X1138067Y127167D01*
X1138650Y127333D01*
X1139233Y127167D01*
X1139650Y126833D01*
X1139900Y126417D01*
Y124000D01*
G01Y126417D02*
X1140150Y126833D01*
X1140567Y127167D01*
X1141150Y127333D01*
X1141733Y127167D01*
X1142150Y126833D01*
X1142400Y126333D01*
Y124000D01*
G01X1167483Y122333D02*
X1166650Y123167D01*
X1166233Y124000D01*
Y127333D01*
X1166650Y128167D01*
X1167483Y129000D01*
G01X1174167Y126667D02*
X1174500Y126917D01*
X1174750Y127333D01*
X1174917Y127917D01*
X1174750Y128417D01*
X1174417Y128750D01*
X1173833Y129000D01*
X1171583D01*
Y124000D01*
X1174333D01*
X1174917Y124333D01*
X1175250Y124833D01*
X1175417Y125417D01*
X1175250Y126000D01*
X1174750Y126500D01*
X1174167Y126667D01*
X1171583D01*
G01X1179100Y124000D02*
X1178433Y124083D01*
X1177850Y124417D01*
X1177350Y124917D01*
X1177017Y125500D01*
X1176850Y126167D01*
Y126833D01*
X1177017Y127500D01*
X1177350Y128083D01*
X1177850Y128583D01*
X1178433Y128917D01*
X1179100Y129000D01*
X1179767Y128917D01*
X1180350Y128583D01*
X1180850Y128083D01*
X1181183Y127500D01*
X1181350Y126833D01*
Y126167D01*
X1181183Y125500D01*
X1180850Y124917D01*
X1180350Y124417D01*
X1179767Y124083D01*
X1179100Y124000D01*
G01X1184700Y129000D02*
Y124000D01*
G01X1182783Y129000D02*
X1186617D01*
G01X1190300D02*
Y124000D01*
G01X1188383Y129000D02*
X1192217D01*
G01X1195900Y124000D02*
X1195233Y124083D01*
X1194650Y124417D01*
X1194150Y124917D01*
X1193817Y125500D01*
X1193650Y126167D01*
Y126833D01*
X1193817Y127500D01*
X1194150Y128083D01*
X1194650Y128583D01*
X1195233Y128917D01*
X1195900Y129000D01*
X1196567Y128917D01*
X1197150Y128583D01*
X1197650Y128083D01*
X1197983Y127500D01*
X1198150Y126833D01*
Y126167D01*
X1197983Y125500D01*
X1197650Y124917D01*
X1197150Y124417D01*
X1196567Y124083D01*
X1195900Y124000D01*
G01X1199333D02*
Y129000D01*
X1201500Y124833D01*
X1203667Y129000D01*
Y124000D01*
G01X1207517Y122333D02*
X1208350Y123167D01*
X1208767Y124000D01*
Y127333D01*
X1208350Y128167D01*
X1207517Y129000D01*
G01X1218300D02*
Y124000D01*
G01X1217133Y127333D02*
X1219467D01*
G01X1223900Y124000D02*
X1223400Y124083D01*
X1222900Y124417D01*
X1222567Y125000D01*
X1222400Y125667D01*
X1222567Y126333D01*
X1222900Y126917D01*
X1223400Y127250D01*
X1223900Y127333D01*
X1224400Y127250D01*
X1224900Y126917D01*
X1225233Y126333D01*
X1225317Y125667D01*
X1225233Y125000D01*
X1224900Y124417D01*
X1224400Y124083D01*
X1223900Y124000D01*
G01X1233433Y129000D02*
Y124000D01*
X1236767D01*
G01X1239450Y127333D02*
X1241950Y124000D01*
G01Y127333D02*
X1239450Y124000D01*
G01X1046500Y485833D02*
X1048000Y482500D01*
X1049500Y485833D01*
G01X1053600D02*
Y482500D01*
G01Y487167D02*
X1053433Y487250D01*
Y487417D01*
X1053600Y487500D01*
X1053767Y487417D01*
Y487250D01*
X1053600Y487167D01*
G01X1060700Y482500D02*
Y485833D01*
G01Y485250D02*
X1060367Y485583D01*
X1059867Y485750D01*
X1059283Y485833D01*
X1058700Y485667D01*
X1058200Y485333D01*
X1057867Y484833D01*
X1057700Y484167D01*
X1057867Y483500D01*
X1058200Y483000D01*
X1058700Y482667D01*
X1059283Y482500D01*
X1059867Y482583D01*
X1060367Y482833D01*
X1060700Y483167D01*
G01X1069150Y483083D02*
X1069567Y482750D01*
X1070150Y482500D01*
X1070650D01*
X1071150Y482667D01*
X1071483Y482917D01*
X1071650Y483250D01*
X1071567Y483750D01*
X1071233Y484000D01*
X1069733Y484500D01*
X1069400Y485083D01*
X1069567Y485500D01*
X1069900Y485750D01*
X1070400Y485833D01*
X1070900Y485750D01*
X1071400Y485500D01*
G01X1074583Y482500D02*
Y487500D01*
G01Y485083D02*
X1075000Y485500D01*
X1075417Y485750D01*
X1076083Y485833D01*
X1076583Y485750D01*
X1077167Y485417D01*
X1077417Y484917D01*
Y482500D01*
G01X1083100D02*
Y485833D01*
G01Y485250D02*
X1082767Y485583D01*
X1082267Y485750D01*
X1081683Y485833D01*
X1081100Y485667D01*
X1080600Y485333D01*
X1080267Y484833D01*
X1080100Y484167D01*
X1080267Y483500D01*
X1080600Y483000D01*
X1081100Y482667D01*
X1081683Y482500D01*
X1082267Y482583D01*
X1082767Y482833D01*
X1083100Y483167D01*
G01X1087200Y482500D02*
Y487500D01*
G01X1092800Y482500D02*
Y487500D01*
G01X1102500Y482500D02*
Y487500D01*
G01Y485000D02*
X1102917Y485500D01*
X1103417Y485750D01*
X1103917Y485833D01*
X1104667Y485667D01*
X1105167Y485333D01*
X1105500Y484750D01*
Y484083D01*
X1105333Y483417D01*
X1105000Y482917D01*
X1104417Y482583D01*
X1103917Y482500D01*
X1103417Y482583D01*
X1102917Y482833D01*
X1102500Y483250D01*
G01X1108350Y484750D02*
X1111017D01*
X1110767Y485333D01*
X1110350Y485667D01*
X1109767Y485833D01*
X1109183Y485750D01*
X1108683Y485500D01*
X1108350Y484917D01*
X1108183Y484417D01*
Y483917D01*
X1108350Y483417D01*
X1108767Y482917D01*
X1109267Y482583D01*
X1109850Y482500D01*
X1110433Y482667D01*
X1111017Y483167D01*
G01X1118717Y485833D02*
X1119717Y482500D01*
X1120800Y485833D01*
X1121883Y482500D01*
X1122883Y485833D01*
G01X1126400D02*
Y482500D01*
G01Y487167D02*
X1126233Y487250D01*
Y487417D01*
X1126400Y487500D01*
X1126567Y487417D01*
Y487250D01*
X1126400Y487167D01*
G01X1132000Y487500D02*
Y482500D01*
G01X1130833Y485833D02*
X1133167D01*
G01X1136183Y482500D02*
Y487500D01*
G01Y485083D02*
X1136600Y485500D01*
X1137017Y485750D01*
X1137683Y485833D01*
X1138183Y485750D01*
X1138767Y485417D01*
X1139017Y484917D01*
Y482500D01*
G01X1150467D02*
X1147133Y484167D01*
X1150467Y485833D01*
G01X1160000Y482500D02*
X1160583Y482583D01*
X1161250Y482833D01*
X1161667Y483250D01*
X1161833Y483833D01*
X1161667Y484417D01*
X1161167Y484917D01*
X1160417Y485167D01*
X1159583D01*
X1159083Y485333D01*
X1158667Y485750D01*
X1158500Y486333D01*
X1158750Y486917D01*
X1159333Y487333D01*
X1160000Y487500D01*
X1160667Y487333D01*
X1161250Y486917D01*
X1161500Y486333D01*
X1161333Y485750D01*
X1160917Y485333D01*
X1160417Y485167D01*
X1159583D01*
X1158833Y484917D01*
X1158333Y484417D01*
X1158167Y483833D01*
X1158333Y483250D01*
X1158750Y482833D01*
X1159417Y482583D01*
X1160000Y482500D01*
G01X1165600Y487500D02*
X1164933Y487333D01*
X1164433Y486917D01*
X1164100Y486417D01*
X1163850Y485750D01*
X1163767Y485000D01*
X1163850Y484250D01*
X1164100Y483583D01*
X1164433Y483083D01*
X1164933Y482667D01*
X1165600Y482500D01*
X1166267Y482667D01*
X1166767Y483083D01*
X1167100Y483583D01*
X1167350Y484250D01*
X1167433Y485000D01*
X1167350Y485750D01*
X1167100Y486417D01*
X1166767Y486917D01*
X1166267Y487333D01*
X1165600Y487500D01*
G01X1175300Y482333D02*
X1178300Y487500D01*
G01X1175300D02*
X1174800Y487333D01*
X1174550Y487083D01*
X1174383Y486583D01*
X1174550Y486083D01*
X1174800Y485833D01*
X1175300Y485667D01*
X1175800Y485833D01*
X1176050Y486083D01*
X1176217Y486583D01*
X1176050Y487083D01*
X1175800Y487333D01*
X1175300Y487500D01*
G01X1178300Y484167D02*
X1177800Y484000D01*
X1177550Y483750D01*
X1177383Y483250D01*
X1177550Y482750D01*
X1177800Y482500D01*
X1178300Y482333D01*
X1178800Y482500D01*
X1179050Y482750D01*
X1179217Y483250D01*
X1179050Y483750D01*
X1178800Y484000D01*
X1178300Y484167D01*
G01X1186750Y483083D02*
X1187167Y482750D01*
X1187750Y482500D01*
X1188250D01*
X1188750Y482667D01*
X1189083Y482917D01*
X1189250Y483250D01*
X1189167Y483750D01*
X1188833Y484000D01*
X1187333Y484500D01*
X1187000Y485083D01*
X1187167Y485500D01*
X1187500Y485750D01*
X1188000Y485833D01*
X1188500Y485750D01*
X1189000Y485500D01*
G01X1193600Y482500D02*
X1193100Y482583D01*
X1192600Y482917D01*
X1192267Y483500D01*
X1192100Y484167D01*
X1192267Y484833D01*
X1192600Y485417D01*
X1193100Y485750D01*
X1193600Y485833D01*
X1194100Y485750D01*
X1194600Y485417D01*
X1194933Y484833D01*
X1195017Y484167D01*
X1194933Y483500D01*
X1194600Y482917D01*
X1194100Y482583D01*
X1193600Y482500D01*
G01X1199200D02*
Y487500D01*
G01X1206300D02*
Y482500D01*
G01Y483250D02*
X1205967Y482833D01*
X1205467Y482583D01*
X1204883Y482500D01*
X1204217Y482667D01*
X1203717Y483083D01*
X1203383Y483583D01*
X1203300Y484167D01*
X1203383Y484750D01*
X1203717Y485250D01*
X1204217Y485667D01*
X1204883Y485833D01*
X1205467Y485750D01*
X1205883Y485583D01*
X1206300Y485250D01*
G01X1209150Y484750D02*
X1211817D01*
X1211567Y485333D01*
X1211150Y485667D01*
X1210567Y485833D01*
X1209983Y485750D01*
X1209483Y485500D01*
X1209150Y484917D01*
X1208983Y484417D01*
Y483917D01*
X1209150Y483417D01*
X1209567Y482917D01*
X1210067Y482583D01*
X1210650Y482500D01*
X1211233Y482667D01*
X1211817Y483167D01*
G01X1214833Y482500D02*
Y485833D01*
G01Y485167D02*
X1215250Y485500D01*
X1215667Y485750D01*
X1216250Y485833D01*
X1216667Y485750D01*
X1217167Y485500D01*
G01X1224700Y482500D02*
Y485833D01*
G01Y484917D02*
X1224950Y485333D01*
X1225367Y485667D01*
X1225950Y485833D01*
X1226533Y485667D01*
X1226950Y485333D01*
X1227200Y484917D01*
Y482500D01*
G01Y484917D02*
X1227450Y485333D01*
X1227867Y485667D01*
X1228450Y485833D01*
X1229033Y485667D01*
X1229450Y485333D01*
X1229700Y484833D01*
Y482500D01*
G01X1234300D02*
Y485833D01*
G01Y485250D02*
X1233967Y485583D01*
X1233467Y485750D01*
X1232883Y485833D01*
X1232300Y485667D01*
X1231800Y485333D01*
X1231467Y484833D01*
X1231300Y484167D01*
X1231467Y483500D01*
X1231800Y483000D01*
X1232300Y482667D01*
X1232883Y482500D01*
X1233467Y482583D01*
X1233967Y482833D01*
X1234300Y483167D01*
G01X1237150Y483083D02*
X1237567Y482750D01*
X1238150Y482500D01*
X1238650D01*
X1239150Y482667D01*
X1239483Y482917D01*
X1239650Y483250D01*
X1239567Y483750D01*
X1239233Y484000D01*
X1237733Y484500D01*
X1237400Y485083D01*
X1237567Y485500D01*
X1237900Y485750D01*
X1238400Y485833D01*
X1238900Y485750D01*
X1239400Y485500D01*
G01X1242583Y482500D02*
Y487500D01*
G01X1245250Y485833D02*
X1242583Y483917D01*
G01X1243667Y484667D02*
X1245417Y482500D01*
G01X1045500Y504833D02*
X1047000Y501500D01*
X1048500Y504833D01*
G01X1052600D02*
Y501500D01*
G01Y506167D02*
X1052433Y506250D01*
Y506417D01*
X1052600Y506500D01*
X1052767Y506417D01*
Y506250D01*
X1052600Y506167D01*
G01X1059700Y501500D02*
Y504833D01*
G01Y504250D02*
X1059367Y504583D01*
X1058867Y504750D01*
X1058283Y504833D01*
X1057700Y504667D01*
X1057200Y504333D01*
X1056867Y503833D01*
X1056700Y503167D01*
X1056867Y502500D01*
X1057200Y502000D01*
X1057700Y501667D01*
X1058283Y501500D01*
X1058867Y501583D01*
X1059367Y501833D01*
X1059700Y502167D01*
G01X1068150Y502083D02*
X1068567Y501750D01*
X1069150Y501500D01*
X1069650D01*
X1070150Y501667D01*
X1070483Y501917D01*
X1070650Y502250D01*
X1070567Y502750D01*
X1070233Y503000D01*
X1068733Y503500D01*
X1068400Y504083D01*
X1068567Y504500D01*
X1068900Y504750D01*
X1069400Y504833D01*
X1069900Y504750D01*
X1070400Y504500D01*
G01X1073583Y501500D02*
Y506500D01*
G01Y504083D02*
X1074000Y504500D01*
X1074417Y504750D01*
X1075083Y504833D01*
X1075583Y504750D01*
X1076167Y504417D01*
X1076417Y503917D01*
Y501500D01*
G01X1082100D02*
Y504833D01*
G01Y504250D02*
X1081767Y504583D01*
X1081267Y504750D01*
X1080683Y504833D01*
X1080100Y504667D01*
X1079600Y504333D01*
X1079267Y503833D01*
X1079100Y503167D01*
X1079267Y502500D01*
X1079600Y502000D01*
X1080100Y501667D01*
X1080683Y501500D01*
X1081267Y501583D01*
X1081767Y501833D01*
X1082100Y502167D01*
G01X1086200Y501500D02*
Y506500D01*
G01X1091800Y501500D02*
Y506500D01*
G01X1101500Y501500D02*
Y506500D01*
G01Y504000D02*
X1101917Y504500D01*
X1102417Y504750D01*
X1102917Y504833D01*
X1103667Y504667D01*
X1104167Y504333D01*
X1104500Y503750D01*
Y503083D01*
X1104333Y502417D01*
X1104000Y501917D01*
X1103417Y501583D01*
X1102917Y501500D01*
X1102417Y501583D01*
X1101917Y501833D01*
X1101500Y502250D01*
G01X1107350Y503750D02*
X1110017D01*
X1109767Y504333D01*
X1109350Y504667D01*
X1108767Y504833D01*
X1108183Y504750D01*
X1107683Y504500D01*
X1107350Y503917D01*
X1107183Y503417D01*
Y502917D01*
X1107350Y502417D01*
X1107767Y501917D01*
X1108267Y501583D01*
X1108850Y501500D01*
X1109433Y501667D01*
X1110017Y502167D01*
G01X1118300Y499833D02*
Y504833D01*
G01Y504083D02*
X1118717Y504500D01*
X1119133Y504750D01*
X1119800Y504833D01*
X1120383Y504750D01*
X1120967Y504333D01*
X1121217Y503750D01*
X1121300Y503167D01*
X1121217Y502583D01*
X1120967Y502000D01*
X1120467Y501667D01*
X1119800Y501500D01*
X1119217Y501583D01*
X1118633Y501833D01*
X1118300Y502167D01*
G01X1125400Y501500D02*
Y506500D01*
G01X1129583Y504833D02*
Y502500D01*
X1129917Y501917D01*
X1130417Y501583D01*
X1131000Y501500D01*
X1131583Y501583D01*
X1132083Y501917D01*
X1132417Y502500D01*
G01Y501500D02*
Y504833D01*
G01X1135433Y500250D02*
X1136017Y499917D01*
X1136683Y499833D01*
X1137267Y499917D01*
X1137767Y500333D01*
X1138100Y500917D01*
Y504833D01*
G01Y504167D02*
X1137767Y504500D01*
X1137267Y504750D01*
X1136683Y504833D01*
X1136017Y504667D01*
X1135600Y504333D01*
X1135267Y503750D01*
X1135100Y503167D01*
X1135183Y502667D01*
X1135517Y502083D01*
X1136017Y501667D01*
X1136683Y501500D01*
X1137183Y501583D01*
X1137767Y501917D01*
X1138100Y502250D01*
G01X1141033Y500250D02*
X1141617Y499917D01*
X1142283Y499833D01*
X1142867Y499917D01*
X1143367Y500333D01*
X1143700Y500917D01*
Y504833D01*
G01Y504167D02*
X1143367Y504500D01*
X1142867Y504750D01*
X1142283Y504833D01*
X1141617Y504667D01*
X1141200Y504333D01*
X1140867Y503750D01*
X1140700Y503167D01*
X1140783Y502667D01*
X1141117Y502083D01*
X1141617Y501667D01*
X1142283Y501500D01*
X1142783Y501583D01*
X1143367Y501917D01*
X1143700Y502250D01*
G01X1146550Y503750D02*
X1149217D01*
X1148967Y504333D01*
X1148550Y504667D01*
X1147967Y504833D01*
X1147383Y504750D01*
X1146883Y504500D01*
X1146550Y503917D01*
X1146383Y503417D01*
Y502917D01*
X1146550Y502417D01*
X1146967Y501917D01*
X1147467Y501583D01*
X1148050Y501500D01*
X1148633Y501667D01*
X1149217Y502167D01*
G01X1154900Y506500D02*
Y501500D01*
G01Y502250D02*
X1154567Y501833D01*
X1154067Y501583D01*
X1153483Y501500D01*
X1152817Y501667D01*
X1152317Y502083D01*
X1151983Y502583D01*
X1151900Y503167D01*
X1151983Y503750D01*
X1152317Y504250D01*
X1152817Y504667D01*
X1153483Y504833D01*
X1154067Y504750D01*
X1154483Y504583D01*
X1154900Y504250D01*
G01X1162517Y504833D02*
X1163517Y501500D01*
X1164600Y504833D01*
X1165683Y501500D01*
X1166683Y504833D01*
G01X1170200D02*
Y501500D01*
G01Y506167D02*
X1170033Y506250D01*
Y506417D01*
X1170200Y506500D01*
X1170367Y506417D01*
Y506250D01*
X1170200Y506167D01*
G01X1175800Y506500D02*
Y501500D01*
G01X1174633Y504833D02*
X1176967D01*
G01X1179983Y501500D02*
Y506500D01*
G01Y504083D02*
X1180400Y504500D01*
X1180817Y504750D01*
X1181483Y504833D01*
X1181983Y504750D01*
X1182567Y504417D01*
X1182817Y503917D01*
Y501500D01*
G01X1194267D02*
X1190933Y503167D01*
X1194267Y504833D01*
G01X1201967Y502250D02*
X1202467Y501833D01*
X1203050Y501583D01*
X1203800Y501500D01*
X1204550Y501667D01*
X1205133Y502000D01*
X1205550Y502583D01*
X1205633Y503250D01*
X1205467Y503917D01*
X1205050Y504333D01*
X1204467Y504667D01*
X1203883Y504750D01*
X1203300Y504667D01*
X1202550Y504333D01*
X1202800Y506500D01*
X1205050D01*
G01X1209400D02*
X1208733Y506333D01*
X1208233Y505917D01*
X1207900Y505417D01*
X1207650Y504750D01*
X1207567Y504000D01*
X1207650Y503250D01*
X1207900Y502583D01*
X1208233Y502083D01*
X1208733Y501667D01*
X1209400Y501500D01*
X1210067Y501667D01*
X1210567Y502083D01*
X1210900Y502583D01*
X1211150Y503250D01*
X1211233Y504000D01*
X1211150Y504750D01*
X1210900Y505417D01*
X1210567Y505917D01*
X1210067Y506333D01*
X1209400Y506500D01*
G01X1219100Y501333D02*
X1222100Y506500D01*
G01X1219100D02*
X1218600Y506333D01*
X1218350Y506083D01*
X1218183Y505583D01*
X1218350Y505083D01*
X1218600Y504833D01*
X1219100Y504667D01*
X1219600Y504833D01*
X1219850Y505083D01*
X1220017Y505583D01*
X1219850Y506083D01*
X1219600Y506333D01*
X1219100Y506500D01*
G01X1222100Y503167D02*
X1221600Y503000D01*
X1221350Y502750D01*
X1221183Y502250D01*
X1221350Y501750D01*
X1221600Y501500D01*
X1222100Y501333D01*
X1222600Y501500D01*
X1222850Y501750D01*
X1223017Y502250D01*
X1222850Y502750D01*
X1222600Y503000D01*
X1222100Y503167D01*
G01X1230550Y502083D02*
X1230967Y501750D01*
X1231550Y501500D01*
X1232050D01*
X1232550Y501667D01*
X1232883Y501917D01*
X1233050Y502250D01*
X1232967Y502750D01*
X1232633Y503000D01*
X1231133Y503500D01*
X1230800Y504083D01*
X1230967Y504500D01*
X1231300Y504750D01*
X1231800Y504833D01*
X1232300Y504750D01*
X1232800Y504500D01*
G01X1237400Y501500D02*
X1236900Y501583D01*
X1236400Y501917D01*
X1236067Y502500D01*
X1235900Y503167D01*
X1236067Y503833D01*
X1236400Y504417D01*
X1236900Y504750D01*
X1237400Y504833D01*
X1237900Y504750D01*
X1238400Y504417D01*
X1238733Y503833D01*
X1238817Y503167D01*
X1238733Y502500D01*
X1238400Y501917D01*
X1237900Y501583D01*
X1237400Y501500D01*
G01X1243000D02*
Y506500D01*
G01X1250100D02*
Y501500D01*
G01Y502250D02*
X1249767Y501833D01*
X1249267Y501583D01*
X1248683Y501500D01*
X1248017Y501667D01*
X1247517Y502083D01*
X1247183Y502583D01*
X1247100Y503167D01*
X1247183Y503750D01*
X1247517Y504250D01*
X1248017Y504667D01*
X1248683Y504833D01*
X1249267Y504750D01*
X1249683Y504583D01*
X1250100Y504250D01*
G01X1252950Y503750D02*
X1255617D01*
X1255367Y504333D01*
X1254950Y504667D01*
X1254367Y504833D01*
X1253783Y504750D01*
X1253283Y504500D01*
X1252950Y503917D01*
X1252783Y503417D01*
Y502917D01*
X1252950Y502417D01*
X1253367Y501917D01*
X1253867Y501583D01*
X1254450Y501500D01*
X1255033Y501667D01*
X1255617Y502167D01*
G01X1258633Y501500D02*
Y504833D01*
G01Y504167D02*
X1259050Y504500D01*
X1259467Y504750D01*
X1260050Y504833D01*
X1260467Y504750D01*
X1260967Y504500D01*
G01X1268500Y501500D02*
Y504833D01*
G01Y503917D02*
X1268750Y504333D01*
X1269167Y504667D01*
X1269750Y504833D01*
X1270333Y504667D01*
X1270750Y504333D01*
X1271000Y503917D01*
Y501500D01*
G01Y503917D02*
X1271250Y504333D01*
X1271667Y504667D01*
X1272250Y504833D01*
X1272833Y504667D01*
X1273250Y504333D01*
X1273500Y503833D01*
Y501500D01*
G01X1278100D02*
Y504833D01*
G01Y504250D02*
X1277767Y504583D01*
X1277267Y504750D01*
X1276683Y504833D01*
X1276100Y504667D01*
X1275600Y504333D01*
X1275267Y503833D01*
X1275100Y503167D01*
X1275267Y502500D01*
X1275600Y502000D01*
X1276100Y501667D01*
X1276683Y501500D01*
X1277267Y501583D01*
X1277767Y501833D01*
X1278100Y502167D01*
G01X1280950Y502083D02*
X1281367Y501750D01*
X1281950Y501500D01*
X1282450D01*
X1282950Y501667D01*
X1283283Y501917D01*
X1283450Y502250D01*
X1283367Y502750D01*
X1283033Y503000D01*
X1281533Y503500D01*
X1281200Y504083D01*
X1281367Y504500D01*
X1281700Y504750D01*
X1282200Y504833D01*
X1282700Y504750D01*
X1283200Y504500D01*
G01X1286383Y501500D02*
Y506500D01*
G01X1289050Y504833D02*
X1286383Y502917D01*
G01X1287467Y503667D02*
X1289217Y501500D01*
G01X1293233Y500583D02*
X1293567Y501667D01*
G01X1136167Y157700D02*
Y162700D01*
X1137833D01*
X1138500Y162450D01*
X1139000Y162117D01*
X1139417Y161617D01*
X1139750Y161033D01*
X1139833Y160200D01*
X1139750Y159367D01*
X1139417Y158783D01*
X1139000Y158283D01*
X1138500Y157950D01*
X1137833Y157700D01*
X1136167D01*
G01X1142017Y161867D02*
X1142517Y162367D01*
X1143100Y162617D01*
X1143767Y162700D01*
X1144600Y162533D01*
X1145183Y162117D01*
X1145350Y161617D01*
X1145267Y161117D01*
X1144933Y160700D01*
X1143267Y159867D01*
X1142517Y159283D01*
X1142017Y158450D01*
X1141850Y157700D01*
X1145350D01*
G01X1135167Y315700D02*
Y320700D01*
X1136833D01*
X1137500Y320450D01*
X1138000Y320117D01*
X1138417Y319617D01*
X1138750Y319033D01*
X1138833Y318200D01*
X1138750Y317367D01*
X1138417Y316783D01*
X1138000Y316283D01*
X1137500Y315950D01*
X1136833Y315700D01*
X1135167D01*
G01X1142600D02*
Y320700D01*
X1141600Y319700D01*
G01Y315700D02*
X1143600D01*
G01X1109833Y590500D02*
Y595500D01*
X1111833D01*
X1112500Y595250D01*
X1113000Y594667D01*
X1113167Y594000D01*
X1113000Y593333D01*
X1112583Y592833D01*
X1111833Y592583D01*
X1109833D01*
G01X1117100Y590500D02*
Y595500D01*
G01X1121283Y593833D02*
Y591500D01*
X1121617Y590917D01*
X1122117Y590583D01*
X1122700Y590500D01*
X1123283Y590583D01*
X1123783Y590917D01*
X1124117Y591500D01*
G01Y590500D02*
Y593833D01*
G01X1127133Y589250D02*
X1127717Y588917D01*
X1128383Y588833D01*
X1128967Y588917D01*
X1129467Y589333D01*
X1129800Y589917D01*
Y593833D01*
G01Y593167D02*
X1129467Y593500D01*
X1128967Y593750D01*
X1128383Y593833D01*
X1127717Y593667D01*
X1127300Y593333D01*
X1126967Y592750D01*
X1126800Y592167D01*
X1126883Y591667D01*
X1127217Y591083D01*
X1127717Y590667D01*
X1128383Y590500D01*
X1128883Y590583D01*
X1129467Y590917D01*
X1129800Y591250D01*
G01X1132733Y589250D02*
X1133317Y588917D01*
X1133983Y588833D01*
X1134567Y588917D01*
X1135067Y589333D01*
X1135400Y589917D01*
Y593833D01*
G01Y593167D02*
X1135067Y593500D01*
X1134567Y593750D01*
X1133983Y593833D01*
X1133317Y593667D01*
X1132900Y593333D01*
X1132567Y592750D01*
X1132400Y592167D01*
X1132483Y591667D01*
X1132817Y591083D01*
X1133317Y590667D01*
X1133983Y590500D01*
X1134483Y590583D01*
X1135067Y590917D01*
X1135400Y591250D01*
G01X1139500Y593833D02*
Y590500D01*
G01Y595167D02*
X1139333Y595250D01*
Y595417D01*
X1139500Y595500D01*
X1139667Y595417D01*
Y595250D01*
X1139500Y595167D01*
G01X1143683Y590500D02*
Y593833D01*
G01Y593000D02*
X1144017Y593417D01*
X1144517Y593750D01*
X1145183Y593833D01*
X1145767Y593750D01*
X1146267Y593417D01*
X1146517Y592833D01*
Y590500D01*
G01X1149533Y589250D02*
X1150117Y588917D01*
X1150783Y588833D01*
X1151367Y588917D01*
X1151867Y589333D01*
X1152200Y589917D01*
Y593833D01*
G01Y593167D02*
X1151867Y593500D01*
X1151367Y593750D01*
X1150783Y593833D01*
X1150117Y593667D01*
X1149700Y593333D01*
X1149367Y592750D01*
X1149200Y592167D01*
X1149283Y591667D01*
X1149617Y591083D01*
X1150117Y590667D01*
X1150783Y590500D01*
X1151283Y590583D01*
X1151867Y590917D01*
X1152200Y591250D01*
G01X1163233Y593417D02*
X1162650Y593750D01*
X1162150Y593833D01*
X1161483Y593667D01*
X1160983Y593333D01*
X1160650Y592750D01*
X1160567Y592167D01*
X1160650Y591583D01*
X1160983Y591083D01*
X1161483Y590667D01*
X1162150Y590500D01*
X1162733Y590667D01*
X1163233Y591000D01*
G01X1166333Y590500D02*
Y593833D01*
G01Y593167D02*
X1166750Y593500D01*
X1167167Y593750D01*
X1167750Y593833D01*
X1168167Y593750D01*
X1168667Y593500D01*
G01X1173100Y593833D02*
Y590500D01*
G01Y595167D02*
X1172933Y595250D01*
Y595417D01*
X1173100Y595500D01*
X1173267Y595417D01*
Y595250D01*
X1173100Y595167D01*
G01X1178700Y595500D02*
Y590500D01*
G01X1177533Y593833D02*
X1179867D01*
G01X1183050Y592750D02*
X1185717D01*
X1185467Y593333D01*
X1185050Y593667D01*
X1184467Y593833D01*
X1183883Y593750D01*
X1183383Y593500D01*
X1183050Y592917D01*
X1182883Y592417D01*
Y591917D01*
X1183050Y591417D01*
X1183467Y590917D01*
X1183967Y590583D01*
X1184550Y590500D01*
X1185133Y590667D01*
X1185717Y591167D01*
G01X1188733Y590500D02*
Y593833D01*
G01Y593167D02*
X1189150Y593500D01*
X1189567Y593750D01*
X1190150Y593833D01*
X1190567Y593750D01*
X1191067Y593500D01*
G01X1195500Y593833D02*
Y590500D01*
G01Y595167D02*
X1195333Y595250D01*
Y595417D01*
X1195500Y595500D01*
X1195667Y595417D01*
Y595250D01*
X1195500Y595167D01*
G01X1202600Y590500D02*
Y593833D01*
G01Y593250D02*
X1202267Y593583D01*
X1201767Y593750D01*
X1201183Y593833D01*
X1200600Y593667D01*
X1200100Y593333D01*
X1199767Y592833D01*
X1199600Y592167D01*
X1199767Y591500D01*
X1200100Y591000D01*
X1200600Y590667D01*
X1201183Y590500D01*
X1201767Y590583D01*
X1202267Y590833D01*
X1202600Y591167D01*
G01X1136833Y619917D02*
X1136250Y620250D01*
X1135750Y620333D01*
X1135083Y620167D01*
X1134583Y619833D01*
X1134250Y619250D01*
X1134167Y618667D01*
X1134250Y618083D01*
X1134583Y617583D01*
X1135083Y617167D01*
X1135750Y617000D01*
X1136333Y617167D01*
X1136833Y617500D01*
G01X1141100Y617000D02*
X1140600Y617083D01*
X1140100Y617417D01*
X1139767Y618000D01*
X1139600Y618667D01*
X1139767Y619333D01*
X1140100Y619917D01*
X1140600Y620250D01*
X1141100Y620333D01*
X1141600Y620250D01*
X1142100Y619917D01*
X1142433Y619333D01*
X1142517Y618667D01*
X1142433Y618000D01*
X1142100Y617417D01*
X1141600Y617083D01*
X1141100Y617000D01*
G01X1145200Y615333D02*
Y620333D01*
G01Y619583D02*
X1145617Y620000D01*
X1146033Y620250D01*
X1146700Y620333D01*
X1147283Y620250D01*
X1147867Y619833D01*
X1148117Y619250D01*
X1148200Y618667D01*
X1148117Y618083D01*
X1147867Y617500D01*
X1147367Y617167D01*
X1146700Y617000D01*
X1146117Y617083D01*
X1145533Y617333D01*
X1145200Y617667D01*
G01X1150800Y615333D02*
Y620333D01*
G01Y619583D02*
X1151217Y620000D01*
X1151633Y620250D01*
X1152300Y620333D01*
X1152883Y620250D01*
X1153467Y619833D01*
X1153717Y619250D01*
X1153800Y618667D01*
X1153717Y618083D01*
X1153467Y617500D01*
X1152967Y617167D01*
X1152300Y617000D01*
X1151717Y617083D01*
X1151133Y617333D01*
X1150800Y617667D01*
G01X1156650Y619250D02*
X1159317D01*
X1159067Y619833D01*
X1158650Y620167D01*
X1158067Y620333D01*
X1157483Y620250D01*
X1156983Y620000D01*
X1156650Y619417D01*
X1156483Y618917D01*
Y618417D01*
X1156650Y617917D01*
X1157067Y617417D01*
X1157567Y617083D01*
X1158150Y617000D01*
X1158733Y617167D01*
X1159317Y617667D01*
G01X1162333Y617000D02*
Y620333D01*
G01Y619667D02*
X1162750Y620000D01*
X1163167Y620250D01*
X1163750Y620333D01*
X1164167Y620250D01*
X1164667Y620000D01*
G01X1106417Y735500D02*
X1108500Y730500D01*
X1110583Y735500D01*
G01X1113100D02*
X1115100D01*
G01X1114100D02*
Y730500D01*
G01X1113100D02*
X1115100D01*
G01X1118033D02*
Y735500D01*
X1120033D01*
X1120700Y735250D01*
X1121200Y734667D01*
X1121367Y734000D01*
X1121200Y733333D01*
X1120783Y732833D01*
X1120033Y732583D01*
X1118033D01*
G01X1184667Y150367D02*
X1185000Y150617D01*
X1185250Y151033D01*
X1185417Y151617D01*
X1185250Y152117D01*
X1184917Y152450D01*
X1184333Y152700D01*
X1182083D01*
Y147700D01*
X1184833D01*
X1185417Y148033D01*
X1185750Y148533D01*
X1185917Y149117D01*
X1185750Y149700D01*
X1185250Y150200D01*
X1184667Y150367D01*
X1182083D01*
G01X1187517Y147700D02*
X1189600Y152700D01*
X1191683Y147700D01*
G01X1190933Y149450D02*
X1188267D01*
G01X1197033Y152283D02*
X1196533Y152533D01*
X1195950Y152700D01*
X1195283D01*
X1194533Y152450D01*
X1193950Y152033D01*
X1193533Y151533D01*
X1193200Y150700D01*
X1193117Y149950D01*
X1193283Y149200D01*
X1193533Y148700D01*
X1194033Y148200D01*
X1194617Y147867D01*
X1195200Y147700D01*
X1195783D01*
X1196367Y147867D01*
X1196867Y148117D01*
X1197283Y148450D01*
G01X1198967Y147700D02*
Y152700D01*
G01X1202133D02*
X1198967Y149617D01*
G01X1202633Y147700D02*
X1200383Y151033D01*
G01X1210167Y147700D02*
Y152700D01*
X1211833D01*
X1212500Y152450D01*
X1213000Y152117D01*
X1213417Y151617D01*
X1213750Y151033D01*
X1213833Y150200D01*
X1213750Y149367D01*
X1213417Y148783D01*
X1213000Y148283D01*
X1212500Y147950D01*
X1211833Y147700D01*
X1210167D01*
G01X1215933D02*
Y152700D01*
X1218017D01*
X1218683Y152450D01*
X1219100Y152117D01*
X1219267Y151450D01*
X1219100Y150783D01*
X1218600Y150367D01*
X1218017Y150117D01*
X1215933D01*
G01X1218017D02*
X1219267Y147700D01*
G01X1222200Y152700D02*
X1224200D01*
G01X1223200D02*
Y147700D01*
G01X1222200D02*
X1224200D01*
G01X1227133Y152700D02*
Y147700D01*
X1230467D01*
G01X1232733Y152700D02*
Y147700D01*
X1236067D01*
G01X1259900D02*
Y151033D01*
G01Y150117D02*
X1260150Y150533D01*
X1260567Y150867D01*
X1261150Y151033D01*
X1261733Y150867D01*
X1262150Y150533D01*
X1262400Y150117D01*
Y147700D01*
G01Y150117D02*
X1262650Y150533D01*
X1263067Y150867D01*
X1263650Y151033D01*
X1264233Y150867D01*
X1264650Y150533D01*
X1264900Y150033D01*
Y147700D01*
G01X1268000Y151033D02*
Y147700D01*
G01Y152367D02*
X1267833Y152450D01*
Y152617D01*
X1268000Y152700D01*
X1268167Y152617D01*
Y152450D01*
X1268000Y152367D01*
G01X1273600Y147700D02*
Y152700D01*
G01X1277950Y148283D02*
X1278367Y147950D01*
X1278950Y147700D01*
X1279450D01*
X1279950Y147867D01*
X1280283Y148117D01*
X1280450Y148450D01*
X1280367Y148950D01*
X1280033Y149200D01*
X1278533Y149700D01*
X1278200Y150283D01*
X1278367Y150700D01*
X1278700Y150950D01*
X1279200Y151033D01*
X1279700Y150950D01*
X1280200Y150700D01*
G01X1284383Y146033D02*
X1283550Y146867D01*
X1283133Y147700D01*
Y151033D01*
X1283550Y151867D01*
X1284383Y152700D01*
G01X1288483Y147700D02*
Y152700D01*
X1292317Y147700D01*
Y152700D01*
G01X1294333Y147700D02*
Y152700D01*
X1296333D01*
X1297000Y152450D01*
X1297500Y151867D01*
X1297667Y151200D01*
X1297500Y150533D01*
X1297083Y150033D01*
X1296333Y149783D01*
X1294333D01*
G01X1301600Y152700D02*
Y147700D01*
G01X1299683Y152700D02*
X1303517D01*
G01X1305450Y147700D02*
Y152700D01*
G01X1308950D02*
Y147700D01*
G01Y150200D02*
X1305450D01*
G01X1313217Y146033D02*
X1314050Y146867D01*
X1314467Y147700D01*
Y151033D01*
X1314050Y151867D01*
X1313217Y152700D01*
G01X1178750Y315500D02*
Y320500D01*
G01X1182250D02*
Y315500D01*
G01Y318000D02*
X1178750D01*
G01X1186100Y315500D02*
X1185433Y315583D01*
X1184850Y315917D01*
X1184350Y316417D01*
X1184017Y317000D01*
X1183850Y317667D01*
Y318333D01*
X1184017Y319000D01*
X1184350Y319583D01*
X1184850Y320083D01*
X1185433Y320417D01*
X1186100Y320500D01*
X1186767Y320417D01*
X1187350Y320083D01*
X1187850Y319583D01*
X1188183Y319000D01*
X1188350Y318333D01*
Y317667D01*
X1188183Y317000D01*
X1187850Y316417D01*
X1187350Y315917D01*
X1186767Y315583D01*
X1186100Y315500D01*
G01X1190033Y320500D02*
Y315500D01*
X1193367D01*
G01X1198967D02*
X1195633D01*
Y320500D01*
X1198967D01*
G01X1197633Y318083D02*
X1195633D01*
G01X1222800Y315500D02*
Y318833D01*
G01Y317917D02*
X1223050Y318333D01*
X1223467Y318667D01*
X1224050Y318833D01*
X1224633Y318667D01*
X1225050Y318333D01*
X1225300Y317917D01*
Y315500D01*
G01Y317917D02*
X1225550Y318333D01*
X1225967Y318667D01*
X1226550Y318833D01*
X1227133Y318667D01*
X1227550Y318333D01*
X1227800Y317833D01*
Y315500D01*
G01X1230900Y318833D02*
Y315500D01*
G01Y320167D02*
X1230733Y320250D01*
Y320417D01*
X1230900Y320500D01*
X1231067Y320417D01*
Y320250D01*
X1230900Y320167D01*
G01X1236500Y315500D02*
Y320500D01*
G01X1240850Y316083D02*
X1241267Y315750D01*
X1241850Y315500D01*
X1242350D01*
X1242850Y315667D01*
X1243183Y315917D01*
X1243350Y316250D01*
X1243267Y316750D01*
X1242933Y317000D01*
X1241433Y317500D01*
X1241100Y318083D01*
X1241267Y318500D01*
X1241600Y318750D01*
X1242100Y318833D01*
X1242600Y318750D01*
X1243100Y318500D01*
G01X1247283Y313833D02*
X1246450Y314667D01*
X1246033Y315500D01*
Y318833D01*
X1246450Y319667D01*
X1247283Y320500D01*
G01X1251633Y315500D02*
Y320500D01*
X1253633D01*
X1254300Y320250D01*
X1254800Y319667D01*
X1254967Y319000D01*
X1254800Y318333D01*
X1254383Y317833D01*
X1253633Y317583D01*
X1251633D01*
G01X1258900Y320500D02*
Y315500D01*
G01X1256983Y320500D02*
X1260817D01*
G01X1262750Y315500D02*
Y320500D01*
G01X1266250D02*
Y315500D01*
G01Y318000D02*
X1262750D01*
G01X1270517Y313833D02*
X1271350Y314667D01*
X1271767Y315500D01*
Y318833D01*
X1271350Y319667D01*
X1270517Y320500D01*
G01X1180417Y734500D02*
X1182500Y729500D01*
X1184583Y734500D01*
G01X1188100Y729500D02*
X1187433Y729583D01*
X1186850Y729917D01*
X1186350Y730417D01*
X1186017Y731000D01*
X1185850Y731667D01*
Y732333D01*
X1186017Y733000D01*
X1186350Y733583D01*
X1186850Y734083D01*
X1187433Y734417D01*
X1188100Y734500D01*
X1188767Y734417D01*
X1189350Y734083D01*
X1189850Y733583D01*
X1190183Y733000D01*
X1190350Y732333D01*
Y731667D01*
X1190183Y731000D01*
X1189850Y730417D01*
X1189350Y729917D01*
X1188767Y729583D01*
X1188100Y729500D01*
G01X1192033D02*
Y734500D01*
X1194033D01*
X1194700Y734250D01*
X1195200Y733667D01*
X1195367Y733000D01*
X1195200Y732333D01*
X1194783Y731833D01*
X1194033Y731583D01*
X1192033D01*
G01X1210333Y218700D02*
Y213700D01*
X1213667D01*
G01X1216350Y217033D02*
X1218850Y213700D01*
G01Y217033D02*
X1216350Y213700D01*
G01X1207333Y260500D02*
Y255500D01*
X1210667D01*
G01X1213183D02*
Y258833D01*
G01Y258000D02*
X1213517Y258417D01*
X1214017Y258750D01*
X1214683Y258833D01*
X1215267Y258750D01*
X1215767Y258417D01*
X1216017Y257833D01*
Y255500D01*
G01X1218250Y281583D02*
X1218667Y281250D01*
X1219250Y281000D01*
X1219750D01*
X1220250Y281167D01*
X1220583Y281417D01*
X1220750Y281750D01*
X1220667Y282250D01*
X1220333Y282500D01*
X1218833Y283000D01*
X1218500Y283583D01*
X1218667Y284000D01*
X1219000Y284250D01*
X1219500Y284333D01*
X1220000Y284250D01*
X1220500Y284000D01*
G01X1225100Y286000D02*
Y281000D01*
G01X1223933Y284333D02*
X1226267D01*
G01X1229283D02*
Y282000D01*
X1229617Y281417D01*
X1230117Y281083D01*
X1230700Y281000D01*
X1231283Y281083D01*
X1231783Y281417D01*
X1232117Y282000D01*
G01Y281000D02*
Y284333D01*
G01X1234800Y281000D02*
Y286000D01*
G01Y283500D02*
X1235217Y284000D01*
X1235717Y284250D01*
X1236217Y284333D01*
X1236967Y284167D01*
X1237467Y283833D01*
X1237800Y283250D01*
Y282583D01*
X1237633Y281917D01*
X1237300Y281417D01*
X1236717Y281083D01*
X1236217Y281000D01*
X1235717Y281083D01*
X1235217Y281333D01*
X1234800Y281750D01*
G01X1247500Y281000D02*
Y286000D01*
G01X1251850Y283250D02*
X1254517D01*
X1254267Y283833D01*
X1253850Y284167D01*
X1253267Y284333D01*
X1252683Y284250D01*
X1252183Y284000D01*
X1251850Y283417D01*
X1251683Y282917D01*
Y282417D01*
X1251850Y281917D01*
X1252267Y281417D01*
X1252767Y281083D01*
X1253350Y281000D01*
X1253933Y281167D01*
X1254517Y281667D01*
G01X1257283Y281000D02*
Y284333D01*
G01Y283500D02*
X1257617Y283917D01*
X1258117Y284250D01*
X1258783Y284333D01*
X1259367Y284250D01*
X1259867Y283917D01*
X1260117Y283333D01*
Y281000D01*
G01X1263133Y279750D02*
X1263717Y279417D01*
X1264383Y279333D01*
X1264967Y279417D01*
X1265467Y279833D01*
X1265800Y280417D01*
Y284333D01*
G01Y283667D02*
X1265467Y284000D01*
X1264967Y284250D01*
X1264383Y284333D01*
X1263717Y284167D01*
X1263300Y283833D01*
X1262967Y283250D01*
X1262800Y282667D01*
X1262883Y282167D01*
X1263217Y281583D01*
X1263717Y281167D01*
X1264383Y281000D01*
X1264883Y281083D01*
X1265467Y281417D01*
X1265800Y281750D01*
G01X1269900Y286000D02*
Y281000D01*
G01X1268733Y284333D02*
X1271067D01*
G01X1274083Y281000D02*
Y286000D01*
G01Y283583D02*
X1274500Y284000D01*
X1274917Y284250D01*
X1275583Y284333D01*
X1276083Y284250D01*
X1276667Y283917D01*
X1276917Y283417D01*
Y281000D01*
G01X1280017Y281917D02*
X1282183D01*
G01Y283417D02*
X1280017D01*
G01X1285117Y283083D02*
X1285700Y283667D01*
X1286200Y284000D01*
X1286867Y284167D01*
X1287450Y284000D01*
X1287867Y283667D01*
X1288200Y283167D01*
X1288283Y282583D01*
X1288200Y282083D01*
X1287867Y281583D01*
X1287367Y281167D01*
X1286783Y281000D01*
X1286117Y281167D01*
X1285533Y281667D01*
X1285200Y282417D01*
X1285117Y283250D01*
X1285283Y284333D01*
X1285533Y284917D01*
X1285950Y285500D01*
X1286533Y285917D01*
X1287117Y286000D01*
X1287700Y285833D01*
X1288117Y285417D01*
G01X1291383Y282667D02*
X1293383D01*
G01X1292300Y283750D02*
Y281583D01*
G01X1296400Y280833D02*
X1299400Y286000D01*
G01X1302417Y282667D02*
X1304583D01*
G01X1307267Y281750D02*
X1307767Y281333D01*
X1308350Y281083D01*
X1309100Y281000D01*
X1309850Y281167D01*
X1310433Y281500D01*
X1310850Y282083D01*
X1310933Y282750D01*
X1310767Y283417D01*
X1310350Y283833D01*
X1309767Y284167D01*
X1309183Y284250D01*
X1308600Y284167D01*
X1307850Y283833D01*
X1308100Y286000D01*
X1310350D01*
G01X1312200Y281000D02*
Y284333D01*
G01Y283417D02*
X1312450Y283833D01*
X1312867Y284167D01*
X1313450Y284333D01*
X1314033Y284167D01*
X1314450Y283833D01*
X1314700Y283417D01*
Y281000D01*
G01Y283417D02*
X1314950Y283833D01*
X1315367Y284167D01*
X1315950Y284333D01*
X1316533Y284167D01*
X1316950Y283833D01*
X1317200Y283333D01*
Y281000D01*
G01X1320300Y284333D02*
Y281000D01*
G01Y285667D02*
X1320133Y285750D01*
Y285917D01*
X1320300Y286000D01*
X1320467Y285917D01*
Y285750D01*
X1320300Y285667D01*
G01X1325900Y281000D02*
Y286000D01*
G01X1234540Y850500D02*
Y782000D01*
G01X1242793Y785443D02*
X1241960Y786277D01*
X1241543Y787110D01*
Y790443D01*
X1241960Y791277D01*
X1242793Y792110D01*
G01X1248810Y787110D02*
Y792110D01*
X1247810Y791110D01*
G01Y787110D02*
X1249810D01*
G01X1254410Y786943D02*
X1254243Y787027D01*
Y787193D01*
X1254410Y787277D01*
X1254577Y787193D01*
Y787027D01*
X1254410Y786943D01*
G01X1258427Y791277D02*
X1258927Y791777D01*
X1259510Y792027D01*
X1260177Y792110D01*
X1261010Y791943D01*
X1261593Y791527D01*
X1261760Y791027D01*
X1261677Y790527D01*
X1261343Y790110D01*
X1259677Y789277D01*
X1258927Y788693D01*
X1258427Y787860D01*
X1258260Y787110D01*
X1261760D01*
G01X1263110D02*
Y790443D01*
G01Y789527D02*
X1263360Y789943D01*
X1263777Y790277D01*
X1264360Y790443D01*
X1264943Y790277D01*
X1265360Y789943D01*
X1265610Y789527D01*
Y787110D01*
G01Y789527D02*
X1265860Y789943D01*
X1266277Y790277D01*
X1266860Y790443D01*
X1267443Y790277D01*
X1267860Y789943D01*
X1268110Y789443D01*
Y787110D01*
G01X1268710D02*
Y790443D01*
G01Y789527D02*
X1268960Y789943D01*
X1269377Y790277D01*
X1269960Y790443D01*
X1270543Y790277D01*
X1270960Y789943D01*
X1271210Y789527D01*
Y787110D01*
G01Y789527D02*
X1271460Y789943D01*
X1271877Y790277D01*
X1272460Y790443D01*
X1273043Y790277D01*
X1273460Y789943D01*
X1273710Y789443D01*
Y787110D01*
G01X1280243D02*
Y792110D01*
X1282410Y787943D01*
X1284577Y792110D01*
Y787110D01*
G01X1289510D02*
Y790443D01*
G01Y789860D02*
X1289177Y790193D01*
X1288677Y790360D01*
X1288093Y790443D01*
X1287510Y790277D01*
X1287010Y789943D01*
X1286677Y789443D01*
X1286510Y788777D01*
X1286677Y788110D01*
X1287010Y787610D01*
X1287510Y787277D01*
X1288093Y787110D01*
X1288677Y787193D01*
X1289177Y787443D01*
X1289510Y787777D01*
G01X1292360Y790443D02*
X1294860Y787110D01*
G01Y790443D02*
X1292360Y787110D01*
G01X1299627Y785443D02*
X1300460Y786277D01*
X1300877Y787110D01*
Y790443D01*
X1300460Y791277D01*
X1299627Y792110D01*
G01X1241083Y826667D02*
X1243083D01*
G01X1242000Y827750D02*
Y825583D01*
G01X1246100Y824833D02*
X1249100Y830000D01*
G01X1252117Y826667D02*
X1254283D01*
G01X1256967Y825750D02*
X1257467Y825333D01*
X1258050Y825083D01*
X1258800Y825000D01*
X1259550Y825167D01*
X1260133Y825500D01*
X1260550Y826083D01*
X1260633Y826750D01*
X1260467Y827417D01*
X1260050Y827833D01*
X1259467Y828167D01*
X1258883Y828250D01*
X1258300Y828167D01*
X1257550Y827833D01*
X1257800Y830000D01*
X1260050D01*
G01X1261900Y825000D02*
Y828333D01*
G01Y827417D02*
X1262150Y827833D01*
X1262567Y828167D01*
X1263150Y828333D01*
X1263733Y828167D01*
X1264150Y827833D01*
X1264400Y827417D01*
Y825000D01*
G01Y827417D02*
X1264650Y827833D01*
X1265067Y828167D01*
X1265650Y828333D01*
X1266233Y828167D01*
X1266650Y827833D01*
X1266900Y827333D01*
Y825000D01*
G01X1270000Y828333D02*
Y825000D01*
G01Y829667D02*
X1269833Y829750D01*
Y829917D01*
X1270000Y830000D01*
X1270167Y829917D01*
Y829750D01*
X1270000Y829667D01*
G01X1275600Y825000D02*
Y830000D01*
G01X1241083Y811667D02*
X1243083D01*
G01X1242000Y812750D02*
Y810583D01*
G01X1246100Y809833D02*
X1249100Y815000D01*
G01X1252117Y811667D02*
X1254283D01*
G01X1257217Y814167D02*
X1257717Y814667D01*
X1258300Y814917D01*
X1258967Y815000D01*
X1259800Y814833D01*
X1260383Y814417D01*
X1260550Y813917D01*
X1260467Y813417D01*
X1260133Y813000D01*
X1258467Y812167D01*
X1257717Y811583D01*
X1257217Y810750D01*
X1257050Y810000D01*
X1260550D01*
G01X1261900D02*
Y813333D01*
G01Y812417D02*
X1262150Y812833D01*
X1262567Y813167D01*
X1263150Y813333D01*
X1263733Y813167D01*
X1264150Y812833D01*
X1264400Y812417D01*
Y810000D01*
G01Y812417D02*
X1264650Y812833D01*
X1265067Y813167D01*
X1265650Y813333D01*
X1266233Y813167D01*
X1266650Y812833D01*
X1266900Y812333D01*
Y810000D01*
G01X1270000Y813333D02*
Y810000D01*
G01Y814667D02*
X1269833Y814750D01*
Y814917D01*
X1270000Y815000D01*
X1270167Y814917D01*
Y814750D01*
X1270000Y814667D01*
G01X1275600Y810000D02*
Y815000D01*
G01X1244877Y797230D02*
X1241543Y798897D01*
X1244877Y800563D01*
G01X1247727Y798147D02*
X1249893D01*
G01Y799647D02*
X1247727D01*
G01X1254410Y802230D02*
X1253743Y802063D01*
X1253243Y801647D01*
X1252910Y801147D01*
X1252660Y800480D01*
X1252577Y799730D01*
X1252660Y798980D01*
X1252910Y798313D01*
X1253243Y797813D01*
X1253743Y797397D01*
X1254410Y797230D01*
X1255077Y797397D01*
X1255577Y797813D01*
X1255910Y798313D01*
X1256160Y798980D01*
X1256243Y799730D01*
X1256160Y800480D01*
X1255910Y801147D01*
X1255577Y801647D01*
X1255077Y802063D01*
X1254410Y802230D01*
G01X1260010Y797063D02*
X1259843Y797147D01*
Y797313D01*
X1260010Y797397D01*
X1260177Y797313D01*
Y797147D01*
X1260010Y797063D01*
G01X1265443Y797230D02*
X1265610Y798313D01*
X1265860Y799230D01*
X1266193Y800063D01*
X1266610Y800980D01*
X1267277Y802230D01*
X1263943D01*
G01X1269377Y797980D02*
X1269877Y797563D01*
X1270460Y797313D01*
X1271210Y797230D01*
X1271960Y797397D01*
X1272543Y797730D01*
X1272960Y798313D01*
X1273043Y798980D01*
X1272877Y799647D01*
X1272460Y800063D01*
X1271877Y800397D01*
X1271293Y800480D01*
X1270710Y800397D01*
X1269960Y800063D01*
X1270210Y802230D01*
X1272460D01*
G01X1275310Y797063D02*
X1278310Y802230D01*
G01X1275310D02*
X1274810Y802063D01*
X1274560Y801813D01*
X1274393Y801313D01*
X1274560Y800813D01*
X1274810Y800563D01*
X1275310Y800397D01*
X1275810Y800563D01*
X1276060Y800813D01*
X1276227Y801313D01*
X1276060Y801813D01*
X1275810Y802063D01*
X1275310Y802230D01*
G01X1278310Y798897D02*
X1277810Y798730D01*
X1277560Y798480D01*
X1277393Y797980D01*
X1277560Y797480D01*
X1277810Y797230D01*
X1278310Y797063D01*
X1278810Y797230D01*
X1279060Y797480D01*
X1279227Y797980D01*
X1279060Y798480D01*
X1278810Y798730D01*
X1278310Y798897D01*
G01X1241083Y841667D02*
X1243083D01*
G01X1242000Y842750D02*
Y840583D01*
G01X1246100Y839833D02*
X1249100Y845000D01*
G01X1252117Y841667D02*
X1254283D01*
G01X1256967Y840750D02*
X1257467Y840333D01*
X1258050Y840083D01*
X1258800Y840000D01*
X1259550Y840167D01*
X1260133Y840500D01*
X1260550Y841083D01*
X1260633Y841750D01*
X1260467Y842417D01*
X1260050Y842833D01*
X1259467Y843167D01*
X1258883Y843250D01*
X1258300Y843167D01*
X1257550Y842833D01*
X1257800Y845000D01*
X1260050D01*
G01X1261900Y840000D02*
Y843333D01*
G01Y842417D02*
X1262150Y842833D01*
X1262567Y843167D01*
X1263150Y843333D01*
X1263733Y843167D01*
X1264150Y842833D01*
X1264400Y842417D01*
Y840000D01*
G01Y842417D02*
X1264650Y842833D01*
X1265067Y843167D01*
X1265650Y843333D01*
X1266233Y843167D01*
X1266650Y842833D01*
X1266900Y842333D01*
Y840000D01*
G01X1270000Y843333D02*
Y840000D01*
G01Y844667D02*
X1269833Y844750D01*
Y844917D01*
X1270000Y845000D01*
X1270167Y844917D01*
Y844750D01*
X1270000Y844667D01*
G01X1275600Y840000D02*
Y845000D01*
G01X1343000Y850610D02*
Y782110D01*
G54D12*
G01X865852Y635354D02*
X843852D01*
G01D02*
Y712354D01*
G01D02*
X865852D01*
G01X898852D02*
Y635354D01*
G01D02*
X942852D01*
G01X891977Y628479D02*
X907102D01*
G01X891977Y721979D02*
Y628479D01*
G01X865852Y712354D02*
Y635354D01*
G01X872727Y628479D02*
Y721979D01*
G01X857602Y628479D02*
X872727D01*
G01X857602Y635354D02*
Y628479D01*
G01X942852Y712354D02*
X898852D01*
G01X907102Y721979D02*
X891977D01*
G01X857602D02*
Y715104D01*
G01X872727Y721979D02*
X857602D01*
G01X934602Y628479D02*
X949727D01*
G01X934602Y635354D02*
Y628479D01*
G01X942852Y635354D02*
Y712354D01*
G01X907102Y628479D02*
Y635354D01*
G01X934602Y721979D02*
Y715104D01*
G01X949727Y721979D02*
X934602D01*
G01X907102Y715104D02*
Y721979D01*
G01X984102Y628479D02*
Y635354D01*
G01X975852Y712354D02*
Y635354D01*
G01D02*
X1019852D01*
G01X968977Y628479D02*
X984102D01*
G01X968977Y721979D02*
Y628479D01*
G01X949727D02*
Y721979D01*
G01X984102Y715104D02*
Y721979D01*
G01X1019852Y712354D02*
X975852D01*
G01X984102Y721979D02*
X968977D01*
G01X1026727Y628479D02*
Y719229D01*
G01X1019852Y635354D02*
Y712354D01*
G01X1011602Y628479D02*
X1026727D01*
G01X1011602Y635354D02*
Y628479D01*
G01Y719229D02*
Y712354D01*
G01X1026727Y719229D02*
X1011602D01*
G01X1088602Y628479D02*
X1122977D01*
G01X1088602Y635354D02*
Y628479D01*
G01X1061102D02*
Y635354D01*
G01X1045977Y628479D02*
X1061102D01*
G01X1045977Y719229D02*
Y628479D01*
G01X1052852Y712354D02*
Y635354D01*
G01D02*
X1096852D01*
G01X1088602Y719229D02*
Y712354D01*
G01X1103727Y719229D02*
X1088602D01*
G01X1061102D02*
X1045977D01*
G01X1061102Y712354D02*
Y719229D01*
G01X1096852Y712354D02*
X1052852D01*
G01X1129852D02*
Y635354D01*
G01D02*
X1173852D01*
G01X1138102Y628479D02*
Y635354D01*
G01X1122977Y628479D02*
X1138102D01*
G01X1096852Y635354D02*
Y712354D01*
G01X1173852D02*
X1129852D01*
G01X1138102D02*
Y719229D01*
G01D02*
X1103727D01*
G01X1180727Y628479D02*
Y719229D01*
G01X1165602Y628479D02*
X1180727D01*
G01X1165602Y635354D02*
Y628479D01*
G01X1173852Y635354D02*
Y712354D01*
G01X1165602Y719229D02*
Y712354D01*
G01X1180727Y719229D02*
X1165602D01*
G01X1215102Y628479D02*
Y635354D01*
G01X1206852Y712354D02*
Y635354D01*
G01D02*
X1250852D01*
G01X1199977Y628479D02*
X1215102D01*
G01X1199977Y719229D02*
Y628479D01*
G01X1215102Y712354D02*
Y719229D01*
G01X1250852Y712354D02*
X1206852D01*
G01X1215102Y719229D02*
X1199977D01*
G01X1250852Y635354D02*
Y712354D01*
G54D13*
G01X303090Y319830D02*
Y303830D01*
G01X292090Y340830D02*
Y357830D01*
G01X341590Y319830D02*
Y303830D01*
G01X352590Y340830D02*
Y357830D01*
G01X356482Y330153D02*
X352452Y324663D01*
X356652Y324643D01*
G01X345680Y327680D02*
G02X350362Y319860I-4190J-7820D01*
G01X348190Y321780D01*
X351420Y321950D01*
X350460Y319850D01*
G01X439562Y301543D02*
X435532Y296053D01*
X439732Y296033D01*
G54D14*
G01X891702Y675345D02*
X891096Y675951D01*
G01X890957Y676193D02*
X891702Y676936D01*
G01X889988Y677557D02*
X891702Y679270D01*
G01X888823Y678725D02*
X891702Y681604D01*
G01X887462Y679697D02*
X891702Y683937D01*
G01X885887Y680455D02*
X891702Y686270D01*
G01X884054Y680956D02*
X891702Y688604D01*
G01X881854Y681089D02*
X891702Y690937D01*
G01Y674644D02*
X891701Y674645D01*
G01X891702Y719229D02*
Y674644D01*
G01Y691679D02*
X873002Y710379D01*
G01X891702Y689346D02*
X873002Y708046D01*
G01X891702Y687012D02*
X873002Y705711D01*
G01X891702Y684678D02*
X873002Y703378D01*
G01X891702Y682345D02*
X873002Y701045D01*
G01X891702Y680012D02*
X873002Y698711D01*
G01Y690905D02*
X891702Y709604D01*
G01Y677678D02*
X873002Y696378D01*
G01X887198Y679848D02*
X873002Y694045D01*
G01X883703Y681010D02*
X873002Y691711D01*
G01X881330Y681049D02*
X873002Y689377D01*
G01X879392Y680653D02*
X873002Y687044D01*
G01X877738Y679974D02*
X873002Y684711D01*
G01X876310Y679069D02*
X873002Y682377D01*
G01X875080Y677966D02*
X873002Y680044D01*
G01X874045Y676668D02*
X873002Y677711D01*
G01X873215Y675163D02*
X873002Y675377D01*
G01X878929Y680497D02*
X891702Y693270D01*
G01X873002Y676905D02*
X891702Y695603D01*
G01X873002Y679238D02*
X891702Y697938D01*
G01X873002Y681571D02*
X891702Y700271D01*
G01X873002Y683905D02*
X891702Y702604D01*
G01X873002Y686238D02*
X891702Y704938D01*
G01X873002Y688571D02*
X891702Y707271D01*
G01X873002Y674644D02*
Y719229D01*
G01Y674645D02*
Y674644D01*
G01X891701Y674645D02*
G03X873003I-9349J-3541D01*
G01X891779Y725829D02*
X949925D01*
G01X905840Y719543D02*
X899554Y725829D01*
G01X903507Y719543D02*
X897221Y725829D01*
G01X901173Y719543D02*
X894886Y725829D01*
G01X898840Y719543D02*
X892553Y725829D01*
G01X896507Y719543D02*
X891342Y724707D01*
G01X894172Y719543D02*
X890494Y723221D01*
G01X891927Y719455D02*
X889440Y721942D01*
G01X891702Y717347D02*
X888191Y720857D01*
G01X891702Y715014D02*
X886738Y719977D01*
G01X891702Y712680D02*
X885053Y719328D01*
G01X891702Y710347D02*
X883070Y718978D01*
G01X891702Y708014D02*
X880607Y719107D01*
G01X899306Y719543D02*
X905593Y725829D01*
G01X896972Y719543D02*
X903258Y725829D01*
G01X894639Y719543D02*
X900925Y725829D01*
G01X892306Y719543D02*
X898592Y725829D01*
G01X892015Y719543D02*
X891702Y719229D01*
G01X907157Y719543D02*
X892015D01*
G01X856340Y725829D02*
X872925D01*
G01X891702Y705679D02*
X876553Y720829D01*
G01X874327Y723054D02*
X871552Y725829D01*
G01X891702Y703346D02*
X869219Y725829D01*
G01X891702Y701013D02*
X866886Y725829D01*
G01X891702Y698679D02*
X873002Y717379D01*
G01X871152Y719229D02*
X864552Y725829D01*
G01X891702Y696346D02*
X873002Y715046D01*
G01X868819Y719229D02*
X862219Y725829D01*
G01X891702Y694013D02*
X873002Y712712D01*
G01X866485Y719229D02*
X859885Y725829D01*
G01X864151Y719229D02*
X857551Y725829D01*
G01X861818Y719229D02*
X855779Y725267D01*
G01X859485Y719229D02*
X854613Y724101D01*
G01X857327Y719053D02*
X853752Y722628D01*
G01X857327Y716720D02*
X853752Y720295D01*
G01X857327Y714387D02*
X853752Y717961D01*
G01X856750Y712629D02*
X853752Y715628D01*
G01X854417Y712629D02*
X853752Y713295D01*
G01X873002Y693238D02*
X891702Y711938D01*
G01X873002Y695572D02*
X891702Y714272D01*
G01X873002Y697906D02*
X891702Y716605D01*
G01X873002Y700239D02*
X891702Y718939D01*
G01X873002Y702572D02*
X896258Y725829D01*
G01X873002Y704906D02*
X893925Y725829D01*
G01X873002Y707239D02*
X885106Y719344D01*
G01X873002Y709572D02*
X882382Y718952D01*
G01X873002Y711907D02*
X880270Y719174D01*
G01X873002Y714240D02*
X878496Y719734D01*
G01X873002Y716573D02*
X876971Y720542D01*
G01X873002Y718907D02*
X875655Y721560D01*
G01X870991Y719229D02*
X874536Y722775D01*
G01X868658Y719229D02*
X873618Y724189D01*
G01X866324Y719229D02*
X872924Y725829D01*
G01X863991Y719229D02*
X870591Y725829D01*
G01X855058Y712629D02*
X857327Y714899D01*
G01X861658Y719229D02*
X868258Y725829D01*
G01X853752Y713657D02*
X857327Y717232D01*
G01X859323Y719229D02*
X865923Y725829D01*
G01X853752Y715991D02*
X863590Y725829D01*
G01X853752Y718324D02*
X861257Y725829D01*
G01X853752Y720657D02*
X858923Y725829D01*
G01X853752Y722991D02*
X856590Y725829D01*
G01X872925D02*
G03X891779I9427J3024D01*
G01X853752Y723240D02*
X856340Y725829D01*
G01X853752Y712629D02*
Y723240D01*
G01X857327Y712629D02*
X853752D01*
G01X857327Y719504D02*
Y712629D01*
G01X857602Y719229D02*
X857327Y719504D01*
G01X873002Y719229D02*
X857602D01*
G01X951751Y624629D02*
X948176Y628204D01*
G01X946733Y624629D02*
X968702Y646597D01*
G01X949418Y624629D02*
X945843Y628204D01*
G01X947085Y624629D02*
X943510Y628204D01*
G01X934327Y635053D02*
X934300Y635079D01*
G01X934327Y632720D02*
X931967Y635079D01*
G01X934327Y630387D02*
X930752Y633961D01*
G01X933037Y624933D02*
X936307Y628204D01*
G01X931869Y626100D02*
X934327Y628556D01*
G01X930752Y627315D02*
X934327Y630890D01*
G01X930752Y629649D02*
X934327Y633224D01*
G01X930752Y631983D02*
X933848Y635079D01*
G01X930752Y634316D02*
X931515Y635079D01*
G01X934327Y628204D02*
X950002D01*
G01X934327Y635079D02*
Y628204D01*
G01X930752Y635079D02*
X934327D01*
G01X930752Y627218D02*
Y635079D01*
G01X944750Y624629D02*
X941175Y628204D01*
G01X942417Y624629D02*
X938842Y628204D01*
G01X940084Y624629D02*
X936509Y628204D01*
G01X937750Y624629D02*
X930752Y631627D01*
G01X935417Y624629D02*
X930752Y629294D01*
G01X944400Y624629D02*
X947975Y628204D01*
G01X942066Y624629D02*
X945640Y628203D01*
G01X939733Y624629D02*
X943307Y628204D01*
G01X937399Y624629D02*
X940974Y628203D01*
G01X935066Y624629D02*
X938640Y628203D01*
G01X985362Y624629D02*
X933340D01*
G01D02*
X930752Y627218D01*
G01X948269Y719504D02*
X951539Y722772D01*
G01X968702Y703350D02*
X946222Y725829D01*
G01X968702Y701017D02*
X943889Y725829D01*
G01X947881Y719504D02*
X941556Y725829D01*
G01X945548Y719504D02*
X939223Y725829D01*
G01X943214Y719504D02*
X936889Y725829D01*
G01X940881Y719504D02*
X934556Y725829D01*
G01X938546Y719504D02*
X932223Y725829D01*
G01X936213Y719504D02*
X929888Y725829D01*
G01X934327Y719058D02*
X927555Y725829D01*
G01X934327Y716725D02*
X925222Y725829D01*
G01X934327Y714390D02*
X922888Y725829D01*
G01X933755Y712629D02*
X920555Y725829D01*
G01X931422Y712629D02*
X918222Y725829D01*
G01X929088Y712629D02*
X915888Y725829D01*
G01X926754Y712629D02*
X913554Y725829D01*
G01X945936Y719504D02*
X950619Y724187D01*
G01X943603Y719504D02*
X949925Y725826D01*
G01X941270Y719504D02*
X947595Y725829D01*
G01X932061Y712629D02*
X934327Y714894D01*
G01X938936Y719504D02*
X945261Y725829D01*
G01X929728Y712629D02*
X934327Y717228D01*
G01X936603Y719504D02*
X942928Y725829D01*
G01X927395Y712629D02*
X940595Y725829D01*
G01X925062Y712629D02*
X938260Y725829D01*
G01X922727Y712629D02*
X935927Y725829D01*
G01X920394Y712629D02*
X933594Y725829D01*
G01X918061Y712629D02*
X931260Y725829D01*
G01X915727Y712629D02*
X928927Y725829D01*
G01X913394Y712629D02*
X926593Y725828D01*
G01X934327Y719504D02*
Y712629D01*
G01X950002Y719504D02*
X934327D01*
G01X924420Y712629D02*
X911221Y725829D01*
G01X922087Y712629D02*
X908887Y725829D01*
G01X919754Y712629D02*
X906554Y725829D01*
G01X917420Y712629D02*
X904221Y725829D01*
G01X915087Y712629D02*
X901887Y725829D01*
G01X912754Y712629D02*
X907377Y718006D01*
G01X910421Y712629D02*
X907377Y715673D01*
G01X908086Y712629D02*
X907377Y713339D01*
G01X911061Y712629D02*
X924260Y725829D01*
G01X908727Y712629D02*
X921927Y725829D01*
G01X907377Y713613D02*
X919592Y725828D01*
G01X907377Y715946D02*
X917259Y725829D01*
G01X907377Y718280D02*
X914926Y725829D01*
G01X906307Y719543D02*
X912592Y725828D01*
G01X903972Y719543D02*
X910259Y725829D01*
G01X901639Y719543D02*
X907926Y725829D01*
G01X907377Y719504D02*
X907157Y719543D01*
G01X907377Y712629D02*
Y719504D01*
G01X934327Y712629D02*
X907377D01*
G01X987952Y632764D02*
X985637Y635078D01*
G01X987952Y630431D02*
X984377Y634006D01*
G01X987952Y628098D02*
X984377Y631673D01*
G01X987225Y626490D02*
X984377Y629338D01*
G01X986058Y625324D02*
X983178Y628204D01*
G01X984377Y629605D02*
X987952Y633180D01*
G01X984377Y631938D02*
X987517Y635079D01*
G01X984377Y634272D02*
X985184Y635079D01*
G01X987952D02*
Y627218D01*
G01X984377Y635079D02*
X987952D01*
G01X984377Y628204D02*
Y635079D01*
G01X984420Y624629D02*
X980845Y628204D01*
G01X984069Y624629D02*
X987952Y628512D01*
G01X981735Y624629D02*
X987952Y630845D01*
G01X979402Y624629D02*
X982977Y628204D01*
G01X987952Y627218D02*
X985362Y624629D01*
G01X968702Y642680D02*
X950002Y661380D01*
G01X968702Y640347D02*
X950002Y659047D01*
G01X982086Y624629D02*
X978512Y628204D01*
G01X968702Y638014D02*
X950002Y656713D01*
G01X979752Y624629D02*
X976177Y628204D01*
G01X968702Y635680D02*
X950002Y654380D01*
G01X968702Y633347D02*
X950002Y652047D01*
G01X968702Y631014D02*
X950002Y649713D01*
G01X968702Y628679D02*
X950002Y647379D01*
G01Y630232D02*
X968702Y648932D01*
G01X950002Y632565D02*
X968702Y651265D01*
G01X950002Y634898D02*
X968702Y653598D01*
G01X950002Y637232D02*
X968702Y655931D01*
G01X950002Y639565D02*
X968702Y658265D01*
G01X950002Y641898D02*
X968702Y660598D01*
G01X950002Y644232D02*
X968702Y662931D01*
G01Y628204D02*
X984377D01*
G01X968702Y719504D02*
Y628204D01*
G01X950002D02*
Y719504D01*
G01X977419Y624629D02*
X973844Y628204D01*
G01X975085Y624629D02*
X971511Y628204D01*
G01X972752Y624629D02*
X969177Y628204D01*
G01X970419Y624629D02*
X950002Y645046D01*
G01X968086Y624629D02*
X950002Y642712D01*
G01X965752Y624629D02*
X950002Y640379D01*
G01X963419Y624629D02*
X950002Y638046D01*
G01X961085Y624629D02*
X950002Y635712D01*
G01X958751Y624629D02*
X950002Y633379D01*
G01X956418Y624629D02*
X950002Y631046D01*
G01X954085Y624629D02*
X950002Y628711D01*
G01X977068Y624629D02*
X980642Y628204D01*
G01X974734Y624629D02*
X978309Y628204D01*
G01X972401Y624629D02*
X975976Y628204D01*
G01X970068Y624629D02*
X973643Y628204D01*
G01X967734Y624629D02*
X971309Y628204D01*
G01X965401Y624629D02*
X968976Y628204D01*
G01X963068Y624629D02*
X968702Y630263D01*
G01X960733Y624629D02*
X968702Y632597D01*
G01X958400Y624629D02*
X968702Y634931D01*
G01X956067Y624629D02*
X968702Y637264D01*
G01X953733Y624629D02*
X968702Y639597D01*
G01X951400Y624629D02*
X968702Y641931D01*
G01X949067Y624629D02*
X968702Y644264D01*
G01Y691683D02*
X950002Y710383D01*
G01Y690901D02*
X968702Y709601D01*
G01Y689350D02*
X950002Y708049D01*
G01X968702Y687016D02*
X950002Y705716D01*
G01X968702Y684683D02*
X950002Y703383D01*
G01X968702Y682350D02*
X950002Y701048D01*
G01X968702Y680015D02*
X950002Y698715D01*
G01X968702Y677682D02*
X950002Y696382D01*
G01X968702Y675349D02*
X950002Y694048D01*
G01X968702Y673015D02*
X950002Y691715D01*
G01X968702Y670682D02*
X950002Y689382D01*
G01X968702Y668349D02*
X950002Y687048D01*
G01X968702Y666015D02*
X950002Y684715D01*
G01X968702Y663681D02*
X950002Y682381D01*
G01X968702Y661348D02*
X950002Y680047D01*
G01X968702Y659014D02*
X950002Y677714D01*
G01Y658233D02*
X968702Y676932D01*
G01X950002Y660566D02*
X968702Y679266D01*
G01X950002Y662899D02*
X968702Y681599D01*
G01X950002Y665234D02*
X968702Y683932D01*
G01X950002Y667567D02*
X968702Y686267D01*
G01X950002Y669900D02*
X968702Y688600D01*
G01X950002Y672234D02*
X968702Y690933D01*
G01X950002Y674567D02*
X968702Y693267D01*
G01X950002Y676900D02*
X968702Y695600D01*
G01X950002Y679233D02*
X968702Y697933D01*
G01X950002Y681567D02*
X968702Y700267D01*
G01X950002Y683901D02*
X968702Y702601D01*
G01X950002Y686234D02*
X968702Y704934D01*
G01X950002Y688568D02*
X968702Y707268D01*
G01Y656681D02*
X950002Y675381D01*
G01X968702Y654348D02*
X950002Y673048D01*
G01X968702Y652014D02*
X950002Y670714D01*
G01X968702Y649681D02*
X950002Y668381D01*
G01X968702Y647348D02*
X950002Y666048D01*
G01X968702Y645013D02*
X950002Y663713D01*
G01Y646565D02*
X968702Y665265D01*
G01X950002Y648899D02*
X968702Y667599D01*
G01X950002Y651233D02*
X968702Y669932D01*
G01X950002Y653566D02*
X968702Y672266D01*
G01X950002Y655899D02*
X968702Y674599D01*
G01X987952Y721436D02*
X983558Y725829D01*
G01X987952Y719102D02*
X981224Y725829D01*
G01X987952Y714435D02*
X984377Y718009D01*
G01X987424Y712629D02*
X984377Y715676D01*
G01X985091Y712629D02*
X984377Y713343D01*
G01X985731Y712629D02*
X987952Y714850D01*
G01X984377Y713608D02*
X987952Y717183D01*
G01X984377Y715942D02*
X987952Y719517D01*
G01X984377Y718276D02*
X987952Y721851D01*
G01X983271Y719504D02*
X987480Y723712D01*
G01X980938Y719504D02*
X986313Y724879D01*
G01X984377Y712629D02*
Y719504D01*
G01X987952Y712629D02*
X984377D01*
G01X987952Y723240D02*
Y712629D01*
G01X985362Y725829D02*
X987952Y723240D01*
G01Y716769D02*
X978891Y725829D01*
G01X968779D02*
X985362D01*
G01X982883Y719504D02*
X976558Y725829D01*
G01X980549Y719504D02*
X974224Y725829D01*
G01X978216Y719504D02*
X971891Y725829D01*
G01X975883Y719504D02*
X969558Y725829D01*
G01X973548Y719504D02*
X968343Y724709D01*
G01X971215Y719504D02*
X967496Y723223D01*
G01X968882Y719504D02*
X966442Y721943D01*
G01X968702Y717350D02*
X965193Y720859D01*
G01X968702Y715017D02*
X963741Y719978D01*
G01X968702Y712684D02*
X962057Y719329D01*
G01X968702Y710350D02*
X960073Y718978D01*
G01X968702Y708017D02*
X957613Y719106D01*
G01X968702Y705684D02*
X953567Y720819D01*
G01X951317Y723067D02*
X948556Y725829D01*
G01X968702Y698683D02*
X950002Y717383D01*
G01X968702Y696350D02*
X950002Y715049D01*
G01X968702Y694016D02*
X950002Y712716D01*
G01X978605Y719504D02*
X984930Y725829D01*
G01X950002Y693234D02*
X968702Y711934D01*
G01X976271Y719504D02*
X982596Y725829D01*
G01X950002Y695568D02*
X968702Y714267D01*
G01X973938Y719504D02*
X980263Y725829D01*
G01X950002Y697901D02*
X968702Y716601D01*
G01X971605Y719504D02*
X977930Y725829D01*
G01X950002Y700234D02*
X968702Y718934D01*
G01X969271Y719504D02*
X975596Y725829D01*
G01X950002Y702569D02*
X973262Y725828D01*
G01X950002Y704902D02*
X970929Y725829D01*
G01X950002Y707235D02*
X962112Y719345D01*
G01X950002Y709569D02*
X959386Y718952D01*
G01X950002Y711902D02*
X957273Y719173D01*
G01X950002Y714235D02*
X955499Y719733D01*
G01X950002Y716569D02*
X953974Y720540D01*
G01X950002Y718903D02*
X952657Y721558D01*
G01X984377Y719504D02*
X968702D01*
G01X949925Y725829D02*
G03X968779I9427J3024D01*
G01X1120658Y632879D02*
X1122702Y634922D01*
G01X1118325Y632879D02*
X1122702Y637256D01*
G01X1115991Y632879D02*
X1122702Y639589D01*
G01X1113658Y632879D02*
X1122702Y641922D01*
G01X1111325Y632879D02*
X1122702Y644257D01*
G01Y714829D02*
Y632879D01*
G01X1108990D02*
X1122702Y646590D01*
G01X1106657Y632879D02*
X1122702Y648923D01*
G01X1104324Y632879D02*
X1122702Y651257D01*
G01X1104002Y634890D02*
X1122702Y653590D01*
G01X1104002Y637224D02*
X1122702Y655923D01*
G01X1104002Y639557D02*
X1122702Y658257D01*
G01X1104002Y641890D02*
X1122702Y660590D01*
G01X1104002Y644225D02*
X1122702Y662924D01*
G01Y642688D02*
X1104002Y661388D01*
G01X1122702Y640355D02*
X1104002Y659055D01*
G01X1122702Y638022D02*
X1104002Y656721D01*
G01X1122702Y635688D02*
X1104002Y654388D01*
G01X1122702Y633354D02*
X1104002Y652054D01*
G01X1120844Y632879D02*
X1104002Y649720D01*
G01X1118510Y632879D02*
X1104002Y647387D01*
G01X1116177Y632879D02*
X1104002Y645054D01*
G01X1113844Y632879D02*
X1104002Y642720D01*
G01X1111509Y632879D02*
X1104002Y640387D01*
G01X1109176Y632879D02*
X1104002Y638054D01*
G01X1106843Y632879D02*
X1104002Y635721D01*
G01X1104509Y632879D02*
X1104002Y633386D01*
G01X1122702Y632879D02*
X1104002D01*
G01D02*
Y714829D01*
G01Y690893D02*
X1122702Y709593D01*
G01Y691691D02*
X1104002Y710391D01*
G01X1122702Y689358D02*
X1104002Y708057D01*
G01X1122702Y687023D02*
X1104002Y705723D01*
G01X1122702Y684690D02*
X1104002Y703390D01*
G01X1122702Y682357D02*
X1104002Y701056D01*
G01X1122702Y680023D02*
X1104002Y698723D01*
G01Y658224D02*
X1122702Y676924D01*
G01X1104002Y660559D02*
X1122702Y679259D01*
G01X1104002Y662892D02*
X1122702Y681592D01*
G01X1104002Y665225D02*
X1122702Y683925D01*
G01X1104002Y667559D02*
X1122702Y686258D01*
G01X1104002Y669892D02*
X1122702Y688592D01*
G01X1104002Y672225D02*
X1122702Y690925D01*
G01X1104002Y674559D02*
X1122702Y693258D01*
G01X1104002Y676892D02*
X1122702Y695592D01*
G01X1104002Y679226D02*
X1122702Y697926D01*
G01X1104002Y681560D02*
X1122702Y700259D01*
G01X1104002Y683893D02*
X1122702Y702593D01*
G01X1104002Y686226D02*
X1122702Y704926D01*
G01X1104002Y688560D02*
X1122702Y707259D01*
G01Y677690D02*
X1104002Y696390D01*
G01X1122702Y675357D02*
X1104002Y694057D01*
G01X1122702Y673023D02*
X1104002Y691723D01*
G01X1122702Y670690D02*
X1104002Y689390D01*
G01X1122702Y668356D02*
X1104002Y687056D01*
G01X1122702Y666022D02*
X1104002Y684722D01*
G01X1122702Y663689D02*
X1104002Y682389D01*
G01X1122702Y661356D02*
X1104002Y680056D01*
G01X1122702Y659023D02*
X1104002Y677722D01*
G01X1122702Y656689D02*
X1104002Y675389D01*
G01X1122702Y654356D02*
X1104002Y673056D01*
G01X1122702Y652023D02*
X1104002Y670721D01*
G01X1122702Y649688D02*
X1104002Y668388D01*
G01X1122702Y647355D02*
X1104002Y666055D01*
G01Y646558D02*
X1122702Y665258D01*
G01X1104002Y648891D02*
X1122702Y667591D01*
G01X1104002Y651225D02*
X1122702Y669924D01*
G01X1104002Y653558D02*
X1122702Y672258D01*
G01X1104002Y655891D02*
X1122702Y674591D01*
G01Y645022D02*
X1104002Y663721D01*
G01X1122702Y712692D02*
X1120565Y714829D01*
G01X1122702Y710359D02*
X1118231Y714829D01*
G01X1122702Y708025D02*
X1115897Y714829D01*
G01X1122702Y705692D02*
X1113564Y714829D01*
G01X1104002Y693226D02*
X1122702Y711926D01*
G01X1104002Y695561D02*
X1122702Y714259D01*
G01X1104002Y697894D02*
X1120937Y714829D01*
G01X1104002Y700227D02*
X1118604Y714829D01*
G01X1104002Y702561D02*
X1116270Y714829D01*
G01X1104002Y704894D02*
X1113937Y714829D01*
G01X1104002Y707227D02*
X1111604Y714829D01*
G01X1104002Y709561D02*
X1109270Y714829D01*
G01X1104002Y711894D02*
X1106937Y714829D01*
G01X1104002Y714228D02*
X1104604Y714829D01*
G01X1122702Y703358D02*
X1111231Y714829D01*
G01X1122702Y701024D02*
X1108897Y714829D01*
G01X1122702Y698691D02*
X1106564Y714829D01*
G01X1122702Y696358D02*
X1104231Y714829D01*
G01X1122702Y694024D02*
X1104002Y712724D01*
G01Y714829D02*
X1122702D01*
G01X1185995Y632879D02*
X1199702Y646585D01*
G01X1183662Y632879D02*
X1199702Y648919D01*
G01X1181327Y632879D02*
X1199702Y651253D01*
G01X1181002Y634887D02*
X1199702Y653586D01*
G01X1181002Y637220D02*
X1199702Y655920D01*
G01X1181002Y639553D02*
X1199702Y658253D01*
G01X1181002Y641887D02*
X1199702Y660586D01*
G01X1181002Y644220D02*
X1199702Y662920D01*
G01X1197847Y632879D02*
X1181002Y649725D01*
G01X1195514Y632879D02*
X1181002Y647392D01*
G01X1193181Y632879D02*
X1181002Y645057D01*
G01X1190847Y632879D02*
X1181002Y642724D01*
G01X1188514Y632879D02*
X1181002Y640391D01*
G01X1186181Y632879D02*
X1181002Y638057D01*
G01X1183846Y632879D02*
X1181002Y635724D01*
G01X1181513Y632879D02*
X1181002Y633391D01*
G01X1199702Y632879D02*
X1181002D01*
G01D02*
Y714829D01*
G01Y690889D02*
X1199702Y709589D01*
G01X1181002Y658221D02*
X1199702Y676921D01*
G01X1181002Y660554D02*
X1199702Y679254D01*
G01X1181002Y662888D02*
X1199702Y681587D01*
G01X1181002Y665221D02*
X1199702Y683921D01*
G01X1181002Y667555D02*
X1199702Y686255D01*
G01X1181002Y669888D02*
X1199702Y688588D01*
G01X1181002Y672222D02*
X1199702Y690922D01*
G01X1181002Y674555D02*
X1199702Y693255D01*
G01X1181002Y676888D02*
X1199702Y695588D01*
G01X1181002Y679222D02*
X1199702Y697922D01*
G01X1181002Y681555D02*
X1199702Y700255D01*
G01X1181002Y683888D02*
X1199702Y702588D01*
G01X1181002Y686223D02*
X1199702Y704922D01*
G01X1181002Y688556D02*
X1199702Y707256D01*
G01Y677694D02*
X1181002Y696393D01*
G01X1199702Y675360D02*
X1181002Y694060D01*
G01X1199702Y673027D02*
X1181002Y691727D01*
G01X1199702Y670694D02*
X1181002Y689393D01*
G01X1199702Y668360D02*
X1181002Y687060D01*
G01X1199702Y666027D02*
X1181002Y684727D01*
G01X1199702Y663694D02*
X1181002Y682392D01*
G01X1199702Y661359D02*
X1181002Y680059D01*
G01X1199702Y659026D02*
X1181002Y677726D01*
G01Y646553D02*
X1199702Y665253D01*
G01X1181002Y648888D02*
X1199702Y667586D01*
G01X1181002Y651221D02*
X1199702Y669921D01*
G01X1181002Y653554D02*
X1199702Y672254D01*
G01X1181002Y655888D02*
X1199702Y674587D01*
G01Y656693D02*
X1181002Y675393D01*
G01X1199702Y654359D02*
X1181002Y673059D01*
G01X1199702Y652026D02*
X1181002Y670726D01*
G01X1199702Y649693D02*
X1181002Y668393D01*
G01X1199702Y647360D02*
X1181002Y666059D01*
G01X1199702Y645025D02*
X1181002Y663725D01*
G01X1199702Y642692D02*
X1181002Y661392D01*
G01X1199702Y640359D02*
X1181002Y659058D01*
G01X1199702Y638025D02*
X1181002Y656725D01*
G01X1199702Y635692D02*
X1181002Y654392D01*
G01X1199702Y633359D02*
X1181002Y652058D01*
G01Y693223D02*
X1199702Y711922D01*
G01X1181002Y695556D02*
X1199702Y714256D01*
G01X1181002Y697889D02*
X1197941Y714829D01*
G01X1181002Y700223D02*
X1195608Y714829D01*
G01X1181002Y702557D02*
X1193275Y714829D01*
G01X1181002Y704890D02*
X1190940Y714829D01*
G01X1181002Y707224D02*
X1188607Y714829D01*
G01X1181002Y709557D02*
X1186274Y714829D01*
G01X1181002Y711890D02*
X1183940Y714829D01*
G01X1181002Y714224D02*
X1181607Y714829D01*
G01X1199702Y701029D02*
X1185901Y714829D01*
G01X1199702Y698696D02*
X1183568Y714829D01*
G01X1199702Y696361D02*
X1181234Y714829D01*
G01X1199702Y694028D02*
X1181002Y712728D01*
G01X1199702Y691695D02*
X1181002Y710394D01*
G01Y714829D02*
X1199702D01*
G01Y689361D02*
X1181002Y708061D01*
G01X1199702Y687028D02*
X1181002Y705728D01*
G01X1199702Y684695D02*
X1181002Y703394D01*
G01X1199702Y682361D02*
X1181002Y701061D01*
G01X1199702Y680027D02*
X1181002Y698727D01*
G01X1197662Y632879D02*
X1199702Y634919D01*
G01X1195328Y632879D02*
X1199702Y637252D01*
G01X1192995Y632879D02*
X1199702Y639586D01*
G01X1190662Y632879D02*
X1199702Y641919D01*
G01X1188328Y632879D02*
X1199702Y644252D01*
G01Y714829D02*
Y632879D01*
G01Y712695D02*
X1197568Y714829D01*
G01X1199702Y710362D02*
X1195235Y714829D01*
G01X1199702Y708029D02*
X1192902Y714829D01*
G01X1199702Y705696D02*
X1190569Y714829D01*
G01X1199702Y703362D02*
X1188234Y714829D01*
M02*
